(kicad_pcb
	(version 20260206)
	(generator "pcbnew")
	(generator_version "10.0")
	(general
		(thickness 1.6)
		(legacy_teardrops no)
	)
	(paper "A4")
	(layers
		(0 "F.Cu" signal "TOP")
		(4 "In1.Cu" signal "L2GND")
		(6 "In2.Cu" signal "L3")
		(8 "In3.Cu" signal "L4VCC")
		(10 "In4.Cu" signal "L5VCC")
		(12 "In5.Cu" signal "L6")
		(14 "In6.Cu" signal "L7GND")
		(2 "B.Cu" signal "BOTTOM")
		(9 "F.Adhes" user "F.Adhesive")
		(11 "B.Adhes" user "B.Adhesive")
		(13 "F.Paste" user "Package Geometry/Pastemask Top")
		(15 "B.Paste" user "Package Geometry/Pastemask Bottom")
		(5 "F.SilkS" user "Ref Des/Silkscreen Top")
		(7 "B.SilkS" user "Ref Des/Silkscreen Bottom")
		(1 "F.Mask" user "Board Geometry/Soldermask Top")
		(3 "B.Mask" user "Board Geometry/Soldermask Bottom")
		(17 "Dwgs.User" user "User.Drawings")
		(19 "Cmts.User" user "User.Comments")
		(21 "Eco1.User" user "User.Eco1")
		(23 "Eco2.User" user "User.Eco2")
		(25 "Edge.Cuts" user "Board Geometry/Outline")
		(27 "Margin" user)
		(31 "F.CrtYd" user "Package Geometry/Place Bound Top")
		(29 "B.CrtYd" user "Package Geometry/Place Bound Bottom")
		(35 "F.Fab" user "Ref Des/Assembly Top")
		(33 "B.Fab" user "Ref Des/Assembly Bottom")
	)
	(setup
		(pad_to_mask_clearance 0)
		(allow_soldermask_bridges_in_footprints no)
		(tenting
			(front yes)
			(back yes)
		)
		(covering
			(front no)
			(back no)
		)
		(plugging
			(front no)
			(back no)
		)
		(capping no)
		(filling no)
		(pcbplotparams
			(layerselection 0x00000000_00000000_55555555_5755f5ff)
			(plot_on_all_layers_selection 0x00000000_00000000_00000000_00000000)
			(disableapertmacros no)
			(usegerberextensions no)
			(usegerberattributes yes)
			(usegerberadvancedattributes yes)
			(creategerberjobfile yes)
			(dashed_line_dash_ratio 12)
			(dashed_line_gap_ratio 3)
			(svgprecision 4)
			(plotframeref no)
			(mode 1)
			(useauxorigin no)
			(pdf_front_fp_property_popups yes)
			(pdf_back_fp_property_popups yes)
			(pdf_metadata yes)
			(pdf_single_document no)
			(dxfpolygonmode yes)
			(dxfimperialunits yes)
			(dxfusepcbnewfont yes)
			(psnegative no)
			(psa4output no)
			(plot_black_and_white yes)
			(sketchpadsonfab no)
			(plotpadnumbers no)
			(hidednponfab no)
			(sketchdnponfab yes)
			(crossoutdnponfab yes)
			(subtractmaskfromsilk no)
			(outputformat 1)
			(mirror no)
			(drillshape 1)
			(scaleselection 1)
			(outputdirectory "")
		)
	)
	(footprint ""
		(layer "F.Cu")
		(at 61.294772 -145.496534 -90)
		(property "Reference" "R162"
			(at 0 0 270)
			(layer "F.SilkS")
			(hide yes)
			(effects
				(font
					(size 1.27 1.27)
				)
			)
		)
		(property "Value" "0R2J-2-GP"
			(at 0.064008 -3.993896 270)
			(unlocked yes)
			(layer "F.Fab")
			(hide yes)
			(effects
				(font
					(size 1.016 1.016)
					(thickness 0.1524)
				)
			)
		)
		(property "Device Type" "R402H16"
			(at 0.064008 -5.517896 270)
			(unlocked yes)
			(layer "F.Fab")
			(hide yes)
			(effects
				(font
					(size 1.016 1.016)
					(thickness 0.1524)
				)
			)
		)
		(duplicate_pad_numbers_are_jumpers no)
		(fp_line
			(start -0.508 -0.9398)
			(end -0.508 0.9398)
			(stroke
				(width 0.1524)
				(type default)
			)
			(layer "F.SilkS")
		)
		(fp_line
			(start 0.508 -0.9398)
			(end -0.508 -0.9398)
			(stroke
				(width 0.1524)
				(type default)
			)
			(layer "F.SilkS")
		)
		(fp_rect
			(start -0.508 0.9398)
			(end 0.508 -0.9398)
			(stroke
				(width 0)
				(type default)
			)
			(fill no)
			(layer "F.CrtYd")
		)
		(fp_rect
			(start -0.508 0.9398)
			(end 0.508 -0.9398)
			(stroke
				(width 0)
				(type default)
			)
			(fill no)
			(layer "F.Fab")
		)
		(pad "1" smd custom
			(at 0 -0.4445 270)
			(size 0.1397 0.1397)
			(layers "F.Cu" "F.Mask" "F.Paste")
			(net "I2C_SCC_SDA_OUT")
			(options
				(clearance outline)
				(anchor circle)
			)
			(primitives
				(gr_poly
					(pts
						(arc
							(start -0.1778 -0.2794)
							(mid -0.249642 -0.249642)
							(end -0.2794 -0.1778)
						)
						(arc
							(start -0.2794 0.1778)
							(mid -0.249642 0.249642)
							(end -0.1778 0.2794)
						)
						(arc
							(start 0.1778 0.2794)
							(mid 0.249642 0.249642)
							(end 0.2794 0.1778)
						)
						(arc
							(start 0.2794 -0.1778)
							(mid 0.249642 -0.249642)
							(end 0.1778 -0.2794)
						)
					)
					(width 0)
					(fill yes)
				)
			)
		)
		(pad "2" smd custom
			(at 0 0.4445 270)
			(size 0.1397 0.1397)
			(layers "F.Cu" "F.Mask" "F.Paste")
			(net "BMC_SMB3_DAT")
			(options
				(clearance outline)
				(anchor circle)
			)
			(primitives
				(gr_poly
					(pts
						(arc
							(start -0.1778 -0.2794)
							(mid -0.249642 -0.249642)
							(end -0.2794 -0.1778)
						)
						(arc
							(start -0.2794 0.1778)
							(mid -0.249642 0.249642)
							(end -0.1778 0.2794)
						)
						(arc
							(start 0.1778 0.2794)
							(mid 0.249642 0.249642)
							(end 0.2794 0.1778)
						)
						(arc
							(start 0.2794 -0.1778)
							(mid 0.249642 -0.249642)
							(end 0.1778 -0.2794)
						)
					)
					(width 0)
					(fill yes)
				)
			)
		)
	)
	(footprint ""
		(layer "F.Cu")
		(at 83.358228 -75.749658 90)
		(property "Reference" "VIA10"
			(at 0 0 90)
			(layer "F.SilkS")
			(hide yes)
			(effects
				(font
					(size 1.27 1.27)
				)
			)
		)
		(property "Value" "85OHM-8L-1D6MM-L16L18-GP"
			(at 4.064 0.6096 90)
			(unlocked yes)
			(layer "F.Fab")
			(hide yes)
			(effects
				(font
					(size 1.016 1.016)
					(thickness 0.1524)
				)
			)
		)
		(property "Device Type" "VIA-PCIE-4P-368076"
			(at 4.064 -0.9144 90)
			(unlocked yes)
			(layer "F.Fab")
			(hide yes)
			(effects
				(font
					(size 1.016 1.016)
					(thickness 0.1524)
				)
			)
		)
		(duplicate_pad_numbers_are_jumpers no)
		(fp_rect
			(start -1.8415 0.381)
			(end 1.8415 -0.381)
			(stroke
				(width 0)
				(type default)
			)
			(fill no)
			(layer "F.CrtYd")
		)
		(fp_rect
			(start -1.8415 0.381)
			(end 1.8415 -0.381)
			(stroke
				(width 0)
				(type default)
			)
			(fill no)
			(layer "F.Fab")
		)
		(pad "1" thru_hole circle
			(at -1.4605 0 90)
			(size 0.508 0.508)
			(drill 0.254)
			(layers "*.Cu" "*.Mask")
			(remove_unused_layers no)
			(net "GND")
			(clearance 0.127)
			(thermal_gap 0.127)
		)
		(pad "2" thru_hole circle
			(at -0.4445 0 90)
			(size 0.508 0.508)
			(drill 0.254)
			(layers "*.Cu" "*.Mask")
			(remove_unused_layers no)
			(net "PCIE_IOM_TO_COMP_17_DP")
			(clearance 0.127)
			(thermal_gap 0.127)
		)
		(pad "3" thru_hole circle
			(at 0.4445 0 90)
			(size 0.508 0.508)
			(drill 0.254)
			(layers "*.Cu" "*.Mask")
			(remove_unused_layers no)
			(net "PCIE_IOM_TO_COMP_17_DN")
			(clearance 0.127)
			(thermal_gap 0.127)
		)
		(pad "4" thru_hole circle
			(at 1.4605 0 90)
			(size 0.508 0.508)
			(drill 0.254)
			(layers "*.Cu" "*.Mask")
			(remove_unused_layers no)
			(net "GND")
			(clearance 0.127)
			(thermal_gap 0.127)
		)
	)
	(footprint ""
		(layer "F.Cu")
		(at 184.322212 -45.387768)
		(property "Reference" "R669"
			(at 0 0 0)
			(layer "F.SilkS")
			(hide yes)
			(effects
				(font
					(size 1.27 1.27)
				)
			)
		)
		(property "Value" "10KR2F-2-GP"
			(at 0.064008 -3.993896 0)
			(unlocked yes)
			(layer "F.Fab")
			(hide yes)
			(effects
				(font
					(size 1.016 1.016)
					(thickness 0.1524)
				)
			)
		)
		(property "Device Type" "R402H16"
			(at 0.064008 -5.517896 0)
			(unlocked yes)
			(layer "F.Fab")
			(hide yes)
			(effects
				(font
					(size 1.016 1.016)
					(thickness 0.1524)
				)
			)
		)
		(duplicate_pad_numbers_are_jumpers no)
		(fp_line
			(start -0.508 -0.9398)
			(end -0.508 0.9398)
			(stroke
				(width 0.1524)
				(type default)
			)
			(layer "F.SilkS")
		)
		(fp_line
			(start 0.508 -0.9398)
			(end -0.508 -0.9398)
			(stroke
				(width 0.1524)
				(type default)
			)
			(layer "F.SilkS")
		)
		(fp_rect
			(start -0.508 0.9398)
			(end 0.508 -0.9398)
			(stroke
				(width 0)
				(type default)
			)
			(fill no)
			(layer "F.CrtYd")
		)
		(fp_rect
			(start -0.508 0.9398)
			(end 0.508 -0.9398)
			(stroke
				(width 0)
				(type default)
			)
			(fill no)
			(layer "F.Fab")
		)
		(pad "1" smd custom
			(at 0 -0.4445)
			(size 0.1397 0.1397)
			(layers "F.Cu" "F.Mask" "F.Paste")
			(net "XM_ADDR_2")
			(options
				(clearance outline)
				(anchor circle)
			)
			(primitives
				(gr_poly
					(pts
						(arc
							(start -0.1778 -0.2794)
							(mid -0.249642 -0.249642)
							(end -0.2794 -0.1778)
						)
						(arc
							(start -0.2794 0.1778)
							(mid -0.249642 0.249642)
							(end -0.1778 0.2794)
						)
						(arc
							(start 0.1778 0.2794)
							(mid 0.249642 0.249642)
							(end 0.2794 0.1778)
						)
						(arc
							(start 0.2794 -0.1778)
							(mid 0.249642 -0.249642)
							(end 0.1778 -0.2794)
						)
					)
					(width 0)
					(fill yes)
				)
			)
		)
		(pad "2" smd custom
			(at 0 0.4445)
			(size 0.1397 0.1397)
			(layers "F.Cu" "F.Mask" "F.Paste")
			(net "GND")
			(options
				(clearance outline)
				(anchor circle)
			)
			(primitives
				(gr_poly
					(pts
						(arc
							(start -0.1778 -0.2794)
							(mid -0.249642 -0.249642)
							(end -0.2794 -0.1778)
						)
						(arc
							(start -0.2794 0.1778)
							(mid -0.249642 0.249642)
							(end -0.1778 0.2794)
						)
						(arc
							(start 0.1778 0.2794)
							(mid 0.249642 0.249642)
							(end 0.2794 0.1778)
						)
						(arc
							(start 0.2794 -0.1778)
							(mid 0.249642 -0.249642)
							(end 0.1778 -0.2794)
						)
					)
					(width 0)
					(fill yes)
				)
			)
		)
	)
	(footprint ""
		(layer "F.Cu")
		(at 183.3626 -143.4084 -90)
		(property "Reference" "R475"
			(at 0 0 270)
			(layer "F.SilkS")
			(hide yes)
			(effects
				(font
					(size 1.27 1.27)
				)
			)
		)
		(property "Value" "57K6R2D-GP"
			(at 0.064008 -3.993896 270)
			(unlocked yes)
			(layer "F.Fab")
			(hide yes)
			(effects
				(font
					(size 1.016 1.016)
					(thickness 0.1524)
				)
			)
		)
		(property "Device Type" "R402H16"
			(at 0.064008 -5.517896 270)
			(unlocked yes)
			(layer "F.Fab")
			(hide yes)
			(effects
				(font
					(size 1.016 1.016)
					(thickness 0.1524)
				)
			)
		)
		(duplicate_pad_numbers_are_jumpers no)
		(fp_line
			(start -0.508 -0.9398)
			(end -0.508 0.9398)
			(stroke
				(width 0.1524)
				(type default)
			)
			(layer "F.SilkS")
		)
		(fp_line
			(start 0.508 -0.9398)
			(end -0.508 -0.9398)
			(stroke
				(width 0.1524)
				(type default)
			)
			(layer "F.SilkS")
		)
		(fp_rect
			(start -0.508 0.9398)
			(end 0.508 -0.9398)
			(stroke
				(width 0)
				(type default)
			)
			(fill no)
			(layer "F.CrtYd")
		)
		(fp_rect
			(start -0.508 0.9398)
			(end 0.508 -0.9398)
			(stroke
				(width 0)
				(type default)
			)
			(fill no)
			(layer "F.Fab")
		)
		(pad "1" smd custom
			(at 0 -0.4445 270)
			(size 0.1397 0.1397)
			(layers "F.Cu" "F.Mask" "F.Paste")
			(net "AGND_P5V")
			(options
				(clearance outline)
				(anchor circle)
			)
			(primitives
				(gr_poly
					(pts
						(arc
							(start -0.1778 -0.2794)
							(mid -0.249642 -0.249642)
							(end -0.2794 -0.1778)
						)
						(arc
							(start -0.2794 0.1778)
							(mid -0.249642 0.249642)
							(end -0.1778 0.2794)
						)
						(arc
							(start 0.1778 0.2794)
							(mid 0.249642 0.249642)
							(end 0.2794 0.1778)
						)
						(arc
							(start 0.2794 -0.1778)
							(mid 0.249642 -0.249642)
							(end 0.1778 -0.2794)
						)
					)
					(width 0)
					(fill yes)
				)
			)
		)
		(pad "2" smd custom
			(at 0 0.4445 270)
			(size 0.1397 0.1397)
			(layers "F.Cu" "F.Mask" "F.Paste")
			(net "P5V_TRIP")
			(options
				(clearance outline)
				(anchor circle)
			)
			(primitives
				(gr_poly
					(pts
						(arc
							(start -0.1778 -0.2794)
							(mid -0.249642 -0.249642)
							(end -0.2794 -0.1778)
						)
						(arc
							(start -0.2794 0.1778)
							(mid -0.249642 0.249642)
							(end -0.1778 0.2794)
						)
						(arc
							(start 0.1778 0.2794)
							(mid 0.249642 0.249642)
							(end 0.2794 0.1778)
						)
						(arc
							(start 0.2794 -0.1778)
							(mid 0.249642 -0.249642)
							(end 0.1778 -0.2794)
						)
					)
					(width 0)
					(fill yes)
				)
			)
		)
	)
	(footprint ""
		(layer "F.Cu")
		(at 77.283818 -86.954868 90)
		(property "Reference" "VIA6"
			(at 0 0 90)
			(layer "F.SilkS")
			(hide yes)
			(effects
				(font
					(size 1.27 1.27)
				)
			)
		)
		(property "Value" "85OHM-8L-1D6MM-L16L18-GP"
			(at 4.064 0.6096 90)
			(unlocked yes)
			(layer "F.Fab")
			(hide yes)
			(effects
				(font
					(size 1.016 1.016)
					(thickness 0.1524)
				)
			)
		)
		(property "Device Type" "VIA-PCIE-4P-368076"
			(at 4.064 -0.9144 90)
			(unlocked yes)
			(layer "F.Fab")
			(hide yes)
			(effects
				(font
					(size 1.016 1.016)
					(thickness 0.1524)
				)
			)
		)
		(duplicate_pad_numbers_are_jumpers no)
		(fp_rect
			(start -1.8415 0.381)
			(end 1.8415 -0.381)
			(stroke
				(width 0)
				(type default)
			)
			(fill no)
			(layer "F.CrtYd")
		)
		(fp_rect
			(start -1.8415 0.381)
			(end 1.8415 -0.381)
			(stroke
				(width 0)
				(type default)
			)
			(fill no)
			(layer "F.Fab")
		)
		(pad "1" thru_hole circle
			(at -1.4605 0 90)
			(size 0.508 0.508)
			(drill 0.254)
			(layers "*.Cu" "*.Mask")
			(remove_unused_layers no)
			(net "GND")
			(clearance 0.127)
			(thermal_gap 0.127)
		)
		(pad "2" thru_hole circle
			(at -0.4445 0 90)
			(size 0.508 0.508)
			(drill 0.254)
			(layers "*.Cu" "*.Mask")
			(remove_unused_layers no)
			(net "PCIE_COMP_TO_IOM_21_DP")
			(clearance 0.127)
			(thermal_gap 0.127)
		)
		(pad "3" thru_hole circle
			(at 0.4445 0 90)
			(size 0.508 0.508)
			(drill 0.254)
			(layers "*.Cu" "*.Mask")
			(remove_unused_layers no)
			(net "PCIE_COMP_TO_IOM_21_DN")
			(clearance 0.127)
			(thermal_gap 0.127)
		)
		(pad "4" thru_hole circle
			(at 1.4605 0 90)
			(size 0.508 0.508)
			(drill 0.254)
			(layers "*.Cu" "*.Mask")
			(remove_unused_layers no)
			(net "GND")
			(clearance 0.127)
			(thermal_gap 0.127)
		)
	)
	(footprint ""
		(layer "F.Cu")
		(at 184.6961 -48.1457)
		(property "Reference" "R667"
			(at 0 0 0)
			(layer "F.SilkS")
			(hide yes)
			(effects
				(font
					(size 1.27 1.27)
				)
			)
		)
		(property "Value" "10KR2F-2-GP"
			(at 0.064008 -3.993896 0)
			(unlocked yes)
			(layer "F.Fab")
			(hide yes)
			(effects
				(font
					(size 1.016 1.016)
					(thickness 0.1524)
				)
			)
		)
		(property "Device Type" "R402H16"
			(at 0.064008 -5.517896 0)
			(unlocked yes)
			(layer "F.Fab")
			(hide yes)
			(effects
				(font
					(size 1.016 1.016)
					(thickness 0.1524)
				)
			)
		)
		(duplicate_pad_numbers_are_jumpers no)
		(fp_line
			(start -0.508 -0.9398)
			(end -0.508 0.9398)
			(stroke
				(width 0.1524)
				(type default)
			)
			(layer "F.SilkS")
		)
		(fp_line
			(start 0.508 -0.9398)
			(end -0.508 -0.9398)
			(stroke
				(width 0.1524)
				(type default)
			)
			(layer "F.SilkS")
		)
		(fp_rect
			(start -0.508 0.9398)
			(end 0.508 -0.9398)
			(stroke
				(width 0)
				(type default)
			)
			(fill no)
			(layer "F.CrtYd")
		)
		(fp_rect
			(start -0.508 0.9398)
			(end 0.508 -0.9398)
			(stroke
				(width 0)
				(type default)
			)
			(fill no)
			(layer "F.Fab")
		)
		(pad "1" smd custom
			(at 0 -0.4445)
			(size 0.1397 0.1397)
			(layers "F.Cu" "F.Mask" "F.Paste")
			(net "XM_ADDR_0")
			(options
				(clearance outline)
				(anchor circle)
			)
			(primitives
				(gr_poly
					(pts
						(arc
							(start -0.1778 -0.2794)
							(mid -0.249642 -0.249642)
							(end -0.2794 -0.1778)
						)
						(arc
							(start -0.2794 0.1778)
							(mid -0.249642 0.249642)
							(end -0.1778 0.2794)
						)
						(arc
							(start 0.1778 0.2794)
							(mid 0.249642 0.249642)
							(end 0.2794 0.1778)
						)
						(arc
							(start 0.2794 -0.1778)
							(mid 0.249642 -0.249642)
							(end 0.1778 -0.2794)
						)
					)
					(width 0)
					(fill yes)
				)
			)
		)
		(pad "2" smd custom
			(at 0 0.4445)
			(size 0.1397 0.1397)
			(layers "F.Cu" "F.Mask" "F.Paste")
			(net "GND")
			(options
				(clearance outline)
				(anchor circle)
			)
			(primitives
				(gr_poly
					(pts
						(arc
							(start -0.1778 -0.2794)
							(mid -0.249642 -0.249642)
							(end -0.2794 -0.1778)
						)
						(arc
							(start -0.2794 0.1778)
							(mid -0.249642 0.249642)
							(end -0.1778 0.2794)
						)
						(arc
							(start 0.1778 0.2794)
							(mid 0.249642 0.249642)
							(end 0.2794 0.1778)
						)
						(arc
							(start 0.2794 -0.1778)
							(mid 0.249642 -0.249642)
							(end 0.1778 -0.2794)
						)
					)
					(width 0)
					(fill yes)
				)
			)
		)
	)
	(footprint ""
		(layer "F.Cu")
		(at 16.691356 -169.1259 -90)
		(property "Reference" "PU10"
			(at 0 0 270)
			(layer "F.SilkS")
			(hide yes)
			(effects
				(font
					(size 1.27 1.27)
				)
			)
		)
		(property "Value" "TPS74801RGW-GP"
			(at -4.7244 -6.223 270)
			(unlocked yes)
			(layer "F.Fab")
			(hide yes)
			(effects
				(font
					(size 1.016 1.016)
					(thickness 0.1524)
				)
			)
		)
		(property "Device Type" "QFN20-1G3D15H40"
			(at -4.7244 -7.747 270)
			(unlocked yes)
			(layer "F.Fab")
			(hide yes)
			(effects
				(font
					(size 1.016 1.016)
					(thickness 0.1524)
				)
			)
		)
		(duplicate_pad_numbers_are_jumpers no)
		(fp_line
			(start -3.5179 3.5179)
			(end -2.2479 3.5179)
			(stroke
				(width 0.1524)
				(type default)
			)
			(layer "F.SilkS")
		)
		(fp_line
			(start 2.2479 3.5179)
			(end 3.5179 3.5179)
			(stroke
				(width 0.1524)
				(type default)
			)
			(layer "F.SilkS")
		)
		(fp_line
			(start 3.5179 3.5179)
			(end 3.5179 2.2479)
			(stroke
				(width 0.1524)
				(type default)
			)
			(layer "F.SilkS")
		)
		(fp_line
			(start 1.299972 3.160522)
			(end 1.299972 3.668522)
			(stroke
				(width 0.1524)
				(type default)
			)
			(layer "F.SilkS")
		)
		(fp_line
			(start -3.5179 2.2479)
			(end -3.5179 3.5179)
			(stroke
				(width 0.1524)
				(type default)
			)
			(layer "F.SilkS")
		)
		(fp_line
			(start -3.160522 1.299972)
			(end -3.922522 1.299972)
			(stroke
				(width 0.1524)
				(type default)
			)
			(layer "F.SilkS")
		)
		(fp_line
			(start 3.160522 -1.299972)
			(end 3.922522 -1.299972)
			(stroke
				(width 0.1524)
				(type default)
			)
			(layer "F.SilkS")
		)
		(fp_line
			(start -1.299972 -3.160522)
			(end -1.299972 -3.668522)
			(stroke
				(width 0.1524)
				(type default)
			)
			(layer "F.SilkS")
		)
		(fp_line
			(start -3.5179 -3.5179)
			(end -3.5179 -2.2479)
			(stroke
				(width 0.1524)
				(type default)
			)
			(layer "F.SilkS")
		)
		(fp_line
			(start -2.2479 -3.5179)
			(end -3.5179 -3.5179)
			(stroke
				(width 0.1524)
				(type default)
			)
			(layer "F.SilkS")
		)
		(fp_poly
			(pts
				(xy 3.5179 -3.5179) (xy 2.2479 -3.5179) (xy 3.5179 -2.2479)
			)
			(stroke
				(width 0)
				(type default)
			)
			(fill yes)
			(layer "F.SilkS")
		)
		(fp_rect
			(start -2.5019 2.5019)
			(end 2.5019 -2.5019)
			(stroke
				(width 0)
				(type default)
			)
			(fill no)
			(layer "F.CrtYd")
		)
		(fp_poly
			(pts
				(xy -3.5179 3.5179) (xy -3.5179 -3.5179) (xy 3.5179 -3.5179) (xy 3.5179 -2.5019) (xy -2.5019 -2.5019)
				(xy -2.5019 2.5019) (xy 2.5019 2.5019) (xy 2.5019 -2.49682) (xy 3.5179 -2.49682) (xy 3.5179 3.5179)
			)
			(stroke
				(width 0)
				(type default)
			)
			(fill no)
			(layer "F.CrtYd")
		)
		(fp_rect
			(start -3.5179 3.5179)
			(end 3.5179 -3.5179)
			(stroke
				(width 0)
				(type default)
			)
			(fill no)
			(layer "F.Fab")
		)
		(pad "1" smd rect
			(at 1.299972 -2.474722 270)
			(size 0.3556 1.0668)
			(layers "F.Cu" "F.Mask" "F.Paste")
			(net "TPS74801_P1V2_STBY_OUT")
		)
		(pad "2" smd rect
			(at 0.649986 -2.474722 270)
			(size 0.3556 1.0668)
			(layers "F.Cu" "F.Mask" "F.Paste")
			(net "GND")
		)
		(pad "3" smd rect
			(at 0 -2.474722 270)
			(size 0.3556 1.0668)
			(layers "F.Cu" "F.Mask" "F.Paste")
			(net "GND")
		)
		(pad "4" smd rect
			(at -0.649986 -2.474722 270)
			(size 0.3556 1.0668)
			(layers "F.Cu" "F.Mask" "F.Paste")
			(net "GND")
		)
		(pad "5" smd rect
			(at -1.299972 -2.474722 270)
			(size 0.3556 1.0668)
			(layers "F.Cu" "F.Mask" "F.Paste")
			(net "P1V8_STBY")
		)
		(pad "6" smd rect
			(at -2.474722 -1.299972 270)
			(size 1.0668 0.3556)
			(layers "F.Cu" "F.Mask" "F.Paste")
			(net "P1V8_STBY")
		)
		(pad "7" smd rect
			(at -2.474722 -0.649986 270)
			(size 1.0668 0.3556)
			(layers "F.Cu" "F.Mask" "F.Paste")
			(net "P1V8_STBY")
		)
		(pad "8" smd rect
			(at -2.474722 0 270)
			(size 1.0668 0.3556)
			(layers "F.Cu" "F.Mask" "F.Paste")
			(net "P1V8_STBY")
		)
		(pad "9" smd rect
			(at -2.474722 0.649986 270)
			(size 1.0668 0.3556)
			(layers "F.Cu" "F.Mask" "F.Paste")
			(net "PWRGD_P1V2_STBY")
		)
		(pad "10" smd rect
			(at -2.474722 1.299972 270)
			(size 1.0668 0.3556)
			(layers "F.Cu" "F.Mask" "F.Paste")
			(net "TPS74801_P1V2_STBY_BIAS")
		)
		(pad "11" smd rect
			(at -1.299972 2.474722 270)
			(size 0.3556 1.0668)
			(layers "F.Cu" "F.Mask" "F.Paste")
			(net "TPS74801_P1V2_STBY_EN")
		)
		(pad "12" smd rect
			(at -0.649986 2.474722 270)
			(size 0.3556 1.0668)
			(layers "F.Cu" "F.Mask" "F.Paste")
			(net "GND")
		)
		(pad "13" smd rect
			(at 0 2.474722 270)
			(size 0.3556 1.0668)
			(layers "F.Cu" "F.Mask" "F.Paste")
			(net "GND")
		)
		(pad "14" smd rect
			(at 0.649986 2.474722 270)
			(size 0.3556 1.0668)
			(layers "F.Cu" "F.Mask" "F.Paste")
			(net "GND")
		)
		(pad "15" smd rect
			(at 1.299972 2.474722 270)
			(size 0.3556 1.0668)
			(layers "F.Cu" "F.Mask" "F.Paste")
			(net "TPS74801_P1V2_STBY_SS")
		)
		(pad "16" smd rect
			(at 2.474722 1.299972 270)
			(size 1.0668 0.3556)
			(layers "F.Cu" "F.Mask" "F.Paste")
			(net "TPS74801_P1V2_STBY_FB")
		)
		(pad "17" smd rect
			(at 2.474722 0.649986 270)
			(size 1.0668 0.3556)
			(layers "F.Cu" "F.Mask" "F.Paste")
			(net "GND")
		)
		(pad "18" smd rect
			(at 2.474722 0 270)
			(size 1.0668 0.3556)
			(layers "F.Cu" "F.Mask" "F.Paste")
			(net "TPS74801_P1V2_STBY_OUT")
		)
		(pad "19" smd rect
			(at 2.474722 -0.649986 270)
			(size 1.0668 0.3556)
			(layers "F.Cu" "F.Mask" "F.Paste")
			(net "TPS74801_P1V2_STBY_OUT")
		)
		(pad "20" smd rect
			(at 2.474722 -1.299972 270)
			(size 1.0668 0.3556)
			(layers "F.Cu" "F.Mask" "F.Paste")
			(net "TPS74801_P1V2_STBY_OUT")
		)
		(pad "21" smd rect
			(at 0 0 270)
			(size 3.2512 3.2512)
			(layers "F.Cu" "F.Mask" "F.Paste")
			(net "GND")
		)
	)
	(footprint ""
		(layer "F.Cu")
		(at 199.792336 -134.3025 180)
		(property "Reference" "Q8"
			(at 0 0 180)
			(layer "F.SilkS")
			(hide yes)
			(effects
				(font
					(size 1.27 1.27)
				)
			)
		)
		(property "Value" "2N7002K-1-GP"
			(at 0.127 -8.9662 180)
			(unlocked yes)
			(layer "F.Fab")
			(hide yes)
			(effects
				(font
					(size 1.016 1.016)
					(thickness 0.1524)
				)
			)
		)
		(property "Device Type" "SOT23DGS2D4H44"
			(at 0.127 -10.4902 180)
			(unlocked yes)
			(layer "F.Fab")
			(hide yes)
			(effects
				(font
					(size 1.016 1.016)
					(thickness 0.1524)
				)
			)
		)
		(duplicate_pad_numbers_are_jumpers no)
		(fp_line
			(start 1.651 1.778)
			(end 1.651 -1.778)
			(stroke
				(width 0.1524)
				(type default)
			)
			(layer "F.SilkS")
		)
		(fp_line
			(start 1.651 -1.778)
			(end -1.651 -1.778)
			(stroke
				(width 0.1524)
				(type default)
			)
			(layer "F.SilkS")
		)
		(fp_line
			(start -1.651 1.778)
			(end 1.651 1.778)
			(stroke
				(width 0.1524)
				(type default)
			)
			(layer "F.SilkS")
		)
		(fp_line
			(start -1.651 -1.778)
			(end -1.651 1.778)
			(stroke
				(width 0.1524)
				(type default)
			)
			(layer "F.SilkS")
		)
		(fp_poly
			(pts
				(xy -1.778 1.8796) (xy -1.778 -1.8796) (xy 1.778 -1.8796) (xy 1.778 1.8796)
			)
			(stroke
				(width 0)
				(type default)
			)
			(fill no)
			(layer "F.CrtYd")
		)
		(fp_poly
			(pts
				(xy -1.778 1.8796) (xy -1.778 -1.8796) (xy 1.778 -1.8796) (xy 1.778 1.8796)
			)
			(stroke
				(width 0)
				(type default)
			)
			(fill no)
			(layer "F.Fab")
		)
		(pad "D" smd custom
			(at 0 -0.9525 180)
			(size 0.1905 0.1905)
			(layers "F.Cu" "F.Mask" "F.Paste")
			(net "PWRGD_P1V8")
			(options
				(clearance outline)
				(anchor circle)
			)
			(primitives
				(gr_poly
					(pts
						(arc
							(start -0.1778 0.5715)
							(mid -0.321484 0.511984)
							(end -0.381 0.3683)
						)
						(arc
							(start -0.381 -0.3683)
							(mid -0.321484 -0.511984)
							(end -0.1778 -0.5715)
						)
						(arc
							(start 0.1778 -0.5715)
							(mid 0.321484 -0.511984)
							(end 0.381 -0.3683)
						)
						(arc
							(start 0.381 0.3683)
							(mid 0.321484 0.511984)
							(end 0.1778 0.5715)
						)
					)
					(width 0)
					(fill yes)
				)
			)
		)
		(pad "G" smd custom
			(at -0.98425 0.9525 180)
			(size 0.1905 0.1905)
			(layers "F.Cu" "F.Mask" "F.Paste")
			(net "Q8_G")
			(options
				(clearance outline)
				(anchor circle)
			)
			(primitives
				(gr_poly
					(pts
						(arc
							(start -0.1778 0.5715)
							(mid -0.321484 0.511984)
							(end -0.381 0.3683)
						)
						(arc
							(start -0.381 -0.3683)
							(mid -0.321484 -0.511984)
							(end -0.1778 -0.5715)
						)
						(arc
							(start 0.1778 -0.5715)
							(mid 0.321484 -0.511984)
							(end 0.381 -0.3683)
						)
						(arc
							(start 0.381 0.3683)
							(mid 0.321484 0.511984)
							(end 0.1778 0.5715)
						)
					)
					(width 0)
					(fill yes)
				)
			)
		)
		(pad "S" smd custom
			(at 0.98425 0.9525 180)
			(size 0.1905 0.1905)
			(layers "F.Cu" "F.Mask" "F.Paste")
			(net "GND")
			(options
				(clearance outline)
				(anchor circle)
			)
			(primitives
				(gr_poly
					(pts
						(arc
							(start -0.1778 0.5715)
							(mid -0.321484 0.511984)
							(end -0.381 0.3683)
						)
						(arc
							(start -0.381 -0.3683)
							(mid -0.321484 -0.511984)
							(end -0.1778 -0.5715)
						)
						(arc
							(start 0.1778 -0.5715)
							(mid 0.321484 -0.511984)
							(end 0.381 -0.3683)
						)
						(arc
							(start 0.381 0.3683)
							(mid 0.321484 0.511984)
							(end 0.1778 0.5715)
						)
					)
					(width 0)
					(fill yes)
				)
			)
		)
	)
	(footprint ""
		(layer "F.Cu")
		(at 179.1462 -39.3954)
		(property "Reference" "TP175"
			(at 0 0 0)
			(layer "F.SilkS")
			(hide yes)
			(effects
				(font
					(size 1.27 1.27)
				)
			)
		)
		(property "Value" "TPAD28-2-GP"
			(at -0.0127 -1.6637 0)
			(unlocked yes)
			(layer "F.Fab")
			(hide yes)
			(effects
				(font
					(size 1.016 1.016)
					(thickness 0.1524)
				)
			)
		)
		(property "Device Type" "TPAD28"
			(at -0.0127 -3.1877 0)
			(unlocked yes)
			(layer "F.Fab")
			(hide yes)
			(effects
				(font
					(size 1.016 1.016)
					(thickness 0.1524)
				)
			)
		)
		(duplicate_pad_numbers_are_jumpers no)
		(fp_poly
			(pts
				(arc
					(start 0.3556 0)
					(mid -0.3556 0)
					(end 0.3556 0)
				)
			)
			(stroke
				(width 0)
				(type default)
			)
			(fill no)
			(layer "F.CrtYd")
		)
		(fp_poly
			(pts
				(arc
					(start 0.6096 0)
					(mid -0.6096 0)
					(end 0.6096 0)
				)
			)
			(stroke
				(width 0)
				(type default)
			)
			(fill no)
			(layer "F.Fab")
		)
		(pad "1" smd circle
			(at 0 0)
			(size 0.7112 0.7112)
			(layers "F.Cu" "F.Mask" "F.Paste")
			(net "ZDEF_EXTA_TP_D1")
		)
	)
	(footprint ""
		(layer "F.Cu")
		(at 124.841 -5.588 -90)
		(property "Reference" "R712"
			(at 0 0 270)
			(layer "F.SilkS")
			(hide yes)
			(effects
				(font
					(size 1.27 1.27)
				)
			)
		)
		(property "Value" "0R2J-2-GP"
			(at 0.064008 -3.993896 270)
			(unlocked yes)
			(layer "F.Fab")
			(hide yes)
			(effects
				(font
					(size 1.016 1.016)
					(thickness 0.1524)
				)
			)
		)
		(property "Device Type" "R402H16"
			(at 0.064008 -5.517896 270)
			(unlocked yes)
			(layer "F.Fab")
			(hide yes)
			(effects
				(font
					(size 1.016 1.016)
					(thickness 0.1524)
				)
			)
		)
		(duplicate_pad_numbers_are_jumpers no)
		(fp_line
			(start -0.508 -0.9398)
			(end -0.508 0.9398)
			(stroke
				(width 0.1524)
				(type default)
			)
			(layer "F.SilkS")
		)
		(fp_line
			(start 0.508 -0.9398)
			(end -0.508 -0.9398)
			(stroke
				(width 0.1524)
				(type default)
			)
			(layer "F.SilkS")
		)
		(fp_rect
			(start -0.508 0.9398)
			(end 0.508 -0.9398)
			(stroke
				(width 0)
				(type default)
			)
			(fill no)
			(layer "F.CrtYd")
		)
		(fp_rect
			(start -0.508 0.9398)
			(end 0.508 -0.9398)
			(stroke
				(width 0)
				(type default)
			)
			(fill no)
			(layer "F.Fab")
		)
		(pad "1" smd custom
			(at 0 -0.4445 270)
			(size 0.1397 0.1397)
			(layers "F.Cu" "F.Mask" "F.Paste")
			(net "I2C_IOM_SDA")
			(options
				(clearance outline)
				(anchor circle)
			)
			(primitives
				(gr_poly
					(pts
						(arc
							(start -0.1778 -0.2794)
							(mid -0.249642 -0.249642)
							(end -0.2794 -0.1778)
						)
						(arc
							(start -0.2794 0.1778)
							(mid -0.249642 0.249642)
							(end -0.1778 0.2794)
						)
						(arc
							(start 0.1778 0.2794)
							(mid 0.249642 0.249642)
							(end 0.2794 0.1778)
						)
						(arc
							(start 0.2794 -0.1778)
							(mid 0.249642 -0.249642)
							(end 0.1778 -0.2794)
						)
					)
					(width 0)
					(fill yes)
				)
			)
		)
		(pad "2" smd custom
			(at 0 0.4445 270)
			(size 0.1397 0.1397)
			(layers "F.Cu" "F.Mask" "F.Paste")
			(net "HSW_SDA")
			(options
				(clearance outline)
				(anchor circle)
			)
			(primitives
				(gr_poly
					(pts
						(arc
							(start -0.1778 -0.2794)
							(mid -0.249642 -0.249642)
							(end -0.2794 -0.1778)
						)
						(arc
							(start -0.2794 0.1778)
							(mid -0.249642 0.249642)
							(end -0.1778 0.2794)
						)
						(arc
							(start 0.1778 0.2794)
							(mid 0.249642 0.249642)
							(end 0.2794 0.1778)
						)
						(arc
							(start 0.2794 -0.1778)
							(mid 0.249642 -0.249642)
							(end 0.1778 -0.2794)
						)
					)
					(width 0)
					(fill yes)
				)
			)
		)
	)
	(footprint ""
		(layer "F.Cu")
		(at 41.91 -164.084 180)
		(property "Reference" "R327"
			(at 0 0 180)
			(layer "F.SilkS")
			(hide yes)
			(effects
				(font
					(size 1.27 1.27)
				)
			)
		)
		(property "Value" "4K7R2F-GP"
			(at 0.064008 -3.993896 180)
			(unlocked yes)
			(layer "F.Fab")
			(hide yes)
			(effects
				(font
					(size 1.016 1.016)
					(thickness 0.1524)
				)
			)
		)
		(property "Device Type" "R402H16"
			(at 0.064008 -5.517896 180)
			(unlocked yes)
			(layer "F.Fab")
			(hide yes)
			(effects
				(font
					(size 1.016 1.016)
					(thickness 0.1524)
				)
			)
		)
		(duplicate_pad_numbers_are_jumpers no)
		(fp_line
			(start 0.508 -0.9398)
			(end -0.508 -0.9398)
			(stroke
				(width 0.1524)
				(type default)
			)
			(layer "F.SilkS")
		)
		(fp_line
			(start -0.508 -0.9398)
			(end -0.508 0.9398)
			(stroke
				(width 0.1524)
				(type default)
			)
			(layer "F.SilkS")
		)
		(fp_rect
			(start -0.508 0.9398)
			(end 0.508 -0.9398)
			(stroke
				(width 0)
				(type default)
			)
			(fill no)
			(layer "F.CrtYd")
		)
		(fp_rect
			(start -0.508 0.9398)
			(end 0.508 -0.9398)
			(stroke
				(width 0)
				(type default)
			)
			(fill no)
			(layer "F.Fab")
		)
		(pad "1" smd custom
			(at 0 -0.4445 180)
			(size 0.1397 0.1397)
			(layers "F.Cu" "F.Mask" "F.Paste")
			(net "P3V3_STBY")
			(options
				(clearance outline)
				(anchor circle)
			)
			(primitives
				(gr_poly
					(pts
						(arc
							(start -0.1778 -0.2794)
							(mid -0.249642 -0.249642)
							(end -0.2794 -0.1778)
						)
						(arc
							(start -0.2794 0.1778)
							(mid -0.249642 0.249642)
							(end -0.1778 0.2794)
						)
						(arc
							(start 0.1778 0.2794)
							(mid 0.249642 0.249642)
							(end 0.2794 0.1778)
						)
						(arc
							(start 0.2794 -0.1778)
							(mid 0.249642 -0.249642)
							(end 0.1778 -0.2794)
						)
					)
					(width 0)
					(fill yes)
				)
			)
		)
		(pad "2" smd custom
			(at 0 0.4445 180)
			(size 0.1397 0.1397)
			(layers "F.Cu" "F.Mask" "F.Paste")
			(net "UART_EXP_BMC_RX")
			(options
				(clearance outline)
				(anchor circle)
			)
			(primitives
				(gr_poly
					(pts
						(arc
							(start -0.1778 -0.2794)
							(mid -0.249642 -0.249642)
							(end -0.2794 -0.1778)
						)
						(arc
							(start -0.2794 0.1778)
							(mid -0.249642 0.249642)
							(end -0.1778 0.2794)
						)
						(arc
							(start 0.1778 0.2794)
							(mid 0.249642 0.249642)
							(end 0.2794 0.1778)
						)
						(arc
							(start 0.2794 -0.1778)
							(mid 0.249642 -0.249642)
							(end 0.1778 -0.2794)
						)
					)
					(width 0)
					(fill yes)
				)
			)
		)
	)
	(footprint ""
		(layer "F.Cu")
		(at 191.4144 -86.995 135)
		(property "Reference" "VIA23"
			(at 0 0 135)
			(layer "F.SilkS")
			(hide yes)
			(effects
				(font
					(size 1.27 1.27)
				)
			)
		)
		(property "Value" "85OHM-8L-1D6MM-L16L18-GP"
			(at 4.064105 0.609655 135)
			(unlocked yes)
			(layer "F.Fab")
			(hide yes)
			(effects
				(font
					(size 1.016 1.016)
					(thickness 0.1524)
				)
			)
		)
		(property "Device Type" "VIA-PCIE-4P-368076"
			(at 4.064105 -0.914474 135)
			(unlocked yes)
			(layer "F.Fab")
			(hide yes)
			(effects
				(font
					(size 1.016 1.016)
					(thickness 0.1524)
				)
			)
		)
		(duplicate_pad_numbers_are_jumpers no)
		(fp_poly
			(pts
				(xy -1.841491 -0.381057) (xy 1.841509 -0.381058) (xy 1.841508 0.380942) (xy -1.841491 0.380942)
			)
			(stroke
				(width 0)
				(type default)
			)
			(fill no)
			(layer "F.CrtYd")
		)
		(fp_poly
			(pts
				(xy -1.841491 -0.381057) (xy 1.841509 -0.381058) (xy 1.841508 0.380942) (xy -1.841491 0.380942)
			)
			(stroke
				(width 0)
				(type default)
			)
			(fill no)
			(layer "F.Fab")
		)
		(pad "1" thru_hole circle
			(at -1.460499 0 135)
			(size 0.508 0.508)
			(drill 0.254)
			(layers "*.Cu" "*.Mask")
			(remove_unused_layers no)
			(net "GND")
			(clearance 0.127)
			(thermal_gap 0.127)
		)
		(pad "2" thru_hole circle
			(at -0.4445 0 135)
			(size 0.508 0.508)
			(drill 0.254)
			(layers "*.Cu" "*.Mask")
			(remove_unused_layers no)
			(net "PCIE_COMP_TO_IOM_14_DP")
			(clearance 0.127)
			(thermal_gap 0.127)
		)
		(pad "3" thru_hole circle
			(at 0.4445 0 135)
			(size 0.508 0.508)
			(drill 0.254)
			(layers "*.Cu" "*.Mask")
			(remove_unused_layers no)
			(net "PCIE_COMP_TO_IOM_14_DN")
			(clearance 0.127)
			(thermal_gap 0.127)
		)
		(pad "4" thru_hole circle
			(at 1.460499 0 135)
			(size 0.508 0.508)
			(drill 0.254)
			(layers "*.Cu" "*.Mask")
			(remove_unused_layers no)
			(net "GND")
			(clearance 0.127)
			(thermal_gap 0.127)
		)
	)
	(footprint ""
		(layer "F.Cu")
		(at 190.8556 -127.635 180)
		(property "Reference" "R563"
			(at 0 0 180)
			(layer "F.SilkS")
			(hide yes)
			(effects
				(font
					(size 1.27 1.27)
				)
			)
		)
		(property "Value" "100KR2F-L1-GP"
			(at 0.064008 -3.993896 180)
			(unlocked yes)
			(layer "F.Fab")
			(hide yes)
			(effects
				(font
					(size 1.016 1.016)
					(thickness 0.1524)
				)
			)
		)
		(property "Device Type" "R402H16"
			(at 0.064008 -5.517896 180)
			(unlocked yes)
			(layer "F.Fab")
			(hide yes)
			(effects
				(font
					(size 1.016 1.016)
					(thickness 0.1524)
				)
			)
		)
		(duplicate_pad_numbers_are_jumpers no)
		(fp_line
			(start 0.508 -0.9398)
			(end -0.508 -0.9398)
			(stroke
				(width 0.1524)
				(type default)
			)
			(layer "F.SilkS")
		)
		(fp_line
			(start -0.508 -0.9398)
			(end -0.508 0.9398)
			(stroke
				(width 0.1524)
				(type default)
			)
			(layer "F.SilkS")
		)
		(fp_rect
			(start -0.508 0.9398)
			(end 0.508 -0.9398)
			(stroke
				(width 0)
				(type default)
			)
			(fill no)
			(layer "F.CrtYd")
		)
		(fp_rect
			(start -0.508 0.9398)
			(end 0.508 -0.9398)
			(stroke
				(width 0)
				(type default)
			)
			(fill no)
			(layer "F.Fab")
		)
		(pad "1" smd custom
			(at 0 -0.4445 180)
			(size 0.1397 0.1397)
			(layers "F.Cu" "F.Mask" "F.Paste")
			(net "VT235_VDES")
			(options
				(clearance outline)
				(anchor circle)
			)
			(primitives
				(gr_poly
					(pts
						(arc
							(start -0.1778 -0.2794)
							(mid -0.249642 -0.249642)
							(end -0.2794 -0.1778)
						)
						(arc
							(start -0.2794 0.1778)
							(mid -0.249642 0.249642)
							(end -0.1778 0.2794)
						)
						(arc
							(start 0.1778 0.2794)
							(mid 0.249642 0.249642)
							(end 0.2794 0.1778)
						)
						(arc
							(start 0.2794 -0.1778)
							(mid 0.249642 -0.249642)
							(end 0.1778 -0.2794)
						)
					)
					(width 0)
					(fill yes)
				)
			)
		)
		(pad "2" smd custom
			(at 0 0.4445 180)
			(size 0.1397 0.1397)
			(layers "F.Cu" "F.Mask" "F.Paste")
			(net "VT235_VREF")
			(options
				(clearance outline)
				(anchor circle)
			)
			(primitives
				(gr_poly
					(pts
						(arc
							(start -0.1778 -0.2794)
							(mid -0.249642 -0.249642)
							(end -0.2794 -0.1778)
						)
						(arc
							(start -0.2794 0.1778)
							(mid -0.249642 0.249642)
							(end -0.1778 0.2794)
						)
						(arc
							(start 0.1778 0.2794)
							(mid 0.249642 0.249642)
							(end 0.2794 0.1778)
						)
						(arc
							(start 0.2794 -0.1778)
							(mid 0.249642 -0.249642)
							(end 0.1778 -0.2794)
						)
					)
					(width 0)
					(fill yes)
				)
			)
		)
	)
	(footprint ""
		(layer "F.Cu")
		(at 46.449996 -131.747514 180)
		(property "Reference" "R265"
			(at 0 0 180)
			(layer "F.SilkS")
			(hide yes)
			(effects
				(font
					(size 1.27 1.27)
				)
			)
		)
		(property "Value" "4K7R2F-GP"
			(at 0.064008 -3.993896 180)
			(unlocked yes)
			(layer "F.Fab")
			(hide yes)
			(effects
				(font
					(size 1.016 1.016)
					(thickness 0.1524)
				)
			)
		)
		(property "Device Type" "R402H16"
			(at 0.064008 -5.517896 180)
			(unlocked yes)
			(layer "F.Fab")
			(hide yes)
			(effects
				(font
					(size 1.016 1.016)
					(thickness 0.1524)
				)
			)
		)
		(duplicate_pad_numbers_are_jumpers no)
		(fp_line
			(start 0.508 -0.9398)
			(end -0.508 -0.9398)
			(stroke
				(width 0.1524)
				(type default)
			)
			(layer "F.SilkS")
		)
		(fp_line
			(start -0.508 -0.9398)
			(end -0.508 0.9398)
			(stroke
				(width 0.1524)
				(type default)
			)
			(layer "F.SilkS")
		)
		(fp_rect
			(start -0.508 0.9398)
			(end 0.508 -0.9398)
			(stroke
				(width 0)
				(type default)
			)
			(fill no)
			(layer "F.CrtYd")
		)
		(fp_rect
			(start -0.508 0.9398)
			(end 0.508 -0.9398)
			(stroke
				(width 0)
				(type default)
			)
			(fill no)
			(layer "F.Fab")
		)
		(pad "1" smd custom
			(at 0 -0.4445 180)
			(size 0.1397 0.1397)
			(layers "F.Cu" "F.Mask" "F.Paste")
			(net "P3V3_STBY")
			(options
				(clearance outline)
				(anchor circle)
			)
			(primitives
				(gr_poly
					(pts
						(arc
							(start -0.1778 -0.2794)
							(mid -0.249642 -0.249642)
							(end -0.2794 -0.1778)
						)
						(arc
							(start -0.2794 0.1778)
							(mid -0.249642 0.249642)
							(end -0.1778 0.2794)
						)
						(arc
							(start 0.1778 0.2794)
							(mid 0.249642 0.249642)
							(end 0.2794 0.1778)
						)
						(arc
							(start 0.2794 -0.1778)
							(mid 0.249642 -0.249642)
							(end 0.1778 -0.2794)
						)
					)
					(width 0)
					(fill yes)
				)
			)
		)
		(pad "2" smd custom
			(at 0 0.4445 180)
			(size 0.1397 0.1397)
			(layers "F.Cu" "F.Mask" "F.Paste")
			(net "BMC_GPIOY3")
			(options
				(clearance outline)
				(anchor circle)
			)
			(primitives
				(gr_poly
					(pts
						(arc
							(start -0.1778 -0.2794)
							(mid -0.249642 -0.249642)
							(end -0.2794 -0.1778)
						)
						(arc
							(start -0.2794 0.1778)
							(mid -0.249642 0.249642)
							(end -0.1778 0.2794)
						)
						(arc
							(start 0.1778 0.2794)
							(mid 0.249642 0.249642)
							(end 0.2794 0.1778)
						)
						(arc
							(start 0.2794 -0.1778)
							(mid 0.249642 -0.249642)
							(end 0.1778 -0.2794)
						)
					)
					(width 0)
					(fill yes)
				)
			)
		)
	)
	(footprint ""
		(layer "F.Cu")
		(at 179.787804 -153.207466 180)
		(property "Reference" "R471"
			(at 0 0 180)
			(layer "F.SilkS")
			(hide yes)
			(effects
				(font
					(size 1.27 1.27)
				)
			)
		)
		(property "Value" "15KR2F-GP"
			(at 0.064008 -3.993896 180)
			(unlocked yes)
			(layer "F.Fab")
			(hide yes)
			(effects
				(font
					(size 1.016 1.016)
					(thickness 0.1524)
				)
			)
		)
		(property "Device Type" "R402H16"
			(at 0.064008 -5.517896 180)
			(unlocked yes)
			(layer "F.Fab")
			(hide yes)
			(effects
				(font
					(size 1.016 1.016)
					(thickness 0.1524)
				)
			)
		)
		(duplicate_pad_numbers_are_jumpers no)
		(fp_line
			(start 0.508 -0.9398)
			(end -0.508 -0.9398)
			(stroke
				(width 0.1524)
				(type default)
			)
			(layer "F.SilkS")
		)
		(fp_line
			(start -0.508 -0.9398)
			(end -0.508 0.9398)
			(stroke
				(width 0.1524)
				(type default)
			)
			(layer "F.SilkS")
		)
		(fp_rect
			(start -0.508 0.9398)
			(end 0.508 -0.9398)
			(stroke
				(width 0)
				(type default)
			)
			(fill no)
			(layer "F.CrtYd")
		)
		(fp_rect
			(start -0.508 0.9398)
			(end 0.508 -0.9398)
			(stroke
				(width 0)
				(type default)
			)
			(fill no)
			(layer "F.Fab")
		)
		(pad "1" smd custom
			(at 0 -0.4445 180)
			(size 0.1397 0.1397)
			(layers "F.Cu" "F.Mask" "F.Paste")
			(net "PWRGD_P5V_STBY")
			(options
				(clearance outline)
				(anchor circle)
			)
			(primitives
				(gr_poly
					(pts
						(arc
							(start -0.1778 -0.2794)
							(mid -0.249642 -0.249642)
							(end -0.2794 -0.1778)
						)
						(arc
							(start -0.2794 0.1778)
							(mid -0.249642 0.249642)
							(end -0.1778 0.2794)
						)
						(arc
							(start 0.1778 0.2794)
							(mid 0.249642 0.249642)
							(end 0.2794 0.1778)
						)
						(arc
							(start 0.2794 -0.1778)
							(mid 0.249642 -0.249642)
							(end 0.1778 -0.2794)
						)
					)
					(width 0)
					(fill yes)
				)
			)
		)
		(pad "2" smd custom
			(at 0 0.4445 180)
			(size 0.1397 0.1397)
			(layers "F.Cu" "F.Mask" "F.Paste")
			(net "GND")
			(options
				(clearance outline)
				(anchor circle)
			)
			(primitives
				(gr_poly
					(pts
						(arc
							(start -0.1778 -0.2794)
							(mid -0.249642 -0.249642)
							(end -0.2794 -0.1778)
						)
						(arc
							(start -0.2794 0.1778)
							(mid -0.249642 0.249642)
							(end -0.1778 0.2794)
						)
						(arc
							(start 0.1778 0.2794)
							(mid 0.249642 0.249642)
							(end 0.2794 0.1778)
						)
						(arc
							(start 0.2794 -0.1778)
							(mid 0.249642 -0.249642)
							(end 0.1778 -0.2794)
						)
					)
					(width 0)
					(fill yes)
				)
			)
		)
	)
	(footprint ""
		(layer "F.Cu")
		(at 65.641474 -179.37226)
		(property "Reference" "R81"
			(at 0 0 0)
			(layer "F.SilkS")
			(hide yes)
			(effects
				(font
					(size 1.27 1.27)
				)
			)
		)
		(property "Value" "4K75R2F-1-GP"
			(at 0.064008 -3.993896 0)
			(unlocked yes)
			(layer "F.Fab")
			(hide yes)
			(effects
				(font
					(size 1.016 1.016)
					(thickness 0.1524)
				)
			)
		)
		(property "Device Type" "R402H16"
			(at 0.064008 -5.517896 0)
			(unlocked yes)
			(layer "F.Fab")
			(hide yes)
			(effects
				(font
					(size 1.016 1.016)
					(thickness 0.1524)
				)
			)
		)
		(duplicate_pad_numbers_are_jumpers no)
		(fp_line
			(start -0.508 -0.9398)
			(end -0.508 0.9398)
			(stroke
				(width 0.1524)
				(type default)
			)
			(layer "F.SilkS")
		)
		(fp_line
			(start 0.508 -0.9398)
			(end -0.508 -0.9398)
			(stroke
				(width 0.1524)
				(type default)
			)
			(layer "F.SilkS")
		)
		(fp_rect
			(start -0.508 0.9398)
			(end 0.508 -0.9398)
			(stroke
				(width 0)
				(type default)
			)
			(fill no)
			(layer "F.CrtYd")
		)
		(fp_rect
			(start -0.508 0.9398)
			(end 0.508 -0.9398)
			(stroke
				(width 0)
				(type default)
			)
			(fill no)
			(layer "F.Fab")
		)
		(pad "1" smd custom
			(at 0 -0.4445)
			(size 0.1397 0.1397)
			(layers "F.Cu" "F.Mask" "F.Paste")
			(net "P3V3_STBY")
			(options
				(clearance outline)
				(anchor circle)
			)
			(primitives
				(gr_poly
					(pts
						(arc
							(start -0.1778 -0.2794)
							(mid -0.249642 -0.249642)
							(end -0.2794 -0.1778)
						)
						(arc
							(start -0.2794 0.1778)
							(mid -0.249642 0.249642)
							(end -0.1778 0.2794)
						)
						(arc
							(start 0.1778 0.2794)
							(mid 0.249642 0.249642)
							(end 0.2794 0.1778)
						)
						(arc
							(start 0.2794 -0.1778)
							(mid 0.249642 -0.249642)
							(end 0.1778 -0.2794)
						)
					)
					(width 0)
					(fill yes)
				)
			)
		)
		(pad "2" smd custom
			(at 0 0.4445)
			(size 0.1397 0.1397)
			(layers "F.Cu" "F.Mask" "F.Paste")
			(net "VREF_2V2")
			(options
				(clearance outline)
				(anchor circle)
			)
			(primitives
				(gr_poly
					(pts
						(arc
							(start -0.1778 -0.2794)
							(mid -0.249642 -0.249642)
							(end -0.2794 -0.1778)
						)
						(arc
							(start -0.2794 0.1778)
							(mid -0.249642 0.249642)
							(end -0.1778 0.2794)
						)
						(arc
							(start 0.1778 0.2794)
							(mid 0.249642 0.249642)
							(end 0.2794 0.1778)
						)
						(arc
							(start 0.2794 -0.1778)
							(mid 0.249642 -0.249642)
							(end 0.1778 -0.2794)
						)
					)
					(width 0)
					(fill yes)
				)
			)
		)
	)
	(footprint ""
		(layer "F.Cu")
		(at 112.84839 -5.577078 -90)
		(property "Reference" "R456"
			(at 0 0 270)
			(layer "F.SilkS")
			(hide yes)
			(effects
				(font
					(size 1.27 1.27)
				)
			)
		)
		(property "Value" "0R2J-2-GP"
			(at 0.064008 -3.993896 270)
			(unlocked yes)
			(layer "F.Fab")
			(hide yes)
			(effects
				(font
					(size 1.016 1.016)
					(thickness 0.1524)
				)
			)
		)
		(property "Device Type" "R402H16"
			(at 0.064008 -5.517896 270)
			(unlocked yes)
			(layer "F.Fab")
			(hide yes)
			(effects
				(font
					(size 1.016 1.016)
					(thickness 0.1524)
				)
			)
		)
		(duplicate_pad_numbers_are_jumpers no)
		(fp_line
			(start -0.508 -0.9398)
			(end -0.508 0.9398)
			(stroke
				(width 0.1524)
				(type default)
			)
			(layer "F.SilkS")
		)
		(fp_line
			(start 0.508 -0.9398)
			(end -0.508 -0.9398)
			(stroke
				(width 0.1524)
				(type default)
			)
			(layer "F.SilkS")
		)
		(fp_rect
			(start -0.508 0.9398)
			(end 0.508 -0.9398)
			(stroke
				(width 0)
				(type default)
			)
			(fill no)
			(layer "F.CrtYd")
		)
		(fp_rect
			(start -0.508 0.9398)
			(end 0.508 -0.9398)
			(stroke
				(width 0)
				(type default)
			)
			(fill no)
			(layer "F.Fab")
		)
		(pad "1" smd custom
			(at 0 -0.4445 270)
			(size 0.1397 0.1397)
			(layers "F.Cu" "F.Mask" "F.Paste")
			(net "MB0_SPISS_PD")
			(options
				(clearance outline)
				(anchor circle)
			)
			(primitives
				(gr_poly
					(pts
						(arc
							(start -0.1778 -0.2794)
							(mid -0.249642 -0.249642)
							(end -0.2794 -0.1778)
						)
						(arc
							(start -0.2794 0.1778)
							(mid -0.249642 0.249642)
							(end -0.1778 0.2794)
						)
						(arc
							(start 0.1778 0.2794)
							(mid 0.249642 0.249642)
							(end 0.2794 0.1778)
						)
						(arc
							(start 0.2794 -0.1778)
							(mid 0.249642 -0.249642)
							(end 0.1778 -0.2794)
						)
					)
					(width 0)
					(fill yes)
				)
			)
		)
		(pad "2" smd custom
			(at 0 0.4445 270)
			(size 0.1397 0.1397)
			(layers "F.Cu" "F.Mask" "F.Paste")
			(net "AGND_CURRENT_MON")
			(options
				(clearance outline)
				(anchor circle)
			)
			(primitives
				(gr_poly
					(pts
						(arc
							(start -0.1778 -0.2794)
							(mid -0.249642 -0.249642)
							(end -0.2794 -0.1778)
						)
						(arc
							(start -0.2794 0.1778)
							(mid -0.249642 0.249642)
							(end -0.1778 0.2794)
						)
						(arc
							(start 0.1778 0.2794)
							(mid 0.249642 0.249642)
							(end 0.2794 0.1778)
						)
						(arc
							(start 0.2794 -0.1778)
							(mid 0.249642 -0.249642)
							(end 0.1778 -0.2794)
						)
					)
					(width 0)
					(fill yes)
				)
			)
		)
	)
	(footprint ""
		(layer "F.Cu")
		(at 82.94116 -157.3276 90)
		(property "Reference" "C238"
			(at 0 0 90)
			(layer "F.SilkS")
			(hide yes)
			(effects
				(font
					(size 1.27 1.27)
				)
			)
		)
		(property "Value" "SC10U6D3V5KX-4GP"
			(at -0.0762 -6.1214 90)
			(unlocked yes)
			(layer "F.Fab")
			(hide yes)
			(effects
				(font
					(size 1.016 1.016)
					(thickness 0.1524)
				)
			)
		)
		(property "Device Type" "C805H58"
			(at -0.0762 -8.1534 90)
			(unlocked yes)
			(layer "F.Fab")
			(hide yes)
			(effects
				(font
					(size 1.016 1.016)
					(thickness 0.1524)
				)
			)
		)
		(duplicate_pad_numbers_are_jumpers no)
		(fp_line
			(start 0.635 0)
			(end -0.635 0)
			(stroke
				(width 0.508)
				(type default)
			)
			(layer "F.SilkS")
		)
		(fp_rect
			(start -0.9652 1.778)
			(end 0.9652 -1.778)
			(stroke
				(width 0)
				(type default)
			)
			(fill no)
			(layer "F.CrtYd")
		)
		(fp_poly
			(pts
				(xy -0.9652 -1.778) (xy 0.9652 -1.778) (xy 0.9652 1.778) (xy -0.9652 1.778)
			)
			(stroke
				(width 0)
				(type default)
			)
			(fill no)
			(layer "F.Fab")
		)
		(pad "1" smd rect
			(at 0 -0.9652 90)
			(size 1.397 1.143)
			(layers "F.Cu" "F.Mask" "F.Paste")
			(net "TPS74801_P1V15_STBY_OUT")
		)
		(pad "2" smd rect
			(at 0 0.9652 90)
			(size 1.397 1.143)
			(layers "F.Cu" "F.Mask" "F.Paste")
			(net "GND")
		)
	)
	(footprint ""
		(layer "F.Cu")
		(at 61.28258 -140.349732 90)
		(property "Reference" "R271"
			(at 0 0 90)
			(layer "F.SilkS")
			(hide yes)
			(effects
				(font
					(size 1.27 1.27)
				)
			)
		)
		(property "Value" "4K7R2F-GP"
			(at 0.064008 -3.993896 90)
			(unlocked yes)
			(layer "F.Fab")
			(hide yes)
			(effects
				(font
					(size 1.016 1.016)
					(thickness 0.1524)
				)
			)
		)
		(property "Device Type" "R402H16"
			(at 0.064008 -5.517896 90)
			(unlocked yes)
			(layer "F.Fab")
			(hide yes)
			(effects
				(font
					(size 1.016 1.016)
					(thickness 0.1524)
				)
			)
		)
		(duplicate_pad_numbers_are_jumpers no)
		(fp_line
			(start 0.508 -0.9398)
			(end -0.508 -0.9398)
			(stroke
				(width 0.1524)
				(type default)
			)
			(layer "F.SilkS")
		)
		(fp_line
			(start -0.508 -0.9398)
			(end -0.508 0.9398)
			(stroke
				(width 0.1524)
				(type default)
			)
			(layer "F.SilkS")
		)
		(fp_rect
			(start -0.508 0.9398)
			(end 0.508 -0.9398)
			(stroke
				(width 0)
				(type default)
			)
			(fill no)
			(layer "F.CrtYd")
		)
		(fp_rect
			(start -0.508 0.9398)
			(end 0.508 -0.9398)
			(stroke
				(width 0)
				(type default)
			)
			(fill no)
			(layer "F.Fab")
		)
		(pad "1" smd custom
			(at 0 -0.4445 90)
			(size 0.1397 0.1397)
			(layers "F.Cu" "F.Mask" "F.Paste")
			(net "BMC_TO_EXP_RESET_OUT")
			(options
				(clearance outline)
				(anchor circle)
			)
			(primitives
				(gr_poly
					(pts
						(arc
							(start -0.1778 -0.2794)
							(mid -0.249642 -0.249642)
							(end -0.2794 -0.1778)
						)
						(arc
							(start -0.2794 0.1778)
							(mid -0.249642 0.249642)
							(end -0.1778 0.2794)
						)
						(arc
							(start 0.1778 0.2794)
							(mid 0.249642 0.249642)
							(end 0.2794 0.1778)
						)
						(arc
							(start 0.2794 -0.1778)
							(mid 0.249642 -0.249642)
							(end 0.1778 -0.2794)
						)
					)
					(width 0)
					(fill yes)
				)
			)
		)
		(pad "2" smd custom
			(at 0 0.4445 90)
			(size 0.1397 0.1397)
			(layers "F.Cu" "F.Mask" "F.Paste")
			(net "P3V3_STBY")
			(options
				(clearance outline)
				(anchor circle)
			)
			(primitives
				(gr_poly
					(pts
						(arc
							(start -0.1778 -0.2794)
							(mid -0.249642 -0.249642)
							(end -0.2794 -0.1778)
						)
						(arc
							(start -0.2794 0.1778)
							(mid -0.249642 0.249642)
							(end -0.1778 0.2794)
						)
						(arc
							(start 0.1778 0.2794)
							(mid 0.249642 0.249642)
							(end 0.2794 0.1778)
						)
						(arc
							(start 0.2794 -0.1778)
							(mid 0.249642 -0.249642)
							(end 0.1778 -0.2794)
						)
					)
					(width 0)
					(fill yes)
				)
			)
		)
	)
	(footprint ""
		(layer "F.Cu")
		(at 40.894 -164.084)
		(property "Reference" "R301"
			(at 0 0 0)
			(layer "F.SilkS")
			(hide yes)
			(effects
				(font
					(size 1.27 1.27)
				)
			)
		)
		(property "Value" "0R2J-2-GP"
			(at 0.064008 -3.993896 0)
			(unlocked yes)
			(layer "F.Fab")
			(hide yes)
			(effects
				(font
					(size 1.016 1.016)
					(thickness 0.1524)
				)
			)
		)
		(property "Device Type" "R402H16"
			(at 0.064008 -5.517896 0)
			(unlocked yes)
			(layer "F.Fab")
			(hide yes)
			(effects
				(font
					(size 1.016 1.016)
					(thickness 0.1524)
				)
			)
		)
		(duplicate_pad_numbers_are_jumpers no)
		(fp_line
			(start -0.508 -0.9398)
			(end -0.508 0.9398)
			(stroke
				(width 0.1524)
				(type default)
			)
			(layer "F.SilkS")
		)
		(fp_line
			(start 0.508 -0.9398)
			(end -0.508 -0.9398)
			(stroke
				(width 0.1524)
				(type default)
			)
			(layer "F.SilkS")
		)
		(fp_rect
			(start -0.508 0.9398)
			(end 0.508 -0.9398)
			(stroke
				(width 0)
				(type default)
			)
			(fill no)
			(layer "F.CrtYd")
		)
		(fp_rect
			(start -0.508 0.9398)
			(end 0.508 -0.9398)
			(stroke
				(width 0)
				(type default)
			)
			(fill no)
			(layer "F.Fab")
		)
		(pad "1" smd custom
			(at 0 -0.4445)
			(size 0.1397 0.1397)
			(layers "F.Cu" "F.Mask" "F.Paste")
			(net "UART_EXP_BMC_RX")
			(options
				(clearance outline)
				(anchor circle)
			)
			(primitives
				(gr_poly
					(pts
						(arc
							(start -0.1778 -0.2794)
							(mid -0.249642 -0.249642)
							(end -0.2794 -0.1778)
						)
						(arc
							(start -0.2794 0.1778)
							(mid -0.249642 0.249642)
							(end -0.1778 0.2794)
						)
						(arc
							(start 0.1778 0.2794)
							(mid 0.249642 0.249642)
							(end 0.2794 0.1778)
						)
						(arc
							(start 0.2794 -0.1778)
							(mid 0.249642 -0.249642)
							(end 0.1778 -0.2794)
						)
					)
					(width 0)
					(fill yes)
				)
			)
		)
		(pad "2" smd custom
			(at 0 0.4445)
			(size 0.1397 0.1397)
			(layers "F.Cu" "F.Mask" "F.Paste")
			(net "UART_EXP_BMC_RX_R")
			(options
				(clearance outline)
				(anchor circle)
			)
			(primitives
				(gr_poly
					(pts
						(arc
							(start -0.1778 -0.2794)
							(mid -0.249642 -0.249642)
							(end -0.2794 -0.1778)
						)
						(arc
							(start -0.2794 0.1778)
							(mid -0.249642 0.249642)
							(end -0.1778 0.2794)
						)
						(arc
							(start 0.1778 0.2794)
							(mid 0.249642 0.249642)
							(end 0.2794 0.1778)
						)
						(arc
							(start 0.2794 -0.1778)
							(mid 0.249642 -0.249642)
							(end 0.1778 -0.2794)
						)
					)
					(width 0)
					(fill yes)
				)
			)
		)
	)
	(footprint ""
		(layer "F.Cu")
		(at 135.62076 -17.88414 180)
		(property "Reference" "C139"
			(at 0 0 180)
			(layer "F.SilkS")
			(hide yes)
			(effects
				(font
					(size 1.27 1.27)
				)
			)
		)
		(property "Value" "SCD1U50V3KX-GP"
			(at 0 -2.8194 180)
			(unlocked yes)
			(layer "F.Fab")
			(hide yes)
			(effects
				(font
					(size 1.016 1.016)
					(thickness 0.1524)
				)
			)
		)
		(property "Device Type" "C603H36"
			(at 0 -4.3434 180)
			(unlocked yes)
			(layer "F.Fab")
			(hide yes)
			(effects
				(font
					(size 1.016 1.016)
					(thickness 0.1524)
				)
			)
		)
		(duplicate_pad_numbers_are_jumpers no)
		(fp_line
			(start 0.508 0)
			(end -0.508 0)
			(stroke
				(width 0.2032)
				(type default)
			)
			(layer "F.SilkS")
		)
		(fp_rect
			(start -0.5842 1.3335)
			(end 0.5842 -1.3335)
			(stroke
				(width 0)
				(type default)
			)
			(fill no)
			(layer "F.CrtYd")
		)
		(fp_rect
			(start -0.5842 1.3335)
			(end 0.5842 -1.3335)
			(stroke
				(width 0)
				(type default)
			)
			(fill no)
			(layer "F.Fab")
		)
		(pad "1" smd custom
			(at 0 -0.762 180)
			(size 0.2159 0.2159)
			(layers "F.Cu" "F.Mask" "F.Paste")
			(net "P12V_IOM")
			(options
				(clearance outline)
				(anchor circle)
			)
			(primitives
				(gr_poly
					(pts
						(arc
							(start -0.3302 -0.4318)
							(mid -0.402042 -0.402042)
							(end -0.4318 -0.3302)
						)
						(arc
							(start -0.4318 0.3302)
							(mid -0.402042 0.402042)
							(end -0.3302 0.4318)
						)
						(arc
							(start 0.3302 0.4318)
							(mid 0.402042 0.402042)
							(end 0.4318 0.3302)
						)
						(arc
							(start 0.4318 -0.3302)
							(mid 0.402042 -0.402042)
							(end 0.3302 -0.4318)
						)
					)
					(width 0)
					(fill yes)
				)
			)
		)
		(pad "2" smd custom
			(at 0 0.762 180)
			(size 0.2159 0.2159)
			(layers "F.Cu" "F.Mask" "F.Paste")
			(net "GND")
			(options
				(clearance outline)
				(anchor circle)
			)
			(primitives
				(gr_poly
					(pts
						(arc
							(start -0.3302 -0.4318)
							(mid -0.402042 -0.402042)
							(end -0.4318 -0.3302)
						)
						(arc
							(start -0.4318 0.3302)
							(mid -0.402042 0.402042)
							(end -0.3302 0.4318)
						)
						(arc
							(start 0.3302 0.4318)
							(mid 0.402042 0.402042)
							(end 0.4318 0.3302)
						)
						(arc
							(start 0.4318 -0.3302)
							(mid 0.402042 -0.402042)
							(end 0.3302 -0.4318)
						)
					)
					(width 0)
					(fill yes)
				)
			)
		)
	)
	(footprint ""
		(layer "F.Cu")
		(at 23.78456 -14.69644)
		(property "Reference" "D2"
			(at 0 0 0)
			(layer "F.SilkS")
			(hide yes)
			(effects
				(font
					(size 1.27 1.27)
				)
			)
		)
		(property "Value" "PESD5V0X1UAB-GP"
			(at 0 -4.690618 0)
			(unlocked yes)
			(layer "F.Fab")
			(hide yes)
			(effects
				(font
					(size 1.016 1.016)
					(thickness 0.1524)
				)
			)
		)
		(property "Device Type" "SOD523AKH26"
			(at 0 -6.214618 0)
			(unlocked yes)
			(layer "F.Fab")
			(hide yes)
			(effects
				(font
					(size 1.016 1.016)
					(thickness 0.1524)
				)
			)
		)
		(duplicate_pad_numbers_are_jumpers no)
		(fp_line
			(start -0.5334 -1.4478)
			(end 0.5334 -1.4478)
			(stroke
				(width 0.1524)
				(type default)
			)
			(layer "F.SilkS")
		)
		(fp_line
			(start -0.5334 1.524)
			(end -0.5334 -1.4478)
			(stroke
				(width 0.1524)
				(type default)
			)
			(layer "F.SilkS")
		)
		(fp_line
			(start 0.4064 1.651)
			(end -0.4064 1.651)
			(stroke
				(width 0.4064)
				(type default)
			)
			(layer "F.SilkS")
		)
		(fp_line
			(start 0.5334 -1.4478)
			(end 0.5334 1.524)
			(stroke
				(width 0.1524)
				(type default)
			)
			(layer "F.SilkS")
		)
		(fp_line
			(start 0.5334 1.524)
			(end -0.5334 1.524)
			(stroke
				(width 0.1524)
				(type default)
			)
			(layer "F.SilkS")
		)
		(fp_rect
			(start -0.6096 1.8542)
			(end 0.6096 -1.524)
			(stroke
				(width 0)
				(type default)
			)
			(fill no)
			(layer "F.CrtYd")
		)
		(fp_poly
			(pts
				(xy -0.6096 -1.524) (xy 0.6096 -1.524) (xy 0.6096 1.8542) (xy -0.6096 1.8542)
			)
			(stroke
				(width 0)
				(type default)
			)
			(fill no)
			(layer "F.Fab")
		)
		(pad "A" smd rect
			(at 0 -0.762)
			(size 0.5588 1.016)
			(layers "F.Cu" "F.Mask" "F.Paste")
			(net "GND")
		)
		(pad "K" smd rect
			(at 0 0.762)
			(size 0.5588 1.016)
			(layers "F.Cu" "F.Mask" "F.Paste")
			(net "FP_PWR_BTN_N")
		)
	)
	(footprint ""
		(layer "F.Cu")
		(at 73.4187 -136.398 180)
		(property "Reference" "R102"
			(at 0 0 180)
			(layer "F.SilkS")
			(hide yes)
			(effects
				(font
					(size 1.27 1.27)
				)
			)
		)
		(property "Value" "0R2J-2-GP"
			(at 0.064008 -3.993896 180)
			(unlocked yes)
			(layer "F.Fab")
			(hide yes)
			(effects
				(font
					(size 1.016 1.016)
					(thickness 0.1524)
				)
			)
		)
		(property "Device Type" "R402H16"
			(at 0.064008 -5.517896 180)
			(unlocked yes)
			(layer "F.Fab")
			(hide yes)
			(effects
				(font
					(size 1.016 1.016)
					(thickness 0.1524)
				)
			)
		)
		(duplicate_pad_numbers_are_jumpers no)
		(fp_line
			(start 0.508 -0.9398)
			(end -0.508 -0.9398)
			(stroke
				(width 0.1524)
				(type default)
			)
			(layer "F.SilkS")
		)
		(fp_line
			(start -0.508 -0.9398)
			(end -0.508 0.9398)
			(stroke
				(width 0.1524)
				(type default)
			)
			(layer "F.SilkS")
		)
		(fp_rect
			(start -0.508 0.9398)
			(end 0.508 -0.9398)
			(stroke
				(width 0)
				(type default)
			)
			(fill no)
			(layer "F.CrtYd")
		)
		(fp_rect
			(start -0.508 0.9398)
			(end 0.508 -0.9398)
			(stroke
				(width 0)
				(type default)
			)
			(fill no)
			(layer "F.Fab")
		)
		(pad "1" smd custom
			(at 0 -0.4445 180)
			(size 0.1397 0.1397)
			(layers "F.Cu" "F.Mask" "F.Paste")
			(net "BMC_UART_SEL_IN")
			(options
				(clearance outline)
				(anchor circle)
			)
			(primitives
				(gr_poly
					(pts
						(arc
							(start -0.1778 -0.2794)
							(mid -0.249642 -0.249642)
							(end -0.2794 -0.1778)
						)
						(arc
							(start -0.2794 0.1778)
							(mid -0.249642 0.249642)
							(end -0.1778 0.2794)
						)
						(arc
							(start 0.1778 0.2794)
							(mid 0.249642 0.249642)
							(end 0.2794 0.1778)
						)
						(arc
							(start 0.2794 -0.1778)
							(mid 0.249642 -0.249642)
							(end 0.1778 -0.2794)
						)
					)
					(width 0)
					(fill yes)
				)
			)
		)
		(pad "2" smd custom
			(at 0 0.4445 180)
			(size 0.1397 0.1397)
			(layers "F.Cu" "F.Mask" "F.Paste")
			(net "DEBUG_HDR_UART_SEL")
			(options
				(clearance outline)
				(anchor circle)
			)
			(primitives
				(gr_poly
					(pts
						(arc
							(start -0.1778 -0.2794)
							(mid -0.249642 -0.249642)
							(end -0.2794 -0.1778)
						)
						(arc
							(start -0.2794 0.1778)
							(mid -0.249642 0.249642)
							(end -0.1778 0.2794)
						)
						(arc
							(start 0.1778 0.2794)
							(mid 0.249642 0.249642)
							(end 0.2794 0.1778)
						)
						(arc
							(start 0.2794 -0.1778)
							(mid 0.249642 -0.249642)
							(end 0.1778 -0.2794)
						)
					)
					(width 0)
					(fill yes)
				)
			)
		)
	)
	(footprint ""
		(layer "F.Cu")
		(at 31.4706 -165.0238)
		(property "Reference" "R703"
			(at 0 0 0)
			(layer "F.SilkS")
			(hide yes)
			(effects
				(font
					(size 1.27 1.27)
				)
			)
		)
		(property "Value" "4K7R2F-GP"
			(at 0.064008 -3.993896 0)
			(unlocked yes)
			(layer "F.Fab")
			(hide yes)
			(effects
				(font
					(size 1.016 1.016)
					(thickness 0.1524)
				)
			)
		)
		(property "Device Type" "R402H16"
			(at 0.064008 -5.517896 0)
			(unlocked yes)
			(layer "F.Fab")
			(hide yes)
			(effects
				(font
					(size 1.016 1.016)
					(thickness 0.1524)
				)
			)
		)
		(duplicate_pad_numbers_are_jumpers no)
		(fp_line
			(start -0.508 -0.9398)
			(end -0.508 0.9398)
			(stroke
				(width 0.1524)
				(type default)
			)
			(layer "F.SilkS")
		)
		(fp_line
			(start 0.508 -0.9398)
			(end -0.508 -0.9398)
			(stroke
				(width 0.1524)
				(type default)
			)
			(layer "F.SilkS")
		)
		(fp_rect
			(start -0.508 0.9398)
			(end 0.508 -0.9398)
			(stroke
				(width 0)
				(type default)
			)
			(fill no)
			(layer "F.CrtYd")
		)
		(fp_rect
			(start -0.508 0.9398)
			(end 0.508 -0.9398)
			(stroke
				(width 0)
				(type default)
			)
			(fill no)
			(layer "F.Fab")
		)
		(pad "1" smd custom
			(at 0 -0.4445)
			(size 0.1397 0.1397)
			(layers "F.Cu" "F.Mask" "F.Paste")
			(net "GND")
			(options
				(clearance outline)
				(anchor circle)
			)
			(primitives
				(gr_poly
					(pts
						(arc
							(start -0.1778 -0.2794)
							(mid -0.249642 -0.249642)
							(end -0.2794 -0.1778)
						)
						(arc
							(start -0.2794 0.1778)
							(mid -0.249642 0.249642)
							(end -0.1778 0.2794)
						)
						(arc
							(start 0.1778 0.2794)
							(mid 0.249642 0.249642)
							(end 0.2794 0.1778)
						)
						(arc
							(start 0.2794 -0.1778)
							(mid 0.249642 -0.249642)
							(end 0.1778 -0.2794)
						)
					)
					(width 0)
					(fill yes)
				)
			)
		)
		(pad "2" smd custom
			(at 0 0.4445)
			(size 0.1397 0.1397)
			(layers "F.Cu" "F.Mask" "F.Paste")
			(net "IOM_TYPE1")
			(options
				(clearance outline)
				(anchor circle)
			)
			(primitives
				(gr_poly
					(pts
						(arc
							(start -0.1778 -0.2794)
							(mid -0.249642 -0.249642)
							(end -0.2794 -0.1778)
						)
						(arc
							(start -0.2794 0.1778)
							(mid -0.249642 0.249642)
							(end -0.1778 0.2794)
						)
						(arc
							(start 0.1778 0.2794)
							(mid 0.249642 0.249642)
							(end 0.2794 0.1778)
						)
						(arc
							(start 0.2794 -0.1778)
							(mid 0.249642 -0.249642)
							(end 0.1778 -0.2794)
						)
					)
					(width 0)
					(fill yes)
				)
			)
		)
	)
	(footprint ""
		(layer "F.Cu")
		(at 57.3024 -131.33832)
		(property "Reference" "R278"
			(at 0 0 0)
			(layer "F.SilkS")
			(hide yes)
			(effects
				(font
					(size 1.27 1.27)
				)
			)
		)
		(property "Value" "0R2J-2-GP"
			(at 0.064008 -3.993896 0)
			(unlocked yes)
			(layer "F.Fab")
			(hide yes)
			(effects
				(font
					(size 1.016 1.016)
					(thickness 0.1524)
				)
			)
		)
		(property "Device Type" "R402H16"
			(at 0.064008 -5.517896 0)
			(unlocked yes)
			(layer "F.Fab")
			(hide yes)
			(effects
				(font
					(size 1.016 1.016)
					(thickness 0.1524)
				)
			)
		)
		(duplicate_pad_numbers_are_jumpers no)
		(fp_line
			(start -0.508 -0.9398)
			(end -0.508 0.9398)
			(stroke
				(width 0.1524)
				(type default)
			)
			(layer "F.SilkS")
		)
		(fp_line
			(start 0.508 -0.9398)
			(end -0.508 -0.9398)
			(stroke
				(width 0.1524)
				(type default)
			)
			(layer "F.SilkS")
		)
		(fp_rect
			(start -0.508 0.9398)
			(end 0.508 -0.9398)
			(stroke
				(width 0)
				(type default)
			)
			(fill no)
			(layer "F.CrtYd")
		)
		(fp_rect
			(start -0.508 0.9398)
			(end 0.508 -0.9398)
			(stroke
				(width 0)
				(type default)
			)
			(fill no)
			(layer "F.Fab")
		)
		(pad "1" smd custom
			(at 0 -0.4445)
			(size 0.1397 0.1397)
			(layers "F.Cu" "F.Mask" "F.Paste")
			(net "RSTBTN_OUT_N_R")
			(options
				(clearance outline)
				(anchor circle)
			)
			(primitives
				(gr_poly
					(pts
						(arc
							(start -0.1778 -0.2794)
							(mid -0.249642 -0.249642)
							(end -0.2794 -0.1778)
						)
						(arc
							(start -0.2794 0.1778)
							(mid -0.249642 0.249642)
							(end -0.1778 0.2794)
						)
						(arc
							(start 0.1778 0.2794)
							(mid 0.249642 0.249642)
							(end 0.2794 0.1778)
						)
						(arc
							(start 0.2794 -0.1778)
							(mid 0.249642 -0.249642)
							(end 0.1778 -0.2794)
						)
					)
					(width 0)
					(fill yes)
				)
			)
		)
		(pad "2" smd custom
			(at 0 0.4445)
			(size 0.1397 0.1397)
			(layers "F.Cu" "F.Mask" "F.Paste")
			(net "RSTBTN_OUT_N")
			(options
				(clearance outline)
				(anchor circle)
			)
			(primitives
				(gr_poly
					(pts
						(arc
							(start -0.1778 -0.2794)
							(mid -0.249642 -0.249642)
							(end -0.2794 -0.1778)
						)
						(arc
							(start -0.2794 0.1778)
							(mid -0.249642 0.249642)
							(end -0.1778 0.2794)
						)
						(arc
							(start 0.1778 0.2794)
							(mid 0.249642 0.249642)
							(end 0.2794 0.1778)
						)
						(arc
							(start 0.2794 -0.1778)
							(mid 0.249642 -0.249642)
							(end 0.1778 -0.2794)
						)
					)
					(width 0)
					(fill yes)
				)
			)
		)
	)
	(footprint ""
		(layer "F.Cu")
		(at 31.5976 -161.6456 90)
		(property "Reference" "R700"
			(at 0 0 90)
			(layer "F.SilkS")
			(hide yes)
			(effects
				(font
					(size 1.27 1.27)
				)
			)
		)
		(property "Value" "4K7R2F-GP"
			(at 0.064008 -3.993896 90)
			(unlocked yes)
			(layer "F.Fab")
			(hide yes)
			(effects
				(font
					(size 1.016 1.016)
					(thickness 0.1524)
				)
			)
		)
		(property "Device Type" "R402H16"
			(at 0.064008 -5.517896 90)
			(unlocked yes)
			(layer "F.Fab")
			(hide yes)
			(effects
				(font
					(size 1.016 1.016)
					(thickness 0.1524)
				)
			)
		)
		(duplicate_pad_numbers_are_jumpers no)
		(fp_line
			(start 0.508 -0.9398)
			(end -0.508 -0.9398)
			(stroke
				(width 0.1524)
				(type default)
			)
			(layer "F.SilkS")
		)
		(fp_line
			(start -0.508 -0.9398)
			(end -0.508 0.9398)
			(stroke
				(width 0.1524)
				(type default)
			)
			(layer "F.SilkS")
		)
		(fp_rect
			(start -0.508 0.9398)
			(end 0.508 -0.9398)
			(stroke
				(width 0)
				(type default)
			)
			(fill no)
			(layer "F.CrtYd")
		)
		(fp_rect
			(start -0.508 0.9398)
			(end 0.508 -0.9398)
			(stroke
				(width 0)
				(type default)
			)
			(fill no)
			(layer "F.Fab")
		)
		(pad "1" smd custom
			(at 0 -0.4445 90)
			(size 0.1397 0.1397)
			(layers "F.Cu" "F.Mask" "F.Paste")
			(net "P3V3_STBY")
			(options
				(clearance outline)
				(anchor circle)
			)
			(primitives
				(gr_poly
					(pts
						(arc
							(start -0.1778 -0.2794)
							(mid -0.249642 -0.249642)
							(end -0.2794 -0.1778)
						)
						(arc
							(start -0.2794 0.1778)
							(mid -0.249642 0.249642)
							(end -0.1778 0.2794)
						)
						(arc
							(start 0.1778 0.2794)
							(mid 0.249642 0.249642)
							(end 0.2794 0.1778)
						)
						(arc
							(start 0.2794 -0.1778)
							(mid 0.249642 -0.249642)
							(end 0.1778 -0.2794)
						)
					)
					(width 0)
					(fill yes)
				)
			)
		)
		(pad "2" smd custom
			(at 0 0.4445 90)
			(size 0.1397 0.1397)
			(layers "F.Cu" "F.Mask" "F.Paste")
			(net "IOM_TYPE3")
			(options
				(clearance outline)
				(anchor circle)
			)
			(primitives
				(gr_poly
					(pts
						(arc
							(start -0.1778 -0.2794)
							(mid -0.249642 -0.249642)
							(end -0.2794 -0.1778)
						)
						(arc
							(start -0.2794 0.1778)
							(mid -0.249642 0.249642)
							(end -0.1778 0.2794)
						)
						(arc
							(start 0.1778 0.2794)
							(mid 0.249642 0.249642)
							(end 0.2794 0.1778)
						)
						(arc
							(start 0.2794 -0.1778)
							(mid 0.249642 -0.249642)
							(end 0.1778 -0.2794)
						)
					)
					(width 0)
					(fill yes)
				)
			)
		)
	)
	(footprint ""
		(layer "F.Cu")
		(at 77.700124 -72.55002 -90)
		(property "Reference" "MEZZ1"
			(at 0 0 270)
			(layer "F.SilkS")
			(hide yes)
			(effects
				(font
					(size 1.27 1.27)
				)
			)
		)
		(property "Value" "FCI-CONN120-GP-U1"
			(at -28.2321 -1.7018 270)
			(unlocked yes)
			(layer "F.Fab")
			(hide yes)
			(effects
				(font
					(size 1.016 1.016)
					(thickness 0.1524)
				)
			)
		)
		(property "Device Type" "61082-121402LF-U1"
			(at -28.2321 -3.2258 270)
			(unlocked yes)
			(layer "F.Fab")
			(hide yes)
			(effects
				(font
					(size 1.016 1.016)
					(thickness 0.1524)
				)
			)
		)
		(duplicate_pad_numbers_are_jumpers no)
		(fp_line
			(start -27.1526 3.5052)
			(end 27.1526 3.5052)
			(stroke
				(width 0.1524)
				(type default)
			)
			(layer "F.SilkS")
		)
		(fp_line
			(start 27.1526 3.5052)
			(end 27.1526 -3.5052)
			(stroke
				(width 0.1524)
				(type default)
			)
			(layer "F.SilkS")
		)
		(fp_line
			(start -27.1526 -3.5052)
			(end -27.1526 3.5052)
			(stroke
				(width 0.1524)
				(type default)
			)
			(layer "F.SilkS")
		)
		(fp_line
			(start 27.1526 -3.5052)
			(end -27.1526 -3.5052)
			(stroke
				(width 0.1524)
				(type default)
			)
			(layer "F.SilkS")
		)
		(fp_line
			(start 23.34895 -3.5941)
			(end 23.85695 -3.5941)
			(stroke
				(width 0.3302)
				(type default)
			)
			(layer "F.SilkS")
		)
		(fp_poly
			(pts
				(xy 23.597108 -3.578098) (xy 24.105108 -4.086098) (xy 23.089108 -4.086098)
			)
			(stroke
				(width 0)
				(type default)
			)
			(fill yes)
			(layer "F.SilkS")
		)
		(fp_poly
			(pts
				(xy -23.853902 0.99314) (xy 23.853902 0.99314) (xy 23.853902 -0.99314) (xy -23.853902 -0.99314)
			)
			(stroke
				(width 0)
				(type default)
			)
			(fill yes)
			(layer "F.SilkS")
		)
		(fp_rect
			(start -26.8986 2.9972)
			(end 26.8986 -2.9972)
			(stroke
				(width 0)
				(type default)
			)
			(fill no)
			(layer "F.CrtYd")
		)
		(fp_poly
			(pts
				(xy 27.4066 -2.9972) (xy -26.8986 -2.9972) (xy -26.8986 2.9972) (xy 26.8986 2.9972) (xy 26.8986 -2.9845)
				(xy 27.4066 -2.9845) (xy 27.4066 3.7592) (xy -27.4066 3.7592) (xy -27.4066 -3.7592) (xy 27.4066 -3.7592)
			)
			(stroke
				(width 0)
				(type default)
			)
			(fill no)
			(layer "F.CrtYd")
		)
		(fp_rect
			(start -27.4066 3.7592)
			(end 27.4066 -3.7592)
			(stroke
				(width 0)
				(type default)
			)
			(fill no)
			(layer "F.Fab")
		)
		(pad "" np_thru_hole circle
			(at -26.100024 0 270)
			(size 0.254 0.254)
			(drill 0.8636)
			(layers "*.Cu" "*.Mask")
			(clearance 0.6604)
			(thermal_gap 0.6604)
		)
		(pad "" np_thru_hole circle
			(at 26.100024 0 270)
			(size 0.254 0.254)
			(drill 1.2192)
			(layers "*.Cu" "*.Mask")
			(clearance 0.8382)
			(thermal_gap 0.8382)
		)
		(pad "1" smd rect
			(at 23.599902 -2.22504 270)
			(size 0.508 2.0574)
			(layers "F.Cu" "F.Mask" "F.Paste")
			(net "MEZZA_PRSNT1_N")
		)
		(pad "2" smd rect
			(at 22.800056 -2.22504 270)
			(size 0.508 2.0574)
			(layers "F.Cu" "F.Mask" "F.Paste")
			(net "P5V_STBY")
		)
		(pad "3" smd rect
			(at 21.999956 -2.22504 270)
			(size 0.508 2.0574)
			(layers "F.Cu" "F.Mask" "F.Paste")
			(net "P5V_STBY")
		)
		(pad "4" smd rect
			(at 21.20011 -2.22504 270)
			(size 0.508 2.0574)
			(layers "F.Cu" "F.Mask" "F.Paste")
			(net "P5V_STBY")
		)
		(pad "5" smd rect
			(at 20.40001 -2.22504 270)
			(size 0.508 2.0574)
			(layers "F.Cu" "F.Mask" "F.Paste")
			(net "GND")
		)
		(pad "6" smd rect
			(at 19.59991 -2.22504 270)
			(size 0.508 2.0574)
			(layers "F.Cu" "F.Mask" "F.Paste")
			(net "GND")
		)
		(pad "7" smd rect
			(at 18.800064 -2.22504 270)
			(size 0.508 2.0574)
			(layers "F.Cu" "F.Mask" "F.Paste")
			(net "P3V3_STBY")
		)
		(pad "8" smd rect
			(at 17.999964 -2.22504 270)
			(size 0.508 2.0574)
			(layers "F.Cu" "F.Mask" "F.Paste")
			(net "GND")
		)
		(pad "9" smd rect
			(at 17.200118 -2.22504 270)
			(size 0.508 2.0574)
			(layers "F.Cu" "F.Mask" "F.Paste")
			(net "GND")
		)
		(pad "10" smd rect
			(at 16.400018 -2.22504 270)
			(size 0.508 2.0574)
			(layers "F.Cu" "F.Mask" "F.Paste")
			(net "P3V3")
		)
		(pad "11" smd rect
			(at 15.599918 -2.22504 270)
			(size 0.508 2.0574)
			(layers "F.Cu" "F.Mask" "F.Paste")
			(net "P3V3")
		)
		(pad "12" smd rect
			(at 14.800072 -2.22504 270)
			(size 0.508 2.0574)
			(layers "F.Cu" "F.Mask" "F.Paste")
			(net "P3V3")
		)
		(pad "13" smd rect
			(at 13.999972 -2.22504 270)
			(size 0.508 2.0574)
			(layers "F.Cu" "F.Mask" "F.Paste")
			(net "P3V3")
		)
		(pad "14" smd rect
			(at 13.200126 -2.22504 270)
			(size 0.508 2.0574)
			(layers "F.Cu" "F.Mask" "F.Paste")
			(net "NCSI_RCSDV_R")
		)
		(pad "15" smd rect
			(at 12.400026 -2.22504 270)
			(size 0.508 2.0574)
			(layers "F.Cu" "F.Mask" "F.Paste")
			(net "NCSI_RCLK")
		)
		(pad "16" smd rect
			(at 11.599926 -2.22504 270)
			(size 0.508 2.0574)
			(layers "F.Cu" "F.Mask" "F.Paste")
			(net "NCSI_TXEN_R")
		)
		(pad "17" smd rect
			(at 10.80008 -2.22504 270)
			(size 0.508 2.0574)
			(layers "F.Cu" "F.Mask" "F.Paste")
			(net "PCIE_COMP_TO_IOM_RST_4_R")
		)
		(pad "18" smd rect
			(at 9.99998 -2.22504 270)
			(size 0.508 2.0574)
			(layers "F.Cu" "F.Mask" "F.Paste")
			(net "I2C_MEZZ_OOB_SCL")
		)
		(pad "19" smd rect
			(at 9.19988 -2.22504 270)
			(size 0.508 2.0574)
			(layers "F.Cu" "F.Mask" "F.Paste")
			(net "I2C_MEZZ_OOB_SDA")
		)
		(pad "20" smd rect
			(at 8.400034 -2.22504 270)
			(size 0.508 2.0574)
			(layers "F.Cu" "F.Mask" "F.Paste")
			(net "GND")
		)
		(pad "21" smd rect
			(at 7.599934 -2.22504 270)
			(size 0.508 2.0574)
			(layers "F.Cu" "F.Mask" "F.Paste")
			(net "GND")
		)
		(pad "22" smd rect
			(at 6.800088 -2.22504 270)
			(size 0.508 2.0574)
			(layers "F.Cu" "F.Mask" "F.Paste")
			(net "NCSI_RXD0_R")
		)
		(pad "23" smd rect
			(at 5.999988 -2.22504 270)
			(size 0.508 2.0574)
			(layers "F.Cu" "F.Mask" "F.Paste")
			(net "NCSI_RXD1_R")
		)
		(pad "24" smd rect
			(at 5.199888 -2.22504 270)
			(size 0.508 2.0574)
			(layers "F.Cu" "F.Mask" "F.Paste")
			(net "GND")
		)
		(pad "25" smd rect
			(at 4.400042 -2.22504 270)
			(size 0.508 2.0574)
			(layers "F.Cu" "F.Mask" "F.Paste")
			(net "GND")
		)
		(pad "26" smd rect
			(at 3.599942 -2.22504 270)
			(size 0.508 2.0574)
			(layers "F.Cu" "F.Mask" "F.Paste")
			(net "Net_17")
		)
		(pad "27" smd rect
			(at 2.800096 -2.22504 270)
			(size 0.508 2.0574)
			(layers "F.Cu" "F.Mask" "F.Paste")
			(net "Net_16")
		)
		(pad "28" smd rect
			(at 1.999996 -2.22504 270)
			(size 0.508 2.0574)
			(layers "F.Cu" "F.Mask" "F.Paste")
			(net "GND")
		)
		(pad "29" smd rect
			(at 1.199896 -2.22504 270)
			(size 0.508 2.0574)
			(layers "F.Cu" "F.Mask" "F.Paste")
			(net "GND")
		)
		(pad "30" smd rect
			(at 0.40005 -2.22504 270)
			(size 0.508 2.0574)
			(layers "F.Cu" "F.Mask" "F.Paste")
			(net "PCIE_IOM_TO_COMP_16_DP")
		)
		(pad "31" smd rect
			(at -0.40005 -2.22504 270)
			(size 0.508 2.0574)
			(layers "F.Cu" "F.Mask" "F.Paste")
			(net "PCIE_IOM_TO_COMP_16_DN")
		)
		(pad "32" smd rect
			(at -1.199896 -2.22504 270)
			(size 0.508 2.0574)
			(layers "F.Cu" "F.Mask" "F.Paste")
			(net "GND")
		)
		(pad "33" smd rect
			(at -1.999996 -2.22504 270)
			(size 0.508 2.0574)
			(layers "F.Cu" "F.Mask" "F.Paste")
			(net "GND")
		)
		(pad "34" smd rect
			(at -2.800096 -2.22504 270)
			(size 0.508 2.0574)
			(layers "F.Cu" "F.Mask" "F.Paste")
			(net "PCIE_IOM_TO_COMP_17_DP")
		)
		(pad "35" smd rect
			(at -3.599942 -2.22504 270)
			(size 0.508 2.0574)
			(layers "F.Cu" "F.Mask" "F.Paste")
			(net "PCIE_IOM_TO_COMP_17_DN")
		)
		(pad "36" smd rect
			(at -4.400042 -2.22504 270)
			(size 0.508 2.0574)
			(layers "F.Cu" "F.Mask" "F.Paste")
			(net "GND")
		)
		(pad "37" smd rect
			(at -5.199888 -2.22504 270)
			(size 0.508 2.0574)
			(layers "F.Cu" "F.Mask" "F.Paste")
			(net "GND")
		)
		(pad "38" smd rect
			(at -5.999988 -2.22504 270)
			(size 0.508 2.0574)
			(layers "F.Cu" "F.Mask" "F.Paste")
			(net "PCIE_IOM_TO_COMP_18_DP")
		)
		(pad "39" smd rect
			(at -6.800088 -2.22504 270)
			(size 0.508 2.0574)
			(layers "F.Cu" "F.Mask" "F.Paste")
			(net "PCIE_IOM_TO_COMP_18_DN")
		)
		(pad "40" smd rect
			(at -7.599934 -2.22504 270)
			(size 0.508 2.0574)
			(layers "F.Cu" "F.Mask" "F.Paste")
			(net "GND")
		)
		(pad "41" smd rect
			(at -8.400034 -2.22504 270)
			(size 0.508 2.0574)
			(layers "F.Cu" "F.Mask" "F.Paste")
			(net "GND")
		)
		(pad "42" smd rect
			(at -9.19988 -2.22504 270)
			(size 0.508 2.0574)
			(layers "F.Cu" "F.Mask" "F.Paste")
			(net "PCIE_IOM_TO_COMP_19_DP")
		)
		(pad "43" smd rect
			(at -9.99998 -2.22504 270)
			(size 0.508 2.0574)
			(layers "F.Cu" "F.Mask" "F.Paste")
			(net "PCIE_IOM_TO_COMP_19_DN")
		)
		(pad "44" smd rect
			(at -10.80008 -2.22504 270)
			(size 0.508 2.0574)
			(layers "F.Cu" "F.Mask" "F.Paste")
			(net "GND")
		)
		(pad "45" smd rect
			(at -11.599926 -2.22504 270)
			(size 0.508 2.0574)
			(layers "F.Cu" "F.Mask" "F.Paste")
			(net "GND")
		)
		(pad "46" smd rect
			(at -12.400026 -2.22504 270)
			(size 0.508 2.0574)
			(layers "F.Cu" "F.Mask" "F.Paste")
			(net "PCIE_IOM_TO_COMP_20_DP")
		)
		(pad "47" smd rect
			(at -13.200126 -2.22504 270)
			(size 0.508 2.0574)
			(layers "F.Cu" "F.Mask" "F.Paste")
			(net "PCIE_IOM_TO_COMP_20_DN")
		)
		(pad "48" smd rect
			(at -13.999972 -2.22504 270)
			(size 0.508 2.0574)
			(layers "F.Cu" "F.Mask" "F.Paste")
			(net "GND")
		)
		(pad "49" smd rect
			(at -14.800072 -2.22504 270)
			(size 0.508 2.0574)
			(layers "F.Cu" "F.Mask" "F.Paste")
			(net "GND")
		)
		(pad "50" smd rect
			(at -15.599918 -2.22504 270)
			(size 0.508 2.0574)
			(layers "F.Cu" "F.Mask" "F.Paste")
			(net "PCIE_IOM_TO_COMP_21_DP")
		)
		(pad "51" smd rect
			(at -16.400018 -2.22504 270)
			(size 0.508 2.0574)
			(layers "F.Cu" "F.Mask" "F.Paste")
			(net "PCIE_IOM_TO_COMP_21_DN")
		)
		(pad "52" smd rect
			(at -17.200118 -2.22504 270)
			(size 0.508 2.0574)
			(layers "F.Cu" "F.Mask" "F.Paste")
			(net "GND")
		)
		(pad "53" smd rect
			(at -17.999964 -2.22504 270)
			(size 0.508 2.0574)
			(layers "F.Cu" "F.Mask" "F.Paste")
			(net "GND")
		)
		(pad "54" smd rect
			(at -18.800064 -2.22504 270)
			(size 0.508 2.0574)
			(layers "F.Cu" "F.Mask" "F.Paste")
			(net "PCIE_IOM_TO_COMP_22_DP")
		)
		(pad "55" smd rect
			(at -19.59991 -2.22504 270)
			(size 0.508 2.0574)
			(layers "F.Cu" "F.Mask" "F.Paste")
			(net "PCIE_IOM_TO_COMP_22_DN")
		)
		(pad "56" smd rect
			(at -20.40001 -2.22504 270)
			(size 0.508 2.0574)
			(layers "F.Cu" "F.Mask" "F.Paste")
			(net "GND")
		)
		(pad "57" smd rect
			(at -21.20011 -2.22504 270)
			(size 0.508 2.0574)
			(layers "F.Cu" "F.Mask" "F.Paste")
			(net "GND")
		)
		(pad "58" smd rect
			(at -21.999956 -2.22504 270)
			(size 0.508 2.0574)
			(layers "F.Cu" "F.Mask" "F.Paste")
			(net "PCIE_IOM_TO_COMP_23_DP")
		)
		(pad "59" smd rect
			(at -22.800056 -2.22504 270)
			(size 0.508 2.0574)
			(layers "F.Cu" "F.Mask" "F.Paste")
			(net "PCIE_IOM_TO_COMP_23_DN")
		)
		(pad "60" smd rect
			(at -23.599902 -2.22504 270)
			(size 0.508 2.0574)
			(layers "F.Cu" "F.Mask" "F.Paste")
			(net "GND")
		)
		(pad "61" smd rect
			(at 23.599902 2.22504 270)
			(size 0.508 2.0574)
			(layers "F.Cu" "F.Mask" "F.Paste")
			(net "P12V_STBY")
		)
		(pad "62" smd rect
			(at 22.800056 2.22504 270)
			(size 0.508 2.0574)
			(layers "F.Cu" "F.Mask" "F.Paste")
			(net "P12V_STBY")
		)
		(pad "63" smd rect
			(at 21.999956 2.22504 270)
			(size 0.508 2.0574)
			(layers "F.Cu" "F.Mask" "F.Paste")
			(net "P12V_STBY")
		)
		(pad "64" smd rect
			(at 21.20011 2.22504 270)
			(size 0.508 2.0574)
			(layers "F.Cu" "F.Mask" "F.Paste")
			(net "GND")
		)
		(pad "65" smd rect
			(at 20.40001 2.22504 270)
			(size 0.508 2.0574)
			(layers "F.Cu" "F.Mask" "F.Paste")
			(net "GND")
		)
		(pad "66" smd rect
			(at 19.59991 2.22504 270)
			(size 0.508 2.0574)
			(layers "F.Cu" "F.Mask" "F.Paste")
			(net "P3V3_STBY")
		)
		(pad "67" smd rect
			(at 18.800064 2.22504 270)
			(size 0.508 2.0574)
			(layers "F.Cu" "F.Mask" "F.Paste")
			(net "GND")
		)
		(pad "68" smd rect
			(at 17.999964 2.22504 270)
			(size 0.508 2.0574)
			(layers "F.Cu" "F.Mask" "F.Paste")
			(net "GND")
		)
		(pad "69" smd rect
			(at 17.200118 2.22504 270)
			(size 0.508 2.0574)
			(layers "F.Cu" "F.Mask" "F.Paste")
			(net "P3V3")
		)
		(pad "70" smd rect
			(at 16.400018 2.22504 270)
			(size 0.508 2.0574)
			(layers "F.Cu" "F.Mask" "F.Paste")
			(net "P3V3")
		)
		(pad "71" smd rect
			(at 15.599918 2.22504 270)
			(size 0.508 2.0574)
			(layers "F.Cu" "F.Mask" "F.Paste")
			(net "P3V3")
		)
		(pad "72" smd rect
			(at 14.800072 2.22504 270)
			(size 0.508 2.0574)
			(layers "F.Cu" "F.Mask" "F.Paste")
			(net "P3V3")
		)
		(pad "73" smd rect
			(at 13.999972 2.22504 270)
			(size 0.508 2.0574)
			(layers "F.Cu" "F.Mask" "F.Paste")
			(net "GND")
		)
		(pad "74" smd rect
			(at 13.200126 2.22504 270)
			(size 0.508 2.0574)
			(layers "F.Cu" "F.Mask" "F.Paste")
			(net "I2C_MEZZ_ALERT_R_N")
		)
		(pad "75" smd rect
			(at 12.400026 2.22504 270)
			(size 0.508 2.0574)
			(layers "F.Cu" "F.Mask" "F.Paste")
			(net "I2C_MEZZ_FRU_SENSOR_SCL")
		)
		(pad "76" smd rect
			(at 11.599926 2.22504 270)
			(size 0.508 2.0574)
			(layers "F.Cu" "F.Mask" "F.Paste")
			(net "I2C_MEZZ_FRU_SENSOR_SDA")
		)
		(pad "77" smd rect
			(at 10.80008 2.22504 270)
			(size 0.508 2.0574)
			(layers "F.Cu" "F.Mask" "F.Paste")
			(net "PCIE_WAKE_N")
		)
		(pad "78" smd rect
			(at 9.99998 2.22504 270)
			(size 0.508 2.0574)
			(layers "F.Cu" "F.Mask" "F.Paste")
			(net "NCSI_RX_ER_R")
		)
		(pad "79" smd rect
			(at 9.19988 2.22504 270)
			(size 0.508 2.0574)
			(layers "F.Cu" "F.Mask" "F.Paste")
			(net "GND")
		)
		(pad "80" smd rect
			(at 8.400034 2.22504 270)
			(size 0.508 2.0574)
			(layers "F.Cu" "F.Mask" "F.Paste")
			(net "NCSI_TXD0")
		)
		(pad "81" smd rect
			(at 7.599934 2.22504 270)
			(size 0.508 2.0574)
			(layers "F.Cu" "F.Mask" "F.Paste")
			(net "NCSI_TXD1")
		)
		(pad "82" smd rect
			(at 6.800088 2.22504 270)
			(size 0.508 2.0574)
			(layers "F.Cu" "F.Mask" "F.Paste")
			(net "GND")
		)
		(pad "83" smd rect
			(at 5.999988 2.22504 270)
			(size 0.508 2.0574)
			(layers "F.Cu" "F.Mask" "F.Paste")
			(net "GND")
		)
		(pad "84" smd rect
			(at 5.199888 2.22504 270)
			(size 0.508 2.0574)
			(layers "F.Cu" "F.Mask" "F.Paste")
			(net "PCIE_COMP_TO_IOM_CLK_4_DP")
		)
		(pad "85" smd rect
			(at 4.400042 2.22504 270)
			(size 0.508 2.0574)
			(layers "F.Cu" "F.Mask" "F.Paste")
			(net "PCIE_COMP_TO_IOM_CLK_4_DN")
		)
		(pad "86" smd rect
			(at 3.599942 2.22504 270)
			(size 0.508 2.0574)
			(layers "F.Cu" "F.Mask" "F.Paste")
			(net "GND")
		)
		(pad "87" smd rect
			(at 2.800096 2.22504 270)
			(size 0.508 2.0574)
			(layers "F.Cu" "F.Mask" "F.Paste")
			(net "GND")
		)
		(pad "88" smd rect
			(at 1.999996 2.22504 270)
			(size 0.508 2.0574)
			(layers "F.Cu" "F.Mask" "F.Paste")
			(net "PCIE_COMP_TO_IOM_16_DP")
		)
		(pad "89" smd rect
			(at 1.199896 2.22504 270)
			(size 0.508 2.0574)
			(layers "F.Cu" "F.Mask" "F.Paste")
			(net "PCIE_COMP_TO_IOM_16_DN")
		)
		(pad "90" smd rect
			(at 0.40005 2.22504 270)
			(size 0.508 2.0574)
			(layers "F.Cu" "F.Mask" "F.Paste")
			(net "GND")
		)
		(pad "91" smd rect
			(at -0.40005 2.22504 270)
			(size 0.508 2.0574)
			(layers "F.Cu" "F.Mask" "F.Paste")
			(net "GND")
		)
		(pad "92" smd rect
			(at -1.199896 2.22504 270)
			(size 0.508 2.0574)
			(layers "F.Cu" "F.Mask" "F.Paste")
			(net "PCIE_COMP_TO_IOM_17_DP")
		)
		(pad "93" smd rect
			(at -1.999996 2.22504 270)
			(size 0.508 2.0574)
			(layers "F.Cu" "F.Mask" "F.Paste")
			(net "PCIE_COMP_TO_IOM_17_DN")
		)
		(pad "94" smd rect
			(at -2.800096 2.22504 270)
			(size 0.508 2.0574)
			(layers "F.Cu" "F.Mask" "F.Paste")
			(net "GND")
		)
		(pad "95" smd rect
			(at -3.599942 2.22504 270)
			(size 0.508 2.0574)
			(layers "F.Cu" "F.Mask" "F.Paste")
			(net "GND")
		)
		(pad "96" smd rect
			(at -4.400042 2.22504 270)
			(size 0.508 2.0574)
			(layers "F.Cu" "F.Mask" "F.Paste")
			(net "PCIE_COMP_TO_IOM_18_DP")
		)
		(pad "97" smd rect
			(at -5.199888 2.22504 270)
			(size 0.508 2.0574)
			(layers "F.Cu" "F.Mask" "F.Paste")
			(net "PCIE_COMP_TO_IOM_18_DN")
		)
		(pad "98" smd rect
			(at -5.999988 2.22504 270)
			(size 0.508 2.0574)
			(layers "F.Cu" "F.Mask" "F.Paste")
			(net "GND")
		)
		(pad "99" smd rect
			(at -6.800088 2.22504 270)
			(size 0.508 2.0574)
			(layers "F.Cu" "F.Mask" "F.Paste")
			(net "GND")
		)
		(pad "100" smd rect
			(at -7.599934 2.22504 270)
			(size 0.508 2.0574)
			(layers "F.Cu" "F.Mask" "F.Paste")
			(net "PCIE_COMP_TO_IOM_19_DP")
		)
		(pad "101" smd rect
			(at -8.400034 2.22504 270)
			(size 0.508 2.0574)
			(layers "F.Cu" "F.Mask" "F.Paste")
			(net "PCIE_COMP_TO_IOM_19_DN")
		)
		(pad "102" smd rect
			(at -9.19988 2.22504 270)
			(size 0.508 2.0574)
			(layers "F.Cu" "F.Mask" "F.Paste")
			(net "GND")
		)
		(pad "103" smd rect
			(at -9.99998 2.22504 270)
			(size 0.508 2.0574)
			(layers "F.Cu" "F.Mask" "F.Paste")
			(net "GND")
		)
		(pad "104" smd rect
			(at -10.80008 2.22504 270)
			(size 0.508 2.0574)
			(layers "F.Cu" "F.Mask" "F.Paste")
			(net "PCIE_COMP_TO_IOM_20_DP")
		)
		(pad "105" smd rect
			(at -11.599926 2.22504 270)
			(size 0.508 2.0574)
			(layers "F.Cu" "F.Mask" "F.Paste")
			(net "PCIE_COMP_TO_IOM_20_DN")
		)
		(pad "106" smd rect
			(at -12.400026 2.22504 270)
			(size 0.508 2.0574)
			(layers "F.Cu" "F.Mask" "F.Paste")
			(net "GND")
		)
		(pad "107" smd rect
			(at -13.200126 2.22504 270)
			(size 0.508 2.0574)
			(layers "F.Cu" "F.Mask" "F.Paste")
			(net "GND")
		)
		(pad "108" smd rect
			(at -13.999972 2.22504 270)
			(size 0.508 2.0574)
			(layers "F.Cu" "F.Mask" "F.Paste")
			(net "PCIE_COMP_TO_IOM_21_DP")
		)
		(pad "109" smd rect
			(at -14.800072 2.22504 270)
			(size 0.508 2.0574)
			(layers "F.Cu" "F.Mask" "F.Paste")
			(net "PCIE_COMP_TO_IOM_21_DN")
		)
		(pad "110" smd rect
			(at -15.599918 2.22504 270)
			(size 0.508 2.0574)
			(layers "F.Cu" "F.Mask" "F.Paste")
			(net "GND")
		)
		(pad "111" smd rect
			(at -16.400018 2.22504 270)
			(size 0.508 2.0574)
			(layers "F.Cu" "F.Mask" "F.Paste")
			(net "GND")
		)
		(pad "112" smd rect
			(at -17.200118 2.22504 270)
			(size 0.508 2.0574)
			(layers "F.Cu" "F.Mask" "F.Paste")
			(net "PCIE_COMP_TO_IOM_22_DP")
		)
		(pad "113" smd rect
			(at -17.999964 2.22504 270)
			(size 0.508 2.0574)
			(layers "F.Cu" "F.Mask" "F.Paste")
			(net "PCIE_COMP_TO_IOM_22_DN")
		)
		(pad "114" smd rect
			(at -18.800064 2.22504 270)
			(size 0.508 2.0574)
			(layers "F.Cu" "F.Mask" "F.Paste")
			(net "GND")
		)
		(pad "115" smd rect
			(at -19.59991 2.22504 270)
			(size 0.508 2.0574)
			(layers "F.Cu" "F.Mask" "F.Paste")
			(net "GND")
		)
		(pad "116" smd rect
			(at -20.40001 2.22504 270)
			(size 0.508 2.0574)
			(layers "F.Cu" "F.Mask" "F.Paste")
			(net "PCIE_COMP_TO_IOM_23_DP")
		)
		(pad "117" smd rect
			(at -21.20011 2.22504 270)
			(size 0.508 2.0574)
			(layers "F.Cu" "F.Mask" "F.Paste")
			(net "PCIE_COMP_TO_IOM_23_DN")
		)
		(pad "118" smd rect
			(at -21.999956 2.22504 270)
			(size 0.508 2.0574)
			(layers "F.Cu" "F.Mask" "F.Paste")
			(net "GND")
		)
		(pad "119" smd rect
			(at -22.800056 2.22504 270)
			(size 0.508 2.0574)
			(layers "F.Cu" "F.Mask" "F.Paste")
			(net "GND")
		)
		(pad "120" smd rect
			(at -23.599902 2.22504 270)
			(size 0.508 2.0574)
			(layers "F.Cu" "F.Mask" "F.Paste")
			(net "MEZZ_A_PRSNT_120_N")
		)
		(zone
			(layer "F.Cu")
			(hatch none 0.5)
			(connect_pads
				(clearance 0)
			)
			(min_thickness 0.25)
			(keepout
				(tracks allowed)
				(vias not_allowed)
				(pads allowed)
				(copperpour not_allowed)
				(footprints allowed)
			)
			(placement
				(enabled no)
				(sheetname "")
			)
			(fill
				(thermal_gap 0.5)
				(thermal_bridge_width 0.5)
				(island_removal_mode 0)
			)
			(polygon
				(pts
					(xy 76.503784 -96.403922) (xy 76.503784 -48.696118) (xy 77.308964 -48.696118) (xy 77.308964 -96.403922)
				)
			)
		)
		(zone
			(layer "F.Cu")
			(hatch none 0.5)
			(connect_pads
				(clearance 0)
			)
			(min_thickness 0.25)
			(keepout
				(tracks allowed)
				(vias not_allowed)
				(pads allowed)
				(copperpour not_allowed)
				(footprints allowed)
			)
			(placement
				(enabled no)
				(sheetname "")
			)
			(fill
				(thermal_gap 0.5)
				(thermal_bridge_width 0.5)
				(island_removal_mode 0)
			)
			(polygon
				(pts
					(xy 78.091284 -96.403922) (xy 78.091284 -48.696118) (xy 78.896464 -48.696118) (xy 78.896464 -96.403922)
				)
			)
		)
		(zone
			(layers "F.Cu" "B.Cu" "In1.Cu" "In2.Cu" "In3.Cu" "In4.Cu" "In5.Cu" "In6.Cu")
			(hatch none 0.5)
			(connect_pads
				(clearance 0)
			)
			(min_thickness 0.25)
			(keepout
				(tracks not_allowed)
				(vias allowed)
				(pads allowed)
				(copperpour not_allowed)
				(footprints allowed)
			)
			(placement
				(enabled no)
				(sheetname "")
			)
			(fill
				(thermal_gap 0.5)
				(thermal_bridge_width 0.5)
				(island_removal_mode 0)
			)
			(polygon
				(pts
					(arc
						(start 78.436724 -98.650044)
						(mid 76.963524 -98.650044)
						(end 78.436724 -98.650044)
					)
				)
			)
		)
		(zone
			(layers "F.Cu" "B.Cu" "In1.Cu" "In2.Cu" "In3.Cu" "In4.Cu" "In5.Cu" "In6.Cu")
			(hatch none 0.5)
			(connect_pads
				(clearance 0)
			)
			(min_thickness 0.25)
			(keepout
				(tracks not_allowed)
				(vias allowed)
				(pads allowed)
				(copperpour not_allowed)
				(footprints allowed)
			)
			(placement
				(enabled no)
				(sheetname "")
			)
			(fill
				(thermal_gap 0.5)
				(thermal_bridge_width 0.5)
				(island_removal_mode 0)
			)
			(polygon
				(pts
					(arc
						(start 78.614524 -46.449996)
						(mid 76.785724 -46.449996)
						(end 78.614524 -46.449996)
					)
				)
			)
		)
	)
	(footprint ""
		(layer "F.Cu")
		(at 48.05299 -158.1912)
		(property "Reference" "R170"
			(at 0 0 0)
			(layer "F.SilkS")
			(hide yes)
			(effects
				(font
					(size 1.27 1.27)
				)
			)
		)
		(property "Value" "0R2J-2-GP"
			(at 0.064008 -3.993896 0)
			(unlocked yes)
			(layer "F.Fab")
			(hide yes)
			(effects
				(font
					(size 1.016 1.016)
					(thickness 0.1524)
				)
			)
		)
		(property "Device Type" "R402H16"
			(at 0.064008 -5.517896 0)
			(unlocked yes)
			(layer "F.Fab")
			(hide yes)
			(effects
				(font
					(size 1.016 1.016)
					(thickness 0.1524)
				)
			)
		)
		(duplicate_pad_numbers_are_jumpers no)
		(fp_line
			(start -0.508 -0.9398)
			(end -0.508 0.9398)
			(stroke
				(width 0.1524)
				(type default)
			)
			(layer "F.SilkS")
		)
		(fp_line
			(start 0.508 -0.9398)
			(end -0.508 -0.9398)
			(stroke
				(width 0.1524)
				(type default)
			)
			(layer "F.SilkS")
		)
		(fp_rect
			(start -0.508 0.9398)
			(end 0.508 -0.9398)
			(stroke
				(width 0)
				(type default)
			)
			(fill no)
			(layer "F.CrtYd")
		)
		(fp_rect
			(start -0.508 0.9398)
			(end 0.508 -0.9398)
			(stroke
				(width 0)
				(type default)
			)
			(fill no)
			(layer "F.Fab")
		)
		(pad "1" smd custom
			(at 0 -0.4445)
			(size 0.1397 0.1397)
			(layers "F.Cu" "F.Mask" "F.Paste")
			(net "I2C_DPB_MISC_SDA_OUT")
			(options
				(clearance outline)
				(anchor circle)
			)
			(primitives
				(gr_poly
					(pts
						(arc
							(start -0.1778 -0.2794)
							(mid -0.249642 -0.249642)
							(end -0.2794 -0.1778)
						)
						(arc
							(start -0.2794 0.1778)
							(mid -0.249642 0.249642)
							(end -0.1778 0.2794)
						)
						(arc
							(start 0.1778 0.2794)
							(mid 0.249642 0.249642)
							(end 0.2794 0.1778)
						)
						(arc
							(start 0.2794 -0.1778)
							(mid 0.249642 -0.249642)
							(end 0.1778 -0.2794)
						)
					)
					(width 0)
					(fill yes)
				)
			)
		)
		(pad "2" smd custom
			(at 0 0.4445)
			(size 0.1397 0.1397)
			(layers "F.Cu" "F.Mask" "F.Paste")
			(net "BMC_SMB6_DAT")
			(options
				(clearance outline)
				(anchor circle)
			)
			(primitives
				(gr_poly
					(pts
						(arc
							(start -0.1778 -0.2794)
							(mid -0.249642 -0.249642)
							(end -0.2794 -0.1778)
						)
						(arc
							(start -0.2794 0.1778)
							(mid -0.249642 0.249642)
							(end -0.1778 0.2794)
						)
						(arc
							(start 0.1778 0.2794)
							(mid 0.249642 0.249642)
							(end 0.2794 0.1778)
						)
						(arc
							(start 0.2794 -0.1778)
							(mid 0.249642 -0.249642)
							(end 0.1778 -0.2794)
						)
					)
					(width 0)
					(fill yes)
				)
			)
		)
	)
	(footprint ""
		(layer "F.Cu")
		(at 163.9062 -134.112)
		(property "Reference" "C203"
			(at 0 0 0)
			(layer "F.SilkS")
			(hide yes)
			(effects
				(font
					(size 1.27 1.27)
				)
			)
		)
		(property "Value" "SCD1U16V2KX-3GP"
			(at 1.1811 -2.7051 0)
			(unlocked yes)
			(layer "F.Fab")
			(hide yes)
			(effects
				(font
					(size 1.016 1.016)
					(thickness 0.1524)
				)
			)
		)
		(property "Device Type" "C402H22"
			(at 1.1811 -4.2291 0)
			(unlocked yes)
			(layer "F.Fab")
			(hide yes)
			(effects
				(font
					(size 1.016 1.016)
					(thickness 0.1524)
				)
			)
		)
		(duplicate_pad_numbers_are_jumpers no)
		(fp_rect
			(start -0.4318 0.9525)
			(end 0.4318 -0.9525)
			(stroke
				(width 0)
				(type default)
			)
			(fill no)
			(layer "F.CrtYd")
		)
		(fp_rect
			(start -0.4318 0.9525)
			(end 0.4318 -0.9525)
			(stroke
				(width 0)
				(type default)
			)
			(fill no)
			(layer "F.Fab")
		)
		(pad "1" smd custom
			(at 0 -0.4445)
			(size 0.1524 0.1524)
			(layers "F.Cu" "F.Mask" "F.Paste")
			(net "P12V_STBY_VIN_PU4")
			(options
				(clearance outline)
				(anchor circle)
			)
			(primitives
				(gr_poly
					(pts
						(arc
							(start 0.3048 -0.2032)
							(mid 0.275042 -0.275042)
							(end 0.2032 -0.3048)
						)
						(arc
							(start -0.2032 -0.3048)
							(mid -0.275042 -0.275042)
							(end -0.3048 -0.2032)
						)
						(arc
							(start -0.3048 0.2032)
							(mid -0.275042 0.275042)
							(end -0.2032 0.3048)
						)
						(arc
							(start 0.2032 0.3048)
							(mid 0.275042 0.275042)
							(end 0.3048 0.2032)
						)
					)
					(width 0)
					(fill yes)
				)
			)
		)
		(pad "2" smd custom
			(at 0 0.4445)
			(size 0.1524 0.1524)
			(layers "F.Cu" "F.Mask" "F.Paste")
			(net "GND")
			(options
				(clearance outline)
				(anchor circle)
			)
			(primitives
				(gr_poly
					(pts
						(arc
							(start 0.3048 -0.2032)
							(mid 0.275042 -0.275042)
							(end 0.2032 -0.3048)
						)
						(arc
							(start -0.2032 -0.3048)
							(mid -0.275042 -0.275042)
							(end -0.3048 -0.2032)
						)
						(arc
							(start -0.3048 0.2032)
							(mid -0.275042 0.275042)
							(end -0.2032 0.3048)
						)
						(arc
							(start 0.2032 0.3048)
							(mid 0.275042 0.275042)
							(end 0.3048 0.2032)
						)
					)
					(width 0)
					(fill yes)
				)
			)
		)
	)
	(footprint ""
		(layer "F.Cu")
		(at 174.4726 -65.913 90)
		(property "Reference" "R578"
			(at 0 0 90)
			(layer "F.SilkS")
			(hide yes)
			(effects
				(font
					(size 1.27 1.27)
				)
			)
		)
		(property "Value" "2K2R2F-GP"
			(at 0.064008 -3.993896 90)
			(unlocked yes)
			(layer "F.Fab")
			(hide yes)
			(effects
				(font
					(size 1.016 1.016)
					(thickness 0.1524)
				)
			)
		)
		(property "Device Type" "R402H16"
			(at 0.064008 -5.517896 90)
			(unlocked yes)
			(layer "F.Fab")
			(hide yes)
			(effects
				(font
					(size 1.016 1.016)
					(thickness 0.1524)
				)
			)
		)
		(duplicate_pad_numbers_are_jumpers no)
		(fp_line
			(start 0.508 -0.9398)
			(end -0.508 -0.9398)
			(stroke
				(width 0.1524)
				(type default)
			)
			(layer "F.SilkS")
		)
		(fp_line
			(start -0.508 -0.9398)
			(end -0.508 0.9398)
			(stroke
				(width 0.1524)
				(type default)
			)
			(layer "F.SilkS")
		)
		(fp_rect
			(start -0.508 0.9398)
			(end 0.508 -0.9398)
			(stroke
				(width 0)
				(type default)
			)
			(fill no)
			(layer "F.CrtYd")
		)
		(fp_rect
			(start -0.508 0.9398)
			(end 0.508 -0.9398)
			(stroke
				(width 0)
				(type default)
			)
			(fill no)
			(layer "F.Fab")
		)
		(pad "1" smd custom
			(at 0 -0.4445 90)
			(size 0.1397 0.1397)
			(layers "F.Cu" "F.Mask" "F.Paste")
			(net "P1V8")
			(options
				(clearance outline)
				(anchor circle)
			)
			(primitives
				(gr_poly
					(pts
						(arc
							(start -0.1778 -0.2794)
							(mid -0.249642 -0.249642)
							(end -0.2794 -0.1778)
						)
						(arc
							(start -0.2794 0.1778)
							(mid -0.249642 0.249642)
							(end -0.1778 0.2794)
						)
						(arc
							(start 0.1778 0.2794)
							(mid 0.249642 0.249642)
							(end 0.2794 0.1778)
						)
						(arc
							(start 0.2794 -0.1778)
							(mid 0.249642 -0.249642)
							(end 0.1778 -0.2794)
						)
					)
					(width 0)
					(fill yes)
				)
			)
		)
		(pad "2" smd custom
			(at 0 0.4445 90)
			(size 0.1397 0.1397)
			(layers "F.Cu" "F.Mask" "F.Paste")
			(net "SBL_SCL")
			(options
				(clearance outline)
				(anchor circle)
			)
			(primitives
				(gr_poly
					(pts
						(arc
							(start -0.1778 -0.2794)
							(mid -0.249642 -0.249642)
							(end -0.2794 -0.1778)
						)
						(arc
							(start -0.2794 0.1778)
							(mid -0.249642 0.249642)
							(end -0.1778 0.2794)
						)
						(arc
							(start 0.1778 0.2794)
							(mid 0.249642 0.249642)
							(end 0.2794 0.1778)
						)
						(arc
							(start 0.2794 -0.1778)
							(mid 0.249642 -0.249642)
							(end 0.1778 -0.2794)
						)
					)
					(width 0)
					(fill yes)
				)
			)
		)
	)
	(footprint ""
		(layer "F.Cu")
		(at 157.688788 -95.037656 180)
		(property "Reference" "R691"
			(at 0 0 180)
			(layer "F.SilkS")
			(hide yes)
			(effects
				(font
					(size 1.27 1.27)
				)
			)
		)
		(property "Value" "0R2J-2-GP"
			(at 0.064008 -3.993896 180)
			(unlocked yes)
			(layer "F.Fab")
			(hide yes)
			(effects
				(font
					(size 1.016 1.016)
					(thickness 0.1524)
				)
			)
		)
		(property "Device Type" "R402H16"
			(at 0.064008 -5.517896 180)
			(unlocked yes)
			(layer "F.Fab")
			(hide yes)
			(effects
				(font
					(size 1.016 1.016)
					(thickness 0.1524)
				)
			)
		)
		(duplicate_pad_numbers_are_jumpers no)
		(fp_line
			(start 0.508 -0.9398)
			(end -0.508 -0.9398)
			(stroke
				(width 0.1524)
				(type default)
			)
			(layer "F.SilkS")
		)
		(fp_line
			(start -0.508 -0.9398)
			(end -0.508 0.9398)
			(stroke
				(width 0.1524)
				(type default)
			)
			(layer "F.SilkS")
		)
		(fp_rect
			(start -0.508 0.9398)
			(end 0.508 -0.9398)
			(stroke
				(width 0)
				(type default)
			)
			(fill no)
			(layer "F.CrtYd")
		)
		(fp_rect
			(start -0.508 0.9398)
			(end 0.508 -0.9398)
			(stroke
				(width 0)
				(type default)
			)
			(fill no)
			(layer "F.Fab")
		)
		(pad "1" smd custom
			(at 0 -0.4445 180)
			(size 0.1397 0.1397)
			(layers "F.Cu" "F.Mask" "F.Paste")
			(net "IOC_UART_0_TX_R")
			(options
				(clearance outline)
				(anchor circle)
			)
			(primitives
				(gr_poly
					(pts
						(arc
							(start -0.1778 -0.2794)
							(mid -0.249642 -0.249642)
							(end -0.2794 -0.1778)
						)
						(arc
							(start -0.2794 0.1778)
							(mid -0.249642 0.249642)
							(end -0.1778 0.2794)
						)
						(arc
							(start 0.1778 0.2794)
							(mid 0.249642 0.249642)
							(end 0.2794 0.1778)
						)
						(arc
							(start 0.2794 -0.1778)
							(mid 0.249642 -0.249642)
							(end 0.1778 -0.2794)
						)
					)
					(width 0)
					(fill yes)
				)
			)
		)
		(pad "2" smd custom
			(at 0 0.4445 180)
			(size 0.1397 0.1397)
			(layers "F.Cu" "F.Mask" "F.Paste")
			(net "IOC_UART_0_TX")
			(options
				(clearance outline)
				(anchor circle)
			)
			(primitives
				(gr_poly
					(pts
						(arc
							(start -0.1778 -0.2794)
							(mid -0.249642 -0.249642)
							(end -0.2794 -0.1778)
						)
						(arc
							(start -0.2794 0.1778)
							(mid -0.249642 0.249642)
							(end -0.1778 0.2794)
						)
						(arc
							(start 0.1778 0.2794)
							(mid 0.249642 0.249642)
							(end 0.2794 0.1778)
						)
						(arc
							(start 0.2794 -0.1778)
							(mid 0.249642 -0.249642)
							(end 0.1778 -0.2794)
						)
					)
					(width 0)
					(fill yes)
				)
			)
		)
	)
	(footprint ""
		(layer "F.Cu")
		(at 83.312 -170.5864)
		(property "Reference" "R726"
			(at 0 0 0)
			(layer "F.SilkS")
			(hide yes)
			(effects
				(font
					(size 1.27 1.27)
				)
			)
		)
		(property "Value" "4K7R2F-GP"
			(at 0.064008 -3.993896 0)
			(unlocked yes)
			(layer "F.Fab")
			(hide yes)
			(effects
				(font
					(size 1.016 1.016)
					(thickness 0.1524)
				)
			)
		)
		(property "Device Type" "R402H16"
			(at 0.064008 -5.517896 0)
			(unlocked yes)
			(layer "F.Fab")
			(hide yes)
			(effects
				(font
					(size 1.016 1.016)
					(thickness 0.1524)
				)
			)
		)
		(duplicate_pad_numbers_are_jumpers no)
		(fp_line
			(start -0.508 -0.9398)
			(end -0.508 0.9398)
			(stroke
				(width 0.1524)
				(type default)
			)
			(layer "F.SilkS")
		)
		(fp_line
			(start 0.508 -0.9398)
			(end -0.508 -0.9398)
			(stroke
				(width 0.1524)
				(type default)
			)
			(layer "F.SilkS")
		)
		(fp_rect
			(start -0.508 0.9398)
			(end 0.508 -0.9398)
			(stroke
				(width 0)
				(type default)
			)
			(fill no)
			(layer "F.CrtYd")
		)
		(fp_rect
			(start -0.508 0.9398)
			(end 0.508 -0.9398)
			(stroke
				(width 0)
				(type default)
			)
			(fill no)
			(layer "F.Fab")
		)
		(pad "1" smd custom
			(at 0 -0.4445)
			(size 0.1397 0.1397)
			(layers "F.Cu" "F.Mask" "F.Paste")
			(net "P3V3_STBY")
			(options
				(clearance outline)
				(anchor circle)
			)
			(primitives
				(gr_poly
					(pts
						(arc
							(start -0.1778 -0.2794)
							(mid -0.249642 -0.249642)
							(end -0.2794 -0.1778)
						)
						(arc
							(start -0.2794 0.1778)
							(mid -0.249642 0.249642)
							(end -0.1778 0.2794)
						)
						(arc
							(start 0.1778 0.2794)
							(mid 0.249642 0.249642)
							(end 0.2794 0.1778)
						)
						(arc
							(start 0.2794 -0.1778)
							(mid 0.249642 -0.249642)
							(end 0.1778 -0.2794)
						)
					)
					(width 0)
					(fill yes)
				)
			)
		)
		(pad "2" smd custom
			(at 0 0.4445)
			(size 0.1397 0.1397)
			(layers "F.Cu" "F.Mask" "F.Paste")
			(net "IOM_STBY_PGOOD")
			(options
				(clearance outline)
				(anchor circle)
			)
			(primitives
				(gr_poly
					(pts
						(arc
							(start -0.1778 -0.2794)
							(mid -0.249642 -0.249642)
							(end -0.2794 -0.1778)
						)
						(arc
							(start -0.2794 0.1778)
							(mid -0.249642 0.249642)
							(end -0.1778 0.2794)
						)
						(arc
							(start 0.1778 0.2794)
							(mid 0.249642 0.249642)
							(end 0.2794 0.1778)
						)
						(arc
							(start 0.2794 -0.1778)
							(mid 0.249642 -0.249642)
							(end 0.1778 -0.2794)
						)
					)
					(width 0)
					(fill yes)
				)
			)
		)
	)
	(footprint ""
		(layer "F.Cu")
		(at 39.3954 -164.6936 90)
		(property "Reference" "R302"
			(at 0 0 90)
			(layer "F.SilkS")
			(hide yes)
			(effects
				(font
					(size 1.27 1.27)
				)
			)
		)
		(property "Value" "0R2J-2-GP"
			(at 0.064008 -3.993896 90)
			(unlocked yes)
			(layer "F.Fab")
			(hide yes)
			(effects
				(font
					(size 1.016 1.016)
					(thickness 0.1524)
				)
			)
		)
		(property "Device Type" "R402H16"
			(at 0.064008 -5.517896 90)
			(unlocked yes)
			(layer "F.Fab")
			(hide yes)
			(effects
				(font
					(size 1.016 1.016)
					(thickness 0.1524)
				)
			)
		)
		(duplicate_pad_numbers_are_jumpers no)
		(fp_line
			(start 0.508 -0.9398)
			(end -0.508 -0.9398)
			(stroke
				(width 0.1524)
				(type default)
			)
			(layer "F.SilkS")
		)
		(fp_line
			(start -0.508 -0.9398)
			(end -0.508 0.9398)
			(stroke
				(width 0.1524)
				(type default)
			)
			(layer "F.SilkS")
		)
		(fp_rect
			(start -0.508 0.9398)
			(end 0.508 -0.9398)
			(stroke
				(width 0)
				(type default)
			)
			(fill no)
			(layer "F.CrtYd")
		)
		(fp_rect
			(start -0.508 0.9398)
			(end 0.508 -0.9398)
			(stroke
				(width 0)
				(type default)
			)
			(fill no)
			(layer "F.Fab")
		)
		(pad "1" smd custom
			(at 0 -0.4445 90)
			(size 0.1397 0.1397)
			(layers "F.Cu" "F.Mask" "F.Paste")
			(net "UART_EXP_BMC_TX")
			(options
				(clearance outline)
				(anchor circle)
			)
			(primitives
				(gr_poly
					(pts
						(arc
							(start -0.1778 -0.2794)
							(mid -0.249642 -0.249642)
							(end -0.2794 -0.1778)
						)
						(arc
							(start -0.2794 0.1778)
							(mid -0.249642 0.249642)
							(end -0.1778 0.2794)
						)
						(arc
							(start 0.1778 0.2794)
							(mid 0.249642 0.249642)
							(end 0.2794 0.1778)
						)
						(arc
							(start 0.2794 -0.1778)
							(mid 0.249642 -0.249642)
							(end 0.1778 -0.2794)
						)
					)
					(width 0)
					(fill yes)
				)
			)
		)
		(pad "2" smd custom
			(at 0 0.4445 90)
			(size 0.1397 0.1397)
			(layers "F.Cu" "F.Mask" "F.Paste")
			(net "UART_EXP_BMC_TX_R")
			(options
				(clearance outline)
				(anchor circle)
			)
			(primitives
				(gr_poly
					(pts
						(arc
							(start -0.1778 -0.2794)
							(mid -0.249642 -0.249642)
							(end -0.2794 -0.1778)
						)
						(arc
							(start -0.2794 0.1778)
							(mid -0.249642 0.249642)
							(end -0.1778 0.2794)
						)
						(arc
							(start 0.1778 0.2794)
							(mid 0.249642 0.249642)
							(end 0.2794 0.1778)
						)
						(arc
							(start 0.2794 -0.1778)
							(mid 0.249642 -0.249642)
							(end 0.1778 -0.2794)
						)
					)
					(width 0)
					(fill yes)
				)
			)
		)
	)
	(footprint ""
		(layer "F.Cu")
		(at 187.600844 -86.54542)
		(property "Reference" "TP149"
			(at 0 0 0)
			(layer "F.SilkS")
			(hide yes)
			(effects
				(font
					(size 1.27 1.27)
				)
			)
		)
		(property "Value" "TPAD28-2-GP"
			(at -0.0127 -1.6637 0)
			(unlocked yes)
			(layer "F.Fab")
			(hide yes)
			(effects
				(font
					(size 1.016 1.016)
					(thickness 0.1524)
				)
			)
		)
		(property "Device Type" "TPAD28"
			(at -0.0127 -3.1877 0)
			(unlocked yes)
			(layer "F.Fab")
			(hide yes)
			(effects
				(font
					(size 1.016 1.016)
					(thickness 0.1524)
				)
			)
		)
		(duplicate_pad_numbers_are_jumpers no)
		(fp_poly
			(pts
				(arc
					(start 0.3556 0)
					(mid -0.3556 0)
					(end 0.3556 0)
				)
			)
			(stroke
				(width 0)
				(type default)
			)
			(fill no)
			(layer "F.CrtYd")
		)
		(fp_poly
			(pts
				(arc
					(start 0.6096 0)
					(mid -0.6096 0)
					(end 0.6096 0)
				)
			)
			(stroke
				(width 0)
				(type default)
			)
			(fill no)
			(layer "F.Fab")
		)
		(pad "1" smd circle
			(at 0 0)
			(size 0.7112 0.7112)
			(layers "F.Cu" "F.Mask" "F.Paste")
			(net "SYS_DBMODE1")
		)
	)
	(footprint ""
		(layer "F.Cu")
		(at 184.1754 -116.0526 90)
		(property "Reference" "C274"
			(at 0 0 90)
			(layer "F.SilkS")
			(hide yes)
			(effects
				(font
					(size 1.27 1.27)
				)
			)
		)
		(property "Value" "SC10U16V5KX-7-GP-U"
			(at -0.0762 -6.1214 90)
			(unlocked yes)
			(layer "F.Fab")
			(hide yes)
			(effects
				(font
					(size 1.016 1.016)
					(thickness 0.1524)
				)
			)
		)
		(property "Device Type" "C805H58"
			(at -0.0762 -8.1534 90)
			(unlocked yes)
			(layer "F.Fab")
			(hide yes)
			(effects
				(font
					(size 1.016 1.016)
					(thickness 0.1524)
				)
			)
		)
		(duplicate_pad_numbers_are_jumpers no)
		(fp_line
			(start 0.635 0)
			(end -0.635 0)
			(stroke
				(width 0.508)
				(type default)
			)
			(layer "F.SilkS")
		)
		(fp_rect
			(start -0.9652 1.778)
			(end 0.9652 -1.778)
			(stroke
				(width 0)
				(type default)
			)
			(fill no)
			(layer "F.CrtYd")
		)
		(fp_poly
			(pts
				(xy -0.9652 -1.778) (xy 0.9652 -1.778) (xy 0.9652 1.778) (xy -0.9652 1.778)
			)
			(stroke
				(width 0)
				(type default)
			)
			(fill no)
			(layer "F.Fab")
		)
		(pad "1" smd rect
			(at 0 -0.9652 90)
			(size 1.397 1.143)
			(layers "F.Cu" "F.Mask" "F.Paste")
			(net "VT235_VDDH")
		)
		(pad "2" smd rect
			(at 0 0.9652 90)
			(size 1.397 1.143)
			(layers "F.Cu" "F.Mask" "F.Paste")
			(net "GND")
		)
	)
	(footprint ""
		(layer "F.Cu")
		(at 157.099 -118.618 -90)
		(property "Reference" "C214"
			(at 0 0 270)
			(layer "F.SilkS")
			(hide yes)
			(effects
				(font
					(size 1.27 1.27)
				)
			)
		)
		(property "Value" "SCD1U16V2KX-3GP"
			(at 1.1811 -2.7051 270)
			(unlocked yes)
			(layer "F.Fab")
			(hide yes)
			(effects
				(font
					(size 1.016 1.016)
					(thickness 0.1524)
				)
			)
		)
		(property "Device Type" "C402H22"
			(at 1.1811 -4.2291 270)
			(unlocked yes)
			(layer "F.Fab")
			(hide yes)
			(effects
				(font
					(size 1.016 1.016)
					(thickness 0.1524)
				)
			)
		)
		(duplicate_pad_numbers_are_jumpers no)
		(fp_rect
			(start -0.4318 0.9525)
			(end 0.4318 -0.9525)
			(stroke
				(width 0)
				(type default)
			)
			(fill no)
			(layer "F.CrtYd")
		)
		(fp_rect
			(start -0.4318 0.9525)
			(end 0.4318 -0.9525)
			(stroke
				(width 0)
				(type default)
			)
			(fill no)
			(layer "F.Fab")
		)
		(pad "1" smd custom
			(at 0 -0.4445 270)
			(size 0.1524 0.1524)
			(layers "F.Cu" "F.Mask" "F.Paste")
			(net "P1V8_STBY")
			(options
				(clearance outline)
				(anchor circle)
			)
			(primitives
				(gr_poly
					(pts
						(arc
							(start 0.3048 -0.2032)
							(mid 0.275042 -0.275042)
							(end 0.2032 -0.3048)
						)
						(arc
							(start -0.2032 -0.3048)
							(mid -0.275042 -0.275042)
							(end -0.3048 -0.2032)
						)
						(arc
							(start -0.3048 0.2032)
							(mid -0.275042 0.275042)
							(end -0.2032 0.3048)
						)
						(arc
							(start 0.2032 0.3048)
							(mid 0.275042 0.275042)
							(end 0.3048 0.2032)
						)
					)
					(width 0)
					(fill yes)
				)
			)
		)
		(pad "2" smd custom
			(at 0 0.4445 270)
			(size 0.1524 0.1524)
			(layers "F.Cu" "F.Mask" "F.Paste")
			(net "GND")
			(options
				(clearance outline)
				(anchor circle)
			)
			(primitives
				(gr_poly
					(pts
						(arc
							(start 0.3048 -0.2032)
							(mid 0.275042 -0.275042)
							(end 0.2032 -0.3048)
						)
						(arc
							(start -0.2032 -0.3048)
							(mid -0.275042 -0.275042)
							(end -0.3048 -0.2032)
						)
						(arc
							(start -0.3048 0.2032)
							(mid -0.275042 0.275042)
							(end -0.2032 0.3048)
						)
						(arc
							(start 0.2032 0.3048)
							(mid 0.275042 0.275042)
							(end 0.3048 0.2032)
						)
					)
					(width 0)
					(fill yes)
				)
			)
		)
	)
	(footprint ""
		(layer "F.Cu")
		(at 179.4002 -81.2546)
		(property "Reference" "TP147"
			(at 0 0 0)
			(layer "F.SilkS")
			(hide yes)
			(effects
				(font
					(size 1.27 1.27)
				)
			)
		)
		(property "Value" "TPAD28-2-GP"
			(at -0.0127 -1.6637 0)
			(unlocked yes)
			(layer "F.Fab")
			(hide yes)
			(effects
				(font
					(size 1.016 1.016)
					(thickness 0.1524)
				)
			)
		)
		(property "Device Type" "TPAD28"
			(at -0.0127 -3.1877 0)
			(unlocked yes)
			(layer "F.Fab")
			(hide yes)
			(effects
				(font
					(size 1.016 1.016)
					(thickness 0.1524)
				)
			)
		)
		(duplicate_pad_numbers_are_jumpers no)
		(fp_poly
			(pts
				(arc
					(start 0.3556 0)
					(mid -0.3556 0)
					(end 0.3556 0)
				)
			)
			(stroke
				(width 0)
				(type default)
			)
			(fill no)
			(layer "F.CrtYd")
		)
		(fp_poly
			(pts
				(arc
					(start 0.6096 0)
					(mid -0.6096 0)
					(end 0.6096 0)
				)
			)
			(stroke
				(width 0)
				(type default)
			)
			(fill no)
			(layer "F.Fab")
		)
		(pad "1" smd circle
			(at 0 0)
			(size 0.7112 0.7112)
			(layers "F.Cu" "F.Mask" "F.Paste")
			(net "SYS_HALT1#")
		)
	)
	(footprint ""
		(layer "F.Cu")
		(at 159.55264 -142.885922 180)
		(property "Reference" "C209"
			(at 0 0 180)
			(layer "F.SilkS")
			(hide yes)
			(effects
				(font
					(size 1.27 1.27)
				)
			)
		)
		(property "Value" "SC1U16V3KX-5GP"
			(at 0 -2.8194 180)
			(unlocked yes)
			(layer "F.Fab")
			(hide yes)
			(effects
				(font
					(size 1.016 1.016)
					(thickness 0.1524)
				)
			)
		)
		(property "Device Type" "C603H36"
			(at 0 -4.3434 180)
			(unlocked yes)
			(layer "F.Fab")
			(hide yes)
			(effects
				(font
					(size 1.016 1.016)
					(thickness 0.1524)
				)
			)
		)
		(duplicate_pad_numbers_are_jumpers no)
		(fp_line
			(start 0.508 0)
			(end -0.508 0)
			(stroke
				(width 0.2032)
				(type default)
			)
			(layer "F.SilkS")
		)
		(fp_rect
			(start -0.5842 1.3335)
			(end 0.5842 -1.3335)
			(stroke
				(width 0)
				(type default)
			)
			(fill no)
			(layer "F.CrtYd")
		)
		(fp_rect
			(start -0.5842 1.3335)
			(end 0.5842 -1.3335)
			(stroke
				(width 0)
				(type default)
			)
			(fill no)
			(layer "F.Fab")
		)
		(pad "1" smd custom
			(at 0 -0.762 180)
			(size 0.2159 0.2159)
			(layers "F.Cu" "F.Mask" "F.Paste")
			(net "P1V8_STBY_VRG5")
			(options
				(clearance outline)
				(anchor circle)
			)
			(primitives
				(gr_poly
					(pts
						(arc
							(start -0.3302 -0.4318)
							(mid -0.402042 -0.402042)
							(end -0.4318 -0.3302)
						)
						(arc
							(start -0.4318 0.3302)
							(mid -0.402042 0.402042)
							(end -0.3302 0.4318)
						)
						(arc
							(start 0.3302 0.4318)
							(mid 0.402042 0.402042)
							(end 0.4318 0.3302)
						)
						(arc
							(start 0.4318 -0.3302)
							(mid 0.402042 -0.402042)
							(end 0.3302 -0.4318)
						)
					)
					(width 0)
					(fill yes)
				)
			)
		)
		(pad "2" smd custom
			(at 0 0.762 180)
			(size 0.2159 0.2159)
			(layers "F.Cu" "F.Mask" "F.Paste")
			(net "GND")
			(options
				(clearance outline)
				(anchor circle)
			)
			(primitives
				(gr_poly
					(pts
						(arc
							(start -0.3302 -0.4318)
							(mid -0.402042 -0.402042)
							(end -0.4318 -0.3302)
						)
						(arc
							(start -0.4318 0.3302)
							(mid -0.402042 0.402042)
							(end -0.3302 0.4318)
						)
						(arc
							(start 0.3302 0.4318)
							(mid 0.402042 0.402042)
							(end 0.4318 0.3302)
						)
						(arc
							(start 0.4318 -0.3302)
							(mid 0.402042 -0.402042)
							(end 0.3302 -0.4318)
						)
					)
					(width 0)
					(fill yes)
				)
			)
		)
	)
	(footprint ""
		(layer "F.Cu")
		(at 185.7756 -90.8558 180)
		(property "Reference" "R659"
			(at 0 0 180)
			(layer "F.SilkS")
			(hide yes)
			(effects
				(font
					(size 1.27 1.27)
				)
			)
		)
		(property "Value" "4K7R2F-GP"
			(at 0.064008 -3.993896 180)
			(unlocked yes)
			(layer "F.Fab")
			(hide yes)
			(effects
				(font
					(size 1.016 1.016)
					(thickness 0.1524)
				)
			)
		)
		(property "Device Type" "R402H16"
			(at 0.064008 -5.517896 180)
			(unlocked yes)
			(layer "F.Fab")
			(hide yes)
			(effects
				(font
					(size 1.016 1.016)
					(thickness 0.1524)
				)
			)
		)
		(duplicate_pad_numbers_are_jumpers no)
		(fp_line
			(start 0.508 -0.9398)
			(end -0.508 -0.9398)
			(stroke
				(width 0.1524)
				(type default)
			)
			(layer "F.SilkS")
		)
		(fp_line
			(start -0.508 -0.9398)
			(end -0.508 0.9398)
			(stroke
				(width 0.1524)
				(type default)
			)
			(layer "F.SilkS")
		)
		(fp_rect
			(start -0.508 0.9398)
			(end 0.508 -0.9398)
			(stroke
				(width 0)
				(type default)
			)
			(fill no)
			(layer "F.CrtYd")
		)
		(fp_rect
			(start -0.508 0.9398)
			(end 0.508 -0.9398)
			(stroke
				(width 0)
				(type default)
			)
			(fill no)
			(layer "F.Fab")
		)
		(pad "1" smd custom
			(at 0 -0.4445 180)
			(size 0.1397 0.1397)
			(layers "F.Cu" "F.Mask" "F.Paste")
			(net "SYS_DBMODE4")
			(options
				(clearance outline)
				(anchor circle)
			)
			(primitives
				(gr_poly
					(pts
						(arc
							(start -0.1778 -0.2794)
							(mid -0.249642 -0.249642)
							(end -0.2794 -0.1778)
						)
						(arc
							(start -0.2794 0.1778)
							(mid -0.249642 0.249642)
							(end -0.1778 0.2794)
						)
						(arc
							(start 0.1778 0.2794)
							(mid 0.249642 0.249642)
							(end 0.2794 0.1778)
						)
						(arc
							(start 0.2794 -0.1778)
							(mid 0.249642 -0.249642)
							(end 0.1778 -0.2794)
						)
					)
					(width 0)
					(fill yes)
				)
			)
		)
		(pad "2" smd custom
			(at 0 0.4445 180)
			(size 0.1397 0.1397)
			(layers "F.Cu" "F.Mask" "F.Paste")
			(net "GND")
			(options
				(clearance outline)
				(anchor circle)
			)
			(primitives
				(gr_poly
					(pts
						(arc
							(start -0.1778 -0.2794)
							(mid -0.249642 -0.249642)
							(end -0.2794 -0.1778)
						)
						(arc
							(start -0.2794 0.1778)
							(mid -0.249642 0.249642)
							(end -0.1778 0.2794)
						)
						(arc
							(start 0.1778 0.2794)
							(mid 0.249642 0.249642)
							(end 0.2794 0.1778)
						)
						(arc
							(start 0.2794 -0.1778)
							(mid 0.249642 -0.249642)
							(end 0.1778 -0.2794)
						)
					)
					(width 0)
					(fill yes)
				)
			)
		)
	)
	(footprint ""
		(layer "F.Cu")
		(at 162.8394 -141.605 -90)
		(property "Reference" "C206"
			(at 0 0 270)
			(layer "F.SilkS")
			(hide yes)
			(effects
				(font
					(size 1.27 1.27)
				)
			)
		)
		(property "Value" "SC100P50V2JN-3GP"
			(at 1.1811 -2.7051 270)
			(unlocked yes)
			(layer "F.Fab")
			(hide yes)
			(effects
				(font
					(size 1.016 1.016)
					(thickness 0.1524)
				)
			)
		)
		(property "Device Type" "C402H22"
			(at 1.1811 -4.2291 270)
			(unlocked yes)
			(layer "F.Fab")
			(hide yes)
			(effects
				(font
					(size 1.016 1.016)
					(thickness 0.1524)
				)
			)
		)
		(duplicate_pad_numbers_are_jumpers no)
		(fp_rect
			(start -0.4318 0.9525)
			(end 0.4318 -0.9525)
			(stroke
				(width 0)
				(type default)
			)
			(fill no)
			(layer "F.CrtYd")
		)
		(fp_rect
			(start -0.4318 0.9525)
			(end 0.4318 -0.9525)
			(stroke
				(width 0)
				(type default)
			)
			(fill no)
			(layer "F.Fab")
		)
		(pad "1" smd custom
			(at 0 -0.4445 270)
			(size 0.1524 0.1524)
			(layers "F.Cu" "F.Mask" "F.Paste")
			(net "P1V8_STBY_CC_R")
			(options
				(clearance outline)
				(anchor circle)
			)
			(primitives
				(gr_poly
					(pts
						(arc
							(start 0.3048 -0.2032)
							(mid 0.275042 -0.275042)
							(end 0.2032 -0.3048)
						)
						(arc
							(start -0.2032 -0.3048)
							(mid -0.275042 -0.275042)
							(end -0.3048 -0.2032)
						)
						(arc
							(start -0.3048 0.2032)
							(mid -0.275042 0.275042)
							(end -0.2032 0.3048)
						)
						(arc
							(start 0.2032 0.3048)
							(mid 0.275042 0.275042)
							(end 0.3048 0.2032)
						)
					)
					(width 0)
					(fill yes)
				)
			)
		)
		(pad "2" smd custom
			(at 0 0.4445 270)
			(size 0.1524 0.1524)
			(layers "F.Cu" "F.Mask" "F.Paste")
			(net "P1V8_STBY_VFB")
			(options
				(clearance outline)
				(anchor circle)
			)
			(primitives
				(gr_poly
					(pts
						(arc
							(start 0.3048 -0.2032)
							(mid 0.275042 -0.275042)
							(end 0.2032 -0.3048)
						)
						(arc
							(start -0.2032 -0.3048)
							(mid -0.275042 -0.275042)
							(end -0.3048 -0.2032)
						)
						(arc
							(start -0.3048 0.2032)
							(mid -0.275042 0.275042)
							(end -0.2032 0.3048)
						)
						(arc
							(start 0.2032 0.3048)
							(mid 0.275042 0.275042)
							(end 0.3048 0.2032)
						)
					)
					(width 0)
					(fill yes)
				)
			)
		)
	)
	(footprint ""
		(layer "F.Cu")
		(at 208.055972 -70.0024 90)
		(property "Reference" "C315"
			(at 0 0 90)
			(layer "F.SilkS")
			(hide yes)
			(effects
				(font
					(size 1.27 1.27)
				)
			)
		)
		(property "Value" "SCD01U16V1KX-GP"
			(at -2.8321 -1.7399 90)
			(unlocked yes)
			(layer "F.Fab")
			(hide yes)
			(effects
				(font
					(size 1.016 1.016)
					(thickness 0.1524)
				)
			)
		)
		(property "Device Type" "C0201H13"
			(at -2.8321 -3.2639 90)
			(unlocked yes)
			(layer "F.Fab")
			(hide yes)
			(effects
				(font
					(size 1.016 1.016)
					(thickness 0.1524)
				)
			)
		)
		(duplicate_pad_numbers_are_jumpers no)
		(fp_rect
			(start -0.2794 0.6477)
			(end 0.2794 -0.6477)
			(stroke
				(width 0)
				(type default)
			)
			(fill no)
			(layer "F.CrtYd")
		)
		(fp_rect
			(start -0.2794 0.6477)
			(end 0.2794 -0.6477)
			(stroke
				(width 0)
				(type default)
			)
			(fill no)
			(layer "F.Fab")
		)
		(pad "1" smd custom
			(at 0 -0.2794 90)
			(size 0.0762 0.0762)
			(layers "F.Cu" "F.Mask" "F.Paste")
			(net "PHY_IOC_TO_CON_B_0_DP_C")
			(options
				(clearance outline)
				(anchor circle)
			)
			(primitives
				(gr_poly
					(pts
						(arc
							(start 0.1524 -0.127)
							(mid 0.137521 -0.162921)
							(end 0.1016 -0.1778)
						)
						(arc
							(start -0.1016 -0.1778)
							(mid -0.137521 -0.162921)
							(end -0.1524 -0.127)
						)
						(arc
							(start -0.1524 0.127)
							(mid -0.137521 0.162921)
							(end -0.1016 0.1778)
						)
						(arc
							(start 0.1016 0.1778)
							(mid 0.137521 0.162921)
							(end 0.1524 0.127)
						)
					)
					(width 0)
					(fill yes)
				)
			)
		)
		(pad "2" smd custom
			(at 0 0.2794 90)
			(size 0.0762 0.0762)
			(layers "F.Cu" "F.Mask" "F.Paste")
			(net "PHY_IOC_TO_CON_B_0_DP")
			(options
				(clearance outline)
				(anchor circle)
			)
			(primitives
				(gr_poly
					(pts
						(arc
							(start 0.1524 -0.127)
							(mid 0.137521 -0.162921)
							(end 0.1016 -0.1778)
						)
						(arc
							(start -0.1016 -0.1778)
							(mid -0.137521 -0.162921)
							(end -0.1524 -0.127)
						)
						(arc
							(start -0.1524 0.127)
							(mid -0.137521 0.162921)
							(end -0.1016 0.1778)
						)
						(arc
							(start 0.1016 0.1778)
							(mid 0.137521 0.162921)
							(end 0.1524 0.127)
						)
					)
					(width 0)
					(fill yes)
				)
			)
		)
	)
	(footprint ""
		(layer "F.Cu")
		(at 198.247 -48.387)
		(property "Reference" "TP138"
			(at 0 0 0)
			(layer "F.SilkS")
			(hide yes)
			(effects
				(font
					(size 1.27 1.27)
				)
			)
		)
		(property "Value" "TPAD28-2-GP"
			(at -0.0127 -1.6637 0)
			(unlocked yes)
			(layer "F.Fab")
			(hide yes)
			(effects
				(font
					(size 1.016 1.016)
					(thickness 0.1524)
				)
			)
		)
		(property "Device Type" "TPAD28"
			(at -0.0127 -3.1877 0)
			(unlocked yes)
			(layer "F.Fab")
			(hide yes)
			(effects
				(font
					(size 1.016 1.016)
					(thickness 0.1524)
				)
			)
		)
		(duplicate_pad_numbers_are_jumpers no)
		(fp_poly
			(pts
				(arc
					(start 0.3556 0)
					(mid -0.3556 0)
					(end 0.3556 0)
				)
			)
			(stroke
				(width 0)
				(type default)
			)
			(fill no)
			(layer "F.CrtYd")
		)
		(fp_poly
			(pts
				(arc
					(start 0.6096 0)
					(mid -0.6096 0)
					(end 0.6096 0)
				)
			)
			(stroke
				(width 0)
				(type default)
			)
			(fill no)
			(layer "F.Fab")
		)
		(pad "1" smd circle
			(at 0 0)
			(size 0.7112 0.7112)
			(layers "F.Cu" "F.Mask" "F.Paste")
			(net "ICE0_TDO")
		)
	)
	(footprint ""
		(layer "F.Cu")
		(at 199.200516 -130.6449 90)
		(property "Reference" "R549"
			(at 0 0 90)
			(layer "F.SilkS")
			(hide yes)
			(effects
				(font
					(size 1.27 1.27)
				)
			)
		)
		(property "Value" "0R2J-2-GP"
			(at 0.064008 -3.993896 90)
			(unlocked yes)
			(layer "F.Fab")
			(hide yes)
			(effects
				(font
					(size 1.016 1.016)
					(thickness 0.1524)
				)
			)
		)
		(property "Device Type" "R402H16"
			(at 0.064008 -5.517896 90)
			(unlocked yes)
			(layer "F.Fab")
			(hide yes)
			(effects
				(font
					(size 1.016 1.016)
					(thickness 0.1524)
				)
			)
		)
		(duplicate_pad_numbers_are_jumpers no)
		(fp_line
			(start 0.508 -0.9398)
			(end -0.508 -0.9398)
			(stroke
				(width 0.1524)
				(type default)
			)
			(layer "F.SilkS")
		)
		(fp_line
			(start -0.508 -0.9398)
			(end -0.508 0.9398)
			(stroke
				(width 0.1524)
				(type default)
			)
			(layer "F.SilkS")
		)
		(fp_rect
			(start -0.508 0.9398)
			(end 0.508 -0.9398)
			(stroke
				(width 0)
				(type default)
			)
			(fill no)
			(layer "F.CrtYd")
		)
		(fp_rect
			(start -0.508 0.9398)
			(end 0.508 -0.9398)
			(stroke
				(width 0)
				(type default)
			)
			(fill no)
			(layer "F.Fab")
		)
		(pad "1" smd custom
			(at 0 -0.4445 90)
			(size 0.1397 0.1397)
			(layers "F.Cu" "F.Mask" "F.Paste")
			(net "PWRGD_P1V8")
			(options
				(clearance outline)
				(anchor circle)
			)
			(primitives
				(gr_poly
					(pts
						(arc
							(start -0.1778 -0.2794)
							(mid -0.249642 -0.249642)
							(end -0.2794 -0.1778)
						)
						(arc
							(start -0.2794 0.1778)
							(mid -0.249642 0.249642)
							(end -0.1778 0.2794)
						)
						(arc
							(start 0.1778 0.2794)
							(mid 0.249642 0.249642)
							(end 0.2794 0.1778)
						)
						(arc
							(start 0.2794 -0.1778)
							(mid 0.249642 -0.249642)
							(end 0.1778 -0.2794)
						)
					)
					(width 0)
					(fill yes)
				)
			)
		)
		(pad "2" smd custom
			(at 0 0.4445 90)
			(size 0.1397 0.1397)
			(layers "F.Cu" "F.Mask" "F.Paste")
			(net "TPS74801_1V5_EN")
			(options
				(clearance outline)
				(anchor circle)
			)
			(primitives
				(gr_poly
					(pts
						(arc
							(start -0.1778 -0.2794)
							(mid -0.249642 -0.249642)
							(end -0.2794 -0.1778)
						)
						(arc
							(start -0.2794 0.1778)
							(mid -0.249642 0.249642)
							(end -0.1778 0.2794)
						)
						(arc
							(start 0.1778 0.2794)
							(mid 0.249642 0.249642)
							(end 0.2794 0.1778)
						)
						(arc
							(start 0.2794 -0.1778)
							(mid 0.249642 -0.249642)
							(end 0.1778 -0.2794)
						)
					)
					(width 0)
					(fill yes)
				)
			)
		)
	)
	(footprint ""
		(layer "F.Cu")
		(at 174.4345 -120.239536 90)
		(property "Reference" "PQ4"
			(at 0 0 90)
			(layer "F.SilkS")
			(hide yes)
			(effects
				(font
					(size 1.27 1.27)
				)
			)
		)
		(property "Value" "2N7002K-1-GP"
			(at 0.127 -8.9662 90)
			(unlocked yes)
			(layer "F.Fab")
			(hide yes)
			(effects
				(font
					(size 1.016 1.016)
					(thickness 0.1524)
				)
			)
		)
		(property "Device Type" "SOT23DGS2D4H44"
			(at 0.127 -10.4902 90)
			(unlocked yes)
			(layer "F.Fab")
			(hide yes)
			(effects
				(font
					(size 1.016 1.016)
					(thickness 0.1524)
				)
			)
		)
		(duplicate_pad_numbers_are_jumpers no)
		(fp_line
			(start 1.651 -1.778)
			(end -1.651 -1.778)
			(stroke
				(width 0.1524)
				(type default)
			)
			(layer "F.SilkS")
		)
		(fp_line
			(start -1.651 -1.778)
			(end -1.651 1.778)
			(stroke
				(width 0.1524)
				(type default)
			)
			(layer "F.SilkS")
		)
		(fp_line
			(start 1.651 1.778)
			(end 1.651 -1.778)
			(stroke
				(width 0.1524)
				(type default)
			)
			(layer "F.SilkS")
		)
		(fp_line
			(start -1.651 1.778)
			(end 1.651 1.778)
			(stroke
				(width 0.1524)
				(type default)
			)
			(layer "F.SilkS")
		)
		(fp_poly
			(pts
				(xy -1.778 1.8796) (xy -1.778 -1.8796) (xy 1.778 -1.8796) (xy 1.778 1.8796)
			)
			(stroke
				(width 0)
				(type default)
			)
			(fill no)
			(layer "F.CrtYd")
		)
		(fp_poly
			(pts
				(xy -1.778 1.8796) (xy -1.778 -1.8796) (xy 1.778 -1.8796) (xy 1.778 1.8796)
			)
			(stroke
				(width 0)
				(type default)
			)
			(fill no)
			(layer "F.Fab")
		)
		(pad "D" smd custom
			(at 0 -0.9525 90)
			(size 0.1905 0.1905)
			(layers "F.Cu" "F.Mask" "F.Paste")
			(net "PQ4_D")
			(options
				(clearance outline)
				(anchor circle)
			)
			(primitives
				(gr_poly
					(pts
						(arc
							(start -0.1778 0.5715)
							(mid -0.321484 0.511984)
							(end -0.381 0.3683)
						)
						(arc
							(start -0.381 -0.3683)
							(mid -0.321484 -0.511984)
							(end -0.1778 -0.5715)
						)
						(arc
							(start 0.1778 -0.5715)
							(mid 0.321484 -0.511984)
							(end 0.381 -0.3683)
						)
						(arc
							(start 0.381 0.3683)
							(mid 0.321484 0.511984)
							(end 0.1778 0.5715)
						)
					)
					(width 0)
					(fill yes)
				)
			)
		)
		(pad "G" smd custom
			(at -0.98425 0.9525 90)
			(size 0.1905 0.1905)
			(layers "F.Cu" "F.Mask" "F.Paste")
			(net "PQ4_G")
			(options
				(clearance outline)
				(anchor circle)
			)
			(primitives
				(gr_poly
					(pts
						(arc
							(start -0.1778 0.5715)
							(mid -0.321484 0.511984)
							(end -0.381 0.3683)
						)
						(arc
							(start -0.381 -0.3683)
							(mid -0.321484 -0.511984)
							(end -0.1778 -0.5715)
						)
						(arc
							(start 0.1778 -0.5715)
							(mid 0.321484 -0.511984)
							(end 0.381 -0.3683)
						)
						(arc
							(start 0.381 0.3683)
							(mid 0.321484 0.511984)
							(end 0.1778 0.5715)
						)
					)
					(width 0)
					(fill yes)
				)
			)
		)
		(pad "S" smd custom
			(at 0.98425 0.9525 90)
			(size 0.1905 0.1905)
			(layers "F.Cu" "F.Mask" "F.Paste")
			(net "P1V8_EN")
			(options
				(clearance outline)
				(anchor circle)
			)
			(primitives
				(gr_poly
					(pts
						(arc
							(start -0.1778 0.5715)
							(mid -0.321484 0.511984)
							(end -0.381 0.3683)
						)
						(arc
							(start -0.381 -0.3683)
							(mid -0.321484 -0.511984)
							(end -0.1778 -0.5715)
						)
						(arc
							(start 0.1778 -0.5715)
							(mid 0.321484 -0.511984)
							(end 0.381 -0.3683)
						)
						(arc
							(start 0.381 0.3683)
							(mid 0.321484 0.511984)
							(end 0.1778 0.5715)
						)
					)
					(width 0)
					(fill yes)
				)
			)
		)
	)
	(footprint ""
		(layer "F.Cu")
		(at 176.784 -79.0194)
		(property "Reference" "TP90"
			(at 0 0 0)
			(layer "F.SilkS")
			(hide yes)
			(effects
				(font
					(size 1.27 1.27)
				)
			)
		)
		(property "Value" "TPAD28-2-GP"
			(at -0.0127 -1.6637 0)
			(unlocked yes)
			(layer "F.Fab")
			(hide yes)
			(effects
				(font
					(size 1.016 1.016)
					(thickness 0.1524)
				)
			)
		)
		(property "Device Type" "TPAD28"
			(at -0.0127 -3.1877 0)
			(unlocked yes)
			(layer "F.Fab")
			(hide yes)
			(effects
				(font
					(size 1.016 1.016)
					(thickness 0.1524)
				)
			)
		)
		(duplicate_pad_numbers_are_jumpers no)
		(fp_poly
			(pts
				(arc
					(start 0.3556 0)
					(mid -0.3556 0)
					(end 0.3556 0)
				)
			)
			(stroke
				(width 0)
				(type default)
			)
			(fill no)
			(layer "F.CrtYd")
		)
		(fp_poly
			(pts
				(arc
					(start 0.6096 0)
					(mid -0.6096 0)
					(end 0.6096 0)
				)
			)
			(stroke
				(width 0)
				(type default)
			)
			(fill no)
			(layer "F.Fab")
		)
		(pad "1" smd circle
			(at 0 0)
			(size 0.7112 0.7112)
			(layers "F.Cu" "F.Mask" "F.Paste")
			(net "IOC_GPIO_4")
		)
	)
	(footprint ""
		(layer "F.Cu")
		(at 168.6306 -106.0704 -90)
		(property "Reference" "C463"
			(at 0 0 270)
			(layer "F.SilkS")
			(hide yes)
			(effects
				(font
					(size 1.27 1.27)
				)
			)
		)
		(property "Value" "SC1U16V2KX-7-GP"
			(at 1.7526 -1.6002 270)
			(unlocked yes)
			(layer "F.Fab")
			(hide yes)
			(effects
				(font
					(size 1.016 1.016)
					(thickness 0.1524)
				)
			)
		)
		(property "Device Type" "C402-TO0D2H24"
			(at 1.7526 -3.1242 270)
			(unlocked yes)
			(layer "F.Fab")
			(hide yes)
			(effects
				(font
					(size 1.016 1.016)
					(thickness 0.1524)
				)
			)
		)
		(duplicate_pad_numbers_are_jumpers no)
		(fp_rect
			(start -0.4826 0.889)
			(end 0.4826 -0.889)
			(stroke
				(width 0)
				(type default)
			)
			(fill no)
			(layer "F.CrtYd")
		)
		(fp_rect
			(start -0.4826 0.889)
			(end 0.4826 -0.889)
			(stroke
				(width 0)
				(type default)
			)
			(fill no)
			(layer "F.Fab")
		)
		(pad "1" smd custom
			(at 0 -0.4572 270)
			(size 0.1524 0.1524)
			(layers "F.Cu" "F.Mask" "F.Paste")
			(net "P1V8")
			(options
				(clearance outline)
				(anchor circle)
			)
			(primitives
				(gr_poly
					(pts
						(arc
							(start -0.254 0.3048)
							(mid -0.325842 0.275042)
							(end -0.3556 0.2032)
						)
						(arc
							(start -0.3556 -0.2032)
							(mid -0.325842 -0.275042)
							(end -0.254 -0.3048)
						)
						(arc
							(start 0.254 -0.3048)
							(mid 0.325842 -0.275042)
							(end 0.3556 -0.2032)
						)
						(arc
							(start 0.3556 0.2032)
							(mid 0.325842 0.275042)
							(end 0.254 0.3048)
						)
					)
					(width 0)
					(fill yes)
				)
			)
		)
		(pad "2" smd custom
			(at 0 0.4572 270)
			(size 0.1524 0.1524)
			(layers "F.Cu" "F.Mask" "F.Paste")
			(net "GND")
			(options
				(clearance outline)
				(anchor circle)
			)
			(primitives
				(gr_poly
					(pts
						(arc
							(start -0.254 0.3048)
							(mid -0.325842 0.275042)
							(end -0.3556 0.2032)
						)
						(arc
							(start -0.3556 -0.2032)
							(mid -0.325842 -0.275042)
							(end -0.254 -0.3048)
						)
						(arc
							(start 0.254 -0.3048)
							(mid 0.325842 -0.275042)
							(end 0.3556 -0.2032)
						)
						(arc
							(start 0.3556 0.2032)
							(mid 0.325842 0.275042)
							(end 0.254 0.3048)
						)
					)
					(width 0)
					(fill yes)
				)
			)
		)
	)
	(footprint ""
		(layer "F.Cu")
		(at 209.876136 -127.9398)
		(property "Reference" "C254"
			(at 0 0 0)
			(layer "F.SilkS")
			(hide yes)
			(effects
				(font
					(size 1.27 1.27)
				)
			)
		)
		(property "Value" "SCD1U16V2KX-3GP"
			(at 1.1811 -2.7051 0)
			(unlocked yes)
			(layer "F.Fab")
			(hide yes)
			(effects
				(font
					(size 1.016 1.016)
					(thickness 0.1524)
				)
			)
		)
		(property "Device Type" "C402H22"
			(at 1.1811 -4.2291 0)
			(unlocked yes)
			(layer "F.Fab")
			(hide yes)
			(effects
				(font
					(size 1.016 1.016)
					(thickness 0.1524)
				)
			)
		)
		(duplicate_pad_numbers_are_jumpers no)
		(fp_rect
			(start -0.4318 0.9525)
			(end 0.4318 -0.9525)
			(stroke
				(width 0)
				(type default)
			)
			(fill no)
			(layer "F.CrtYd")
		)
		(fp_rect
			(start -0.4318 0.9525)
			(end 0.4318 -0.9525)
			(stroke
				(width 0)
				(type default)
			)
			(fill no)
			(layer "F.Fab")
		)
		(pad "1" smd custom
			(at 0 -0.4445)
			(size 0.1524 0.1524)
			(layers "F.Cu" "F.Mask" "F.Paste")
			(net "P1V8_STBY")
			(options
				(clearance outline)
				(anchor circle)
			)
			(primitives
				(gr_poly
					(pts
						(arc
							(start 0.3048 -0.2032)
							(mid 0.275042 -0.275042)
							(end 0.2032 -0.3048)
						)
						(arc
							(start -0.2032 -0.3048)
							(mid -0.275042 -0.275042)
							(end -0.3048 -0.2032)
						)
						(arc
							(start -0.3048 0.2032)
							(mid -0.275042 0.275042)
							(end -0.2032 0.3048)
						)
						(arc
							(start 0.2032 0.3048)
							(mid 0.275042 0.275042)
							(end 0.3048 0.2032)
						)
					)
					(width 0)
					(fill yes)
				)
			)
		)
		(pad "2" smd custom
			(at 0 0.4445)
			(size 0.1524 0.1524)
			(layers "F.Cu" "F.Mask" "F.Paste")
			(net "GND")
			(options
				(clearance outline)
				(anchor circle)
			)
			(primitives
				(gr_poly
					(pts
						(arc
							(start 0.3048 -0.2032)
							(mid 0.275042 -0.275042)
							(end 0.2032 -0.3048)
						)
						(arc
							(start -0.2032 -0.3048)
							(mid -0.275042 -0.275042)
							(end -0.3048 -0.2032)
						)
						(arc
							(start -0.3048 0.2032)
							(mid -0.275042 0.275042)
							(end -0.2032 0.3048)
						)
						(arc
							(start 0.2032 0.3048)
							(mid 0.275042 0.275042)
							(end 0.3048 0.2032)
						)
					)
					(width 0)
					(fill yes)
				)
			)
		)
	)
	(footprint ""
		(layer "F.Cu")
		(at 33.693354 -186.99861)
		(property "Reference" "R490"
			(at 0 0 0)
			(layer "F.SilkS")
			(hide yes)
			(effects
				(font
					(size 1.27 1.27)
				)
			)
		)
		(property "Value" "3D01R5F-GP"
			(at 0 -8.9535 0)
			(unlocked yes)
			(layer "F.Fab")
			(hide yes)
			(effects
				(font
					(size 1.27 1.016)
					(thickness 0.1524)
				)
			)
		)
		(property "Device Type" "R805H24"
			(at 0 -10.6299 0)
			(unlocked yes)
			(layer "F.Fab")
			(hide yes)
			(effects
				(font
					(size 1.27 1.016)
					(thickness 0.1524)
				)
			)
		)
		(duplicate_pad_numbers_are_jumpers no)
		(fp_line
			(start -0.889 -1.7018)
			(end -0.889 0.2794)
			(stroke
				(width 0.1524)
				(type default)
			)
			(layer "F.SilkS")
		)
		(fp_line
			(start -0.889 0.0762)
			(end -0.889 1.7018)
			(stroke
				(width 0.1524)
				(type default)
			)
			(layer "F.SilkS")
		)
		(fp_line
			(start -0.889 1.7018)
			(end 0.889 1.7018)
			(stroke
				(width 0.1524)
				(type default)
			)
			(layer "F.SilkS")
		)
		(fp_line
			(start 0.889 -1.7018)
			(end -0.889 -1.7018)
			(stroke
				(width 0.1524)
				(type default)
			)
			(layer "F.SilkS")
		)
		(fp_line
			(start 0.889 -1.7018)
			(end 0.889 -0.381)
			(stroke
				(width 0.1524)
				(type default)
			)
			(layer "F.SilkS")
		)
		(fp_line
			(start 0.889 1.7018)
			(end 0.889 -0.508)
			(stroke
				(width 0.1524)
				(type default)
			)
			(layer "F.SilkS")
		)
		(fp_poly
			(pts
				(xy 0.9652 -1.778) (xy 0.9652 1.778) (xy -0.9652 1.778) (xy -0.9652 -1.778)
			)
			(stroke
				(width 0)
				(type default)
			)
			(fill no)
			(layer "F.CrtYd")
		)
		(fp_rect
			(start -0.9652 1.778)
			(end 0.9652 -1.778)
			(stroke
				(width 0)
				(type default)
			)
			(fill no)
			(layer "F.Fab")
		)
		(pad "1" smd rect
			(at 0 -0.9652)
			(size 1.397 1.143)
			(layers "F.Cu" "F.Mask" "F.Paste")
			(net "P3V3_SNB")
		)
		(pad "2" smd rect
			(at 0 0.9652)
			(size 1.397 1.143)
			(layers "F.Cu" "F.Mask" "F.Paste")
			(net "GND")
		)
	)
	(footprint ""
		(layer "F.Cu")
		(at 94.488 -28.194 90)
		(property "Reference" "C2"
			(at 0 0 90)
			(layer "F.SilkS")
			(hide yes)
			(effects
				(font
					(size 1.27 1.27)
				)
			)
		)
		(property "Value" "SC1U16V3KX-5GP"
			(at 0 -2.8194 90)
			(unlocked yes)
			(layer "F.Fab")
			(hide yes)
			(effects
				(font
					(size 1.016 1.016)
					(thickness 0.1524)
				)
			)
		)
		(property "Device Type" "C603H36"
			(at 0 -4.3434 90)
			(unlocked yes)
			(layer "F.Fab")
			(hide yes)
			(effects
				(font
					(size 1.016 1.016)
					(thickness 0.1524)
				)
			)
		)
		(duplicate_pad_numbers_are_jumpers no)
		(fp_line
			(start 0.508 0)
			(end -0.508 0)
			(stroke
				(width 0.2032)
				(type default)
			)
			(layer "F.SilkS")
		)
		(fp_rect
			(start -0.5842 1.3335)
			(end 0.5842 -1.3335)
			(stroke
				(width 0)
				(type default)
			)
			(fill no)
			(layer "F.CrtYd")
		)
		(fp_rect
			(start -0.5842 1.3335)
			(end 0.5842 -1.3335)
			(stroke
				(width 0)
				(type default)
			)
			(fill no)
			(layer "F.Fab")
		)
		(pad "1" smd custom
			(at 0 -0.762 90)
			(size 0.2159 0.2159)
			(layers "F.Cu" "F.Mask" "F.Paste")
			(net "P5V_USB")
			(options
				(clearance outline)
				(anchor circle)
			)
			(primitives
				(gr_poly
					(pts
						(arc
							(start -0.3302 -0.4318)
							(mid -0.402042 -0.402042)
							(end -0.4318 -0.3302)
						)
						(arc
							(start -0.4318 0.3302)
							(mid -0.402042 0.402042)
							(end -0.3302 0.4318)
						)
						(arc
							(start 0.3302 0.4318)
							(mid 0.402042 0.402042)
							(end 0.4318 0.3302)
						)
						(arc
							(start 0.4318 -0.3302)
							(mid 0.402042 -0.402042)
							(end 0.3302 -0.4318)
						)
					)
					(width 0)
					(fill yes)
				)
			)
		)
		(pad "2" smd custom
			(at 0 0.762 90)
			(size 0.2159 0.2159)
			(layers "F.Cu" "F.Mask" "F.Paste")
			(net "GND")
			(options
				(clearance outline)
				(anchor circle)
			)
			(primitives
				(gr_poly
					(pts
						(arc
							(start -0.3302 -0.4318)
							(mid -0.402042 -0.402042)
							(end -0.4318 -0.3302)
						)
						(arc
							(start -0.4318 0.3302)
							(mid -0.402042 0.402042)
							(end -0.3302 0.4318)
						)
						(arc
							(start 0.3302 0.4318)
							(mid 0.402042 0.402042)
							(end 0.4318 0.3302)
						)
						(arc
							(start 0.4318 -0.3302)
							(mid 0.402042 -0.402042)
							(end 0.3302 -0.4318)
						)
					)
					(width 0)
					(fill yes)
				)
			)
		)
	)
	(footprint ""
		(layer "F.Cu")
		(at 74.0918 -185.9026)
		(property "Reference" "R507"
			(at 0 0 0)
			(layer "F.SilkS")
			(hide yes)
			(effects
				(font
					(size 1.27 1.27)
				)
			)
		)
		(property "Value" "10KR2F-2-GP"
			(at 0.064008 -3.993896 0)
			(unlocked yes)
			(layer "F.Fab")
			(hide yes)
			(effects
				(font
					(size 1.016 1.016)
					(thickness 0.1524)
				)
			)
		)
		(property "Device Type" "R402H16"
			(at 0.064008 -5.517896 0)
			(unlocked yes)
			(layer "F.Fab")
			(hide yes)
			(effects
				(font
					(size 1.016 1.016)
					(thickness 0.1524)
				)
			)
		)
		(duplicate_pad_numbers_are_jumpers no)
		(fp_line
			(start -0.508 -0.9398)
			(end -0.508 0.9398)
			(stroke
				(width 0.1524)
				(type default)
			)
			(layer "F.SilkS")
		)
		(fp_line
			(start 0.508 -0.9398)
			(end -0.508 -0.9398)
			(stroke
				(width 0.1524)
				(type default)
			)
			(layer "F.SilkS")
		)
		(fp_rect
			(start -0.508 0.9398)
			(end 0.508 -0.9398)
			(stroke
				(width 0)
				(type default)
			)
			(fill no)
			(layer "F.CrtYd")
		)
		(fp_rect
			(start -0.508 0.9398)
			(end 0.508 -0.9398)
			(stroke
				(width 0)
				(type default)
			)
			(fill no)
			(layer "F.Fab")
		)
		(pad "1" smd custom
			(at 0 -0.4445)
			(size 0.1397 0.1397)
			(layers "F.Cu" "F.Mask" "F.Paste")
			(net "P3V3_STBY")
			(options
				(clearance outline)
				(anchor circle)
			)
			(primitives
				(gr_poly
					(pts
						(arc
							(start -0.1778 -0.2794)
							(mid -0.249642 -0.249642)
							(end -0.2794 -0.1778)
						)
						(arc
							(start -0.2794 0.1778)
							(mid -0.249642 0.249642)
							(end -0.1778 0.2794)
						)
						(arc
							(start 0.1778 0.2794)
							(mid 0.249642 0.249642)
							(end 0.2794 0.1778)
						)
						(arc
							(start 0.2794 -0.1778)
							(mid 0.249642 -0.249642)
							(end 0.1778 -0.2794)
						)
					)
					(width 0)
					(fill yes)
				)
			)
		)
		(pad "2" smd custom
			(at 0 0.4445)
			(size 0.1397 0.1397)
			(layers "F.Cu" "F.Mask" "F.Paste")
			(net "PWRGD_P2V5_STBY")
			(options
				(clearance outline)
				(anchor circle)
			)
			(primitives
				(gr_poly
					(pts
						(arc
							(start -0.1778 -0.2794)
							(mid -0.249642 -0.249642)
							(end -0.2794 -0.1778)
						)
						(arc
							(start -0.2794 0.1778)
							(mid -0.249642 0.249642)
							(end -0.1778 0.2794)
						)
						(arc
							(start 0.1778 0.2794)
							(mid 0.249642 0.249642)
							(end 0.2794 0.1778)
						)
						(arc
							(start 0.2794 -0.1778)
							(mid 0.249642 -0.249642)
							(end 0.1778 -0.2794)
						)
					)
					(width 0)
					(fill yes)
				)
			)
		)
	)
	(footprint ""
		(layer "F.Cu")
		(at 132.5372 -13.1064)
		(property "Reference" "C134"
			(at 0 0 0)
			(layer "F.SilkS")
			(hide yes)
			(effects
				(font
					(size 1.27 1.27)
				)
			)
		)
		(property "Value" "SCD015U25V2KX-GP"
			(at 1.1811 -2.7051 0)
			(unlocked yes)
			(layer "F.Fab")
			(hide yes)
			(effects
				(font
					(size 1.016 1.016)
					(thickness 0.1524)
				)
			)
		)
		(property "Device Type" "C402H22"
			(at 1.1811 -4.2291 0)
			(unlocked yes)
			(layer "F.Fab")
			(hide yes)
			(effects
				(font
					(size 1.016 1.016)
					(thickness 0.1524)
				)
			)
		)
		(duplicate_pad_numbers_are_jumpers no)
		(fp_rect
			(start -0.4318 0.9525)
			(end 0.4318 -0.9525)
			(stroke
				(width 0)
				(type default)
			)
			(fill no)
			(layer "F.CrtYd")
		)
		(fp_rect
			(start -0.4318 0.9525)
			(end 0.4318 -0.9525)
			(stroke
				(width 0)
				(type default)
			)
			(fill no)
			(layer "F.Fab")
		)
		(pad "1" smd custom
			(at 0 -0.4445)
			(size 0.1524 0.1524)
			(layers "F.Cu" "F.Mask" "F.Paste")
			(net "ADM1278_HS_P")
			(options
				(clearance outline)
				(anchor circle)
			)
			(primitives
				(gr_poly
					(pts
						(arc
							(start 0.3048 -0.2032)
							(mid 0.275042 -0.275042)
							(end 0.2032 -0.3048)
						)
						(arc
							(start -0.2032 -0.3048)
							(mid -0.275042 -0.275042)
							(end -0.3048 -0.2032)
						)
						(arc
							(start -0.3048 0.2032)
							(mid -0.275042 0.275042)
							(end -0.2032 0.3048)
						)
						(arc
							(start 0.2032 0.3048)
							(mid 0.275042 0.275042)
							(end 0.3048 0.2032)
						)
					)
					(width 0)
					(fill yes)
				)
			)
		)
		(pad "2" smd custom
			(at 0 0.4445)
			(size 0.1524 0.1524)
			(layers "F.Cu" "F.Mask" "F.Paste")
			(net "ADM1278_HS_N")
			(options
				(clearance outline)
				(anchor circle)
			)
			(primitives
				(gr_poly
					(pts
						(arc
							(start 0.3048 -0.2032)
							(mid 0.275042 -0.275042)
							(end 0.2032 -0.3048)
						)
						(arc
							(start -0.2032 -0.3048)
							(mid -0.275042 -0.275042)
							(end -0.3048 -0.2032)
						)
						(arc
							(start -0.3048 0.2032)
							(mid -0.275042 0.275042)
							(end -0.2032 0.3048)
						)
						(arc
							(start 0.2032 0.3048)
							(mid 0.275042 0.275042)
							(end 0.3048 0.2032)
						)
					)
					(width 0)
					(fill yes)
				)
			)
		)
	)
	(footprint ""
		(layer "F.Cu")
		(at 61.28258 -141.391132 -90)
		(property "Reference" "R176"
			(at 0 0 270)
			(layer "F.SilkS")
			(hide yes)
			(effects
				(font
					(size 1.27 1.27)
				)
			)
		)
		(property "Value" "0R2J-2-GP"
			(at 0.064008 -3.993896 270)
			(unlocked yes)
			(layer "F.Fab")
			(hide yes)
			(effects
				(font
					(size 1.016 1.016)
					(thickness 0.1524)
				)
			)
		)
		(property "Device Type" "R402H16"
			(at 0.064008 -5.517896 270)
			(unlocked yes)
			(layer "F.Fab")
			(hide yes)
			(effects
				(font
					(size 1.016 1.016)
					(thickness 0.1524)
				)
			)
		)
		(duplicate_pad_numbers_are_jumpers no)
		(fp_line
			(start -0.508 -0.9398)
			(end -0.508 0.9398)
			(stroke
				(width 0.1524)
				(type default)
			)
			(layer "F.SilkS")
		)
		(fp_line
			(start 0.508 -0.9398)
			(end -0.508 -0.9398)
			(stroke
				(width 0.1524)
				(type default)
			)
			(layer "F.SilkS")
		)
		(fp_rect
			(start -0.508 0.9398)
			(end 0.508 -0.9398)
			(stroke
				(width 0)
				(type default)
			)
			(fill no)
			(layer "F.CrtYd")
		)
		(fp_rect
			(start -0.508 0.9398)
			(end 0.508 -0.9398)
			(stroke
				(width 0)
				(type default)
			)
			(fill no)
			(layer "F.Fab")
		)
		(pad "1" smd custom
			(at 0 -0.4445 270)
			(size 0.1397 0.1397)
			(layers "F.Cu" "F.Mask" "F.Paste")
			(net "I2C_M2_2_SDA")
			(options
				(clearance outline)
				(anchor circle)
			)
			(primitives
				(gr_poly
					(pts
						(arc
							(start -0.1778 -0.2794)
							(mid -0.249642 -0.249642)
							(end -0.2794 -0.1778)
						)
						(arc
							(start -0.2794 0.1778)
							(mid -0.249642 0.249642)
							(end -0.1778 0.2794)
						)
						(arc
							(start 0.1778 0.2794)
							(mid 0.249642 0.249642)
							(end 0.2794 0.1778)
						)
						(arc
							(start 0.2794 -0.1778)
							(mid 0.249642 -0.249642)
							(end 0.1778 -0.2794)
						)
					)
					(width 0)
					(fill yes)
				)
			)
		)
		(pad "2" smd custom
			(at 0 0.4445 270)
			(size 0.1397 0.1397)
			(layers "F.Cu" "F.Mask" "F.Paste")
			(net "BMC_SMB9_DAT")
			(options
				(clearance outline)
				(anchor circle)
			)
			(primitives
				(gr_poly
					(pts
						(arc
							(start -0.1778 -0.2794)
							(mid -0.249642 -0.249642)
							(end -0.2794 -0.1778)
						)
						(arc
							(start -0.2794 0.1778)
							(mid -0.249642 0.249642)
							(end -0.1778 0.2794)
						)
						(arc
							(start 0.1778 0.2794)
							(mid 0.249642 0.249642)
							(end 0.2794 0.1778)
						)
						(arc
							(start 0.2794 -0.1778)
							(mid 0.249642 -0.249642)
							(end 0.1778 -0.2794)
						)
					)
					(width 0)
					(fill yes)
				)
			)
		)
	)
	(footprint ""
		(layer "F.Cu")
		(at 43.9166 -157.9118)
		(property "Reference" "R174"
			(at 0 0 0)
			(layer "F.SilkS")
			(hide yes)
			(effects
				(font
					(size 1.27 1.27)
				)
			)
		)
		(property "Value" "0R2J-2-GP"
			(at 0.064008 -3.993896 0)
			(unlocked yes)
			(layer "F.Fab")
			(hide yes)
			(effects
				(font
					(size 1.016 1.016)
					(thickness 0.1524)
				)
			)
		)
		(property "Device Type" "R402H16"
			(at 0.064008 -5.517896 0)
			(unlocked yes)
			(layer "F.Fab")
			(hide yes)
			(effects
				(font
					(size 1.016 1.016)
					(thickness 0.1524)
				)
			)
		)
		(duplicate_pad_numbers_are_jumpers no)
		(fp_line
			(start -0.508 -0.9398)
			(end -0.508 0.9398)
			(stroke
				(width 0.1524)
				(type default)
			)
			(layer "F.SilkS")
		)
		(fp_line
			(start 0.508 -0.9398)
			(end -0.508 -0.9398)
			(stroke
				(width 0.1524)
				(type default)
			)
			(layer "F.SilkS")
		)
		(fp_rect
			(start -0.508 0.9398)
			(end 0.508 -0.9398)
			(stroke
				(width 0)
				(type default)
			)
			(fill no)
			(layer "F.CrtYd")
		)
		(fp_rect
			(start -0.508 0.9398)
			(end 0.508 -0.9398)
			(stroke
				(width 0)
				(type default)
			)
			(fill no)
			(layer "F.Fab")
		)
		(pad "1" smd custom
			(at 0 -0.4445)
			(size 0.1397 0.1397)
			(layers "F.Cu" "F.Mask" "F.Paste")
			(net "I2C_M2_1_SDA")
			(options
				(clearance outline)
				(anchor circle)
			)
			(primitives
				(gr_poly
					(pts
						(arc
							(start -0.1778 -0.2794)
							(mid -0.249642 -0.249642)
							(end -0.2794 -0.1778)
						)
						(arc
							(start -0.2794 0.1778)
							(mid -0.249642 0.249642)
							(end -0.1778 0.2794)
						)
						(arc
							(start 0.1778 0.2794)
							(mid 0.249642 0.249642)
							(end 0.2794 0.1778)
						)
						(arc
							(start 0.2794 -0.1778)
							(mid 0.249642 -0.249642)
							(end 0.1778 -0.2794)
						)
					)
					(width 0)
					(fill yes)
				)
			)
		)
		(pad "2" smd custom
			(at 0 0.4445)
			(size 0.1397 0.1397)
			(layers "F.Cu" "F.Mask" "F.Paste")
			(net "BMC_SMB8_DAT")
			(options
				(clearance outline)
				(anchor circle)
			)
			(primitives
				(gr_poly
					(pts
						(arc
							(start -0.1778 -0.2794)
							(mid -0.249642 -0.249642)
							(end -0.2794 -0.1778)
						)
						(arc
							(start -0.2794 0.1778)
							(mid -0.249642 0.249642)
							(end -0.1778 0.2794)
						)
						(arc
							(start 0.1778 0.2794)
							(mid 0.249642 0.249642)
							(end 0.2794 0.1778)
						)
						(arc
							(start 0.2794 -0.1778)
							(mid 0.249642 -0.249642)
							(end 0.1778 -0.2794)
						)
					)
					(width 0)
					(fill yes)
				)
			)
		)
	)
	(footprint ""
		(layer "F.Cu")
		(at 182.372 -88.392)
		(property "Reference" "R621"
			(at 0 0 0)
			(layer "F.SilkS")
			(hide yes)
			(effects
				(font
					(size 1.27 1.27)
				)
			)
		)
		(property "Value" "4K7R2F-GP"
			(at 0.064008 -3.993896 0)
			(unlocked yes)
			(layer "F.Fab")
			(hide yes)
			(effects
				(font
					(size 1.016 1.016)
					(thickness 0.1524)
				)
			)
		)
		(property "Device Type" "R402H16"
			(at 0.064008 -5.517896 0)
			(unlocked yes)
			(layer "F.Fab")
			(hide yes)
			(effects
				(font
					(size 1.016 1.016)
					(thickness 0.1524)
				)
			)
		)
		(duplicate_pad_numbers_are_jumpers no)
		(fp_line
			(start -0.508 -0.9398)
			(end -0.508 0.9398)
			(stroke
				(width 0.1524)
				(type default)
			)
			(layer "F.SilkS")
		)
		(fp_line
			(start 0.508 -0.9398)
			(end -0.508 -0.9398)
			(stroke
				(width 0.1524)
				(type default)
			)
			(layer "F.SilkS")
		)
		(fp_rect
			(start -0.508 0.9398)
			(end 0.508 -0.9398)
			(stroke
				(width 0)
				(type default)
			)
			(fill no)
			(layer "F.CrtYd")
		)
		(fp_rect
			(start -0.508 0.9398)
			(end 0.508 -0.9398)
			(stroke
				(width 0)
				(type default)
			)
			(fill no)
			(layer "F.Fab")
		)
		(pad "1" smd custom
			(at 0 -0.4445)
			(size 0.1397 0.1397)
			(layers "F.Cu" "F.Mask" "F.Paste")
			(net "P1V8")
			(options
				(clearance outline)
				(anchor circle)
			)
			(primitives
				(gr_poly
					(pts
						(arc
							(start -0.1778 -0.2794)
							(mid -0.249642 -0.249642)
							(end -0.2794 -0.1778)
						)
						(arc
							(start -0.2794 0.1778)
							(mid -0.249642 0.249642)
							(end -0.1778 0.2794)
						)
						(arc
							(start 0.1778 0.2794)
							(mid 0.249642 0.249642)
							(end 0.2794 0.1778)
						)
						(arc
							(start 0.2794 -0.1778)
							(mid 0.249642 -0.249642)
							(end 0.1778 -0.2794)
						)
					)
					(width 0)
					(fill yes)
				)
			)
		)
		(pad "2" smd custom
			(at 0 0.4445)
			(size 0.1397 0.1397)
			(layers "F.Cu" "F.Mask" "F.Paste")
			(net "IOC_UART_0_RX")
			(options
				(clearance outline)
				(anchor circle)
			)
			(primitives
				(gr_poly
					(pts
						(arc
							(start -0.1778 -0.2794)
							(mid -0.249642 -0.249642)
							(end -0.2794 -0.1778)
						)
						(arc
							(start -0.2794 0.1778)
							(mid -0.249642 0.249642)
							(end -0.1778 0.2794)
						)
						(arc
							(start 0.1778 0.2794)
							(mid 0.249642 0.249642)
							(end 0.2794 0.1778)
						)
						(arc
							(start 0.2794 -0.1778)
							(mid 0.249642 -0.249642)
							(end 0.1778 -0.2794)
						)
					)
					(width 0)
					(fill yes)
				)
			)
		)
	)
	(footprint ""
		(layer "F.Cu")
		(at 27.99588 -124.810012)
		(property "Reference" "R788"
			(at 0 0 0)
			(layer "F.SilkS")
			(hide yes)
			(effects
				(font
					(size 1.27 1.27)
				)
			)
		)
		(property "Value" "0R2J-2-GP"
			(at 0.064008 -3.993896 0)
			(unlocked yes)
			(layer "F.Fab")
			(hide yes)
			(effects
				(font
					(size 1.016 1.016)
					(thickness 0.1524)
				)
			)
		)
		(property "Device Type" "R402H16"
			(at 0.064008 -5.517896 0)
			(unlocked yes)
			(layer "F.Fab")
			(hide yes)
			(effects
				(font
					(size 1.016 1.016)
					(thickness 0.1524)
				)
			)
		)
		(duplicate_pad_numbers_are_jumpers no)
		(fp_line
			(start -0.508 -0.9398)
			(end -0.508 0.9398)
			(stroke
				(width 0.1524)
				(type default)
			)
			(layer "F.SilkS")
		)
		(fp_line
			(start 0.508 -0.9398)
			(end -0.508 -0.9398)
			(stroke
				(width 0.1524)
				(type default)
			)
			(layer "F.SilkS")
		)
		(fp_rect
			(start -0.508 0.9398)
			(end 0.508 -0.9398)
			(stroke
				(width 0)
				(type default)
			)
			(fill no)
			(layer "F.CrtYd")
		)
		(fp_rect
			(start -0.508 0.9398)
			(end 0.508 -0.9398)
			(stroke
				(width 0)
				(type default)
			)
			(fill no)
			(layer "F.Fab")
		)
		(pad "1" smd custom
			(at 0 -0.4445)
			(size 0.1397 0.1397)
			(layers "F.Cu" "F.Mask" "F.Paste")
			(net "FLA0_WP_N")
			(options
				(clearance outline)
				(anchor circle)
			)
			(primitives
				(gr_poly
					(pts
						(arc
							(start -0.1778 -0.2794)
							(mid -0.249642 -0.249642)
							(end -0.2794 -0.1778)
						)
						(arc
							(start -0.2794 0.1778)
							(mid -0.249642 0.249642)
							(end -0.1778 0.2794)
						)
						(arc
							(start 0.1778 0.2794)
							(mid 0.249642 0.249642)
							(end 0.2794 0.1778)
						)
						(arc
							(start 0.2794 -0.1778)
							(mid 0.249642 -0.249642)
							(end 0.1778 -0.2794)
						)
					)
					(width 0)
					(fill yes)
				)
			)
		)
		(pad "2" smd custom
			(at 0 0.4445)
			(size 0.1397 0.1397)
			(layers "F.Cu" "F.Mask" "F.Paste")
			(net "WP_ENABLE")
			(options
				(clearance outline)
				(anchor circle)
			)
			(primitives
				(gr_poly
					(pts
						(arc
							(start -0.1778 -0.2794)
							(mid -0.249642 -0.249642)
							(end -0.2794 -0.1778)
						)
						(arc
							(start -0.2794 0.1778)
							(mid -0.249642 0.249642)
							(end -0.1778 0.2794)
						)
						(arc
							(start 0.1778 0.2794)
							(mid 0.249642 0.249642)
							(end 0.2794 0.1778)
						)
						(arc
							(start 0.2794 -0.1778)
							(mid 0.249642 -0.249642)
							(end 0.1778 -0.2794)
						)
					)
					(width 0)
					(fill yes)
				)
			)
		)
	)
	(footprint ""
		(layer "F.Cu")
		(at 210.3755 -125.159516 180)
		(property "Reference" "C248"
			(at 0 0 180)
			(layer "F.SilkS")
			(hide yes)
			(effects
				(font
					(size 1.27 1.27)
				)
			)
		)
		(property "Value" "SC10U6D3V5KX-4GP"
			(at -0.0762 -6.1214 180)
			(unlocked yes)
			(layer "F.Fab")
			(hide yes)
			(effects
				(font
					(size 1.016 1.016)
					(thickness 0.1524)
				)
			)
		)
		(property "Device Type" "C805H58"
			(at -0.0762 -8.1534 180)
			(unlocked yes)
			(layer "F.Fab")
			(hide yes)
			(effects
				(font
					(size 1.016 1.016)
					(thickness 0.1524)
				)
			)
		)
		(duplicate_pad_numbers_are_jumpers no)
		(fp_line
			(start 0.635 0)
			(end -0.635 0)
			(stroke
				(width 0.508)
				(type default)
			)
			(layer "F.SilkS")
		)
		(fp_rect
			(start -0.9652 1.778)
			(end 0.9652 -1.778)
			(stroke
				(width 0)
				(type default)
			)
			(fill no)
			(layer "F.CrtYd")
		)
		(fp_poly
			(pts
				(xy -0.9652 -1.778) (xy 0.9652 -1.778) (xy 0.9652 1.778) (xy -0.9652 1.778)
			)
			(stroke
				(width 0)
				(type default)
			)
			(fill no)
			(layer "F.Fab")
		)
		(pad "1" smd rect
			(at 0 -0.9652 180)
			(size 1.397 1.143)
			(layers "F.Cu" "F.Mask" "F.Paste")
			(net "P1V5_OUT")
		)
		(pad "2" smd rect
			(at 0 0.9652 180)
			(size 1.397 1.143)
			(layers "F.Cu" "F.Mask" "F.Paste")
			(net "GND")
		)
	)
	(footprint ""
		(layer "F.Cu")
		(at 168.6306 -112.5728 -90)
		(property "Reference" "R528"
			(at 0 0 270)
			(layer "F.SilkS")
			(hide yes)
			(effects
				(font
					(size 1.27 1.27)
				)
			)
		)
		(property "Value" "1KR2F-3-GP"
			(at 0.064008 -3.993896 270)
			(unlocked yes)
			(layer "F.Fab")
			(hide yes)
			(effects
				(font
					(size 1.016 1.016)
					(thickness 0.1524)
				)
			)
		)
		(property "Device Type" "R402H16"
			(at 0.064008 -5.517896 270)
			(unlocked yes)
			(layer "F.Fab")
			(hide yes)
			(effects
				(font
					(size 1.016 1.016)
					(thickness 0.1524)
				)
			)
		)
		(duplicate_pad_numbers_are_jumpers no)
		(fp_line
			(start -0.508 -0.9398)
			(end -0.508 0.9398)
			(stroke
				(width 0.1524)
				(type default)
			)
			(layer "F.SilkS")
		)
		(fp_line
			(start 0.508 -0.9398)
			(end -0.508 -0.9398)
			(stroke
				(width 0.1524)
				(type default)
			)
			(layer "F.SilkS")
		)
		(fp_rect
			(start -0.508 0.9398)
			(end 0.508 -0.9398)
			(stroke
				(width 0)
				(type default)
			)
			(fill no)
			(layer "F.CrtYd")
		)
		(fp_rect
			(start -0.508 0.9398)
			(end 0.508 -0.9398)
			(stroke
				(width 0)
				(type default)
			)
			(fill no)
			(layer "F.Fab")
		)
		(pad "1" smd custom
			(at 0 -0.4445 270)
			(size 0.1397 0.1397)
			(layers "F.Cu" "F.Mask" "F.Paste")
			(net "P1V8")
			(options
				(clearance outline)
				(anchor circle)
			)
			(primitives
				(gr_poly
					(pts
						(arc
							(start -0.1778 -0.2794)
							(mid -0.249642 -0.249642)
							(end -0.2794 -0.1778)
						)
						(arc
							(start -0.2794 0.1778)
							(mid -0.249642 0.249642)
							(end -0.1778 0.2794)
						)
						(arc
							(start 0.1778 0.2794)
							(mid 0.249642 0.249642)
							(end 0.2794 0.1778)
						)
						(arc
							(start 0.2794 -0.1778)
							(mid 0.249642 -0.249642)
							(end 0.1778 -0.2794)
						)
					)
					(width 0)
					(fill yes)
				)
			)
		)
		(pad "2" smd custom
			(at 0 0.4445 270)
			(size 0.1397 0.1397)
			(layers "F.Cu" "F.Mask" "F.Paste")
			(net "GND")
			(options
				(clearance outline)
				(anchor circle)
			)
			(primitives
				(gr_poly
					(pts
						(arc
							(start -0.1778 -0.2794)
							(mid -0.249642 -0.249642)
							(end -0.2794 -0.1778)
						)
						(arc
							(start -0.2794 0.1778)
							(mid -0.249642 0.249642)
							(end -0.1778 0.2794)
						)
						(arc
							(start 0.1778 0.2794)
							(mid 0.249642 0.249642)
							(end 0.2794 0.1778)
						)
						(arc
							(start 0.2794 -0.1778)
							(mid 0.249642 -0.249642)
							(end 0.1778 -0.2794)
						)
					)
					(width 0)
					(fill yes)
				)
			)
		)
	)
	(footprint ""
		(layer "F.Cu")
		(at 21.492464 -14.64945 180)
		(property "Reference" "C26"
			(at 0 0 180)
			(layer "F.SilkS")
			(hide yes)
			(effects
				(font
					(size 1.27 1.27)
				)
			)
		)
		(property "Value" "SC1U16V3KX-5GP"
			(at 0 -2.8194 180)
			(unlocked yes)
			(layer "F.Fab")
			(hide yes)
			(effects
				(font
					(size 1.016 1.016)
					(thickness 0.1524)
				)
			)
		)
		(property "Device Type" "C603H36"
			(at 0 -4.3434 180)
			(unlocked yes)
			(layer "F.Fab")
			(hide yes)
			(effects
				(font
					(size 1.016 1.016)
					(thickness 0.1524)
				)
			)
		)
		(duplicate_pad_numbers_are_jumpers no)
		(fp_line
			(start 0.508 0)
			(end -0.508 0)
			(stroke
				(width 0.2032)
				(type default)
			)
			(layer "F.SilkS")
		)
		(fp_rect
			(start -0.5842 1.3335)
			(end 0.5842 -1.3335)
			(stroke
				(width 0)
				(type default)
			)
			(fill no)
			(layer "F.CrtYd")
		)
		(fp_rect
			(start -0.5842 1.3335)
			(end 0.5842 -1.3335)
			(stroke
				(width 0)
				(type default)
			)
			(fill no)
			(layer "F.Fab")
		)
		(pad "1" smd custom
			(at 0 -0.762 180)
			(size 0.2159 0.2159)
			(layers "F.Cu" "F.Mask" "F.Paste")
			(net "FP_PWR_BTN_N")
			(options
				(clearance outline)
				(anchor circle)
			)
			(primitives
				(gr_poly
					(pts
						(arc
							(start -0.3302 -0.4318)
							(mid -0.402042 -0.402042)
							(end -0.4318 -0.3302)
						)
						(arc
							(start -0.4318 0.3302)
							(mid -0.402042 0.402042)
							(end -0.3302 0.4318)
						)
						(arc
							(start 0.3302 0.4318)
							(mid 0.402042 0.402042)
							(end 0.4318 0.3302)
						)
						(arc
							(start 0.4318 -0.3302)
							(mid 0.402042 -0.402042)
							(end 0.3302 -0.4318)
						)
					)
					(width 0)
					(fill yes)
				)
			)
		)
		(pad "2" smd custom
			(at 0 0.762 180)
			(size 0.2159 0.2159)
			(layers "F.Cu" "F.Mask" "F.Paste")
			(net "GND")
			(options
				(clearance outline)
				(anchor circle)
			)
			(primitives
				(gr_poly
					(pts
						(arc
							(start -0.3302 -0.4318)
							(mid -0.402042 -0.402042)
							(end -0.4318 -0.3302)
						)
						(arc
							(start -0.4318 0.3302)
							(mid -0.402042 0.402042)
							(end -0.3302 0.4318)
						)
						(arc
							(start 0.3302 0.4318)
							(mid 0.402042 0.402042)
							(end 0.4318 0.3302)
						)
						(arc
							(start 0.4318 -0.3302)
							(mid 0.402042 -0.402042)
							(end 0.3302 -0.4318)
						)
					)
					(width 0)
					(fill yes)
				)
			)
		)
	)
	(footprint ""
		(layer "F.Cu")
		(at 51.2826 -125.8824 -90)
		(property "Reference" "R599"
			(at 0 0 270)
			(layer "F.SilkS")
			(hide yes)
			(effects
				(font
					(size 1.27 1.27)
				)
			)
		)
		(property "Value" "4K7R2F-GP"
			(at 0.064008 -3.993896 270)
			(unlocked yes)
			(layer "F.Fab")
			(hide yes)
			(effects
				(font
					(size 1.016 1.016)
					(thickness 0.1524)
				)
			)
		)
		(property "Device Type" "R402H16"
			(at 0.064008 -5.517896 270)
			(unlocked yes)
			(layer "F.Fab")
			(hide yes)
			(effects
				(font
					(size 1.016 1.016)
					(thickness 0.1524)
				)
			)
		)
		(duplicate_pad_numbers_are_jumpers no)
		(fp_line
			(start -0.508 -0.9398)
			(end -0.508 0.9398)
			(stroke
				(width 0.1524)
				(type default)
			)
			(layer "F.SilkS")
		)
		(fp_line
			(start 0.508 -0.9398)
			(end -0.508 -0.9398)
			(stroke
				(width 0.1524)
				(type default)
			)
			(layer "F.SilkS")
		)
		(fp_rect
			(start -0.508 0.9398)
			(end 0.508 -0.9398)
			(stroke
				(width 0)
				(type default)
			)
			(fill no)
			(layer "F.CrtYd")
		)
		(fp_rect
			(start -0.508 0.9398)
			(end 0.508 -0.9398)
			(stroke
				(width 0)
				(type default)
			)
			(fill no)
			(layer "F.Fab")
		)
		(pad "1" smd custom
			(at 0 -0.4445 270)
			(size 0.1397 0.1397)
			(layers "F.Cu" "F.Mask" "F.Paste")
			(net "P3V3_STBY")
			(options
				(clearance outline)
				(anchor circle)
			)
			(primitives
				(gr_poly
					(pts
						(arc
							(start -0.1778 -0.2794)
							(mid -0.249642 -0.249642)
							(end -0.2794 -0.1778)
						)
						(arc
							(start -0.2794 0.1778)
							(mid -0.249642 0.249642)
							(end -0.1778 0.2794)
						)
						(arc
							(start 0.1778 0.2794)
							(mid 0.249642 0.249642)
							(end 0.2794 0.1778)
						)
						(arc
							(start 0.2794 -0.1778)
							(mid 0.249642 -0.249642)
							(end 0.1778 -0.2794)
						)
					)
					(width 0)
					(fill yes)
				)
			)
		)
		(pad "2" smd custom
			(at 0 0.4445 270)
			(size 0.1397 0.1397)
			(layers "F.Cu" "F.Mask" "F.Paste")
			(net "DPB_MISC_ALERT_OUT")
			(options
				(clearance outline)
				(anchor circle)
			)
			(primitives
				(gr_poly
					(pts
						(arc
							(start -0.1778 -0.2794)
							(mid -0.249642 -0.249642)
							(end -0.2794 -0.1778)
						)
						(arc
							(start -0.2794 0.1778)
							(mid -0.249642 0.249642)
							(end -0.1778 0.2794)
						)
						(arc
							(start 0.1778 0.2794)
							(mid 0.249642 0.249642)
							(end 0.2794 0.1778)
						)
						(arc
							(start 0.2794 -0.1778)
							(mid 0.249642 -0.249642)
							(end 0.1778 -0.2794)
						)
					)
					(width 0)
					(fill yes)
				)
			)
		)
	)
	(footprint ""
		(layer "F.Cu")
		(at 74.4728 -140.0302 -90)
		(property "Reference" "R58"
			(at 0 0 270)
			(layer "F.SilkS")
			(hide yes)
			(effects
				(font
					(size 1.27 1.27)
				)
			)
		)
		(property "Value" "33R2F-3-GP"
			(at 0.064008 -3.993896 270)
			(unlocked yes)
			(layer "F.Fab")
			(hide yes)
			(effects
				(font
					(size 1.016 1.016)
					(thickness 0.1524)
				)
			)
		)
		(property "Device Type" "R402H16"
			(at 0.064008 -5.517896 270)
			(unlocked yes)
			(layer "F.Fab")
			(hide yes)
			(effects
				(font
					(size 1.016 1.016)
					(thickness 0.1524)
				)
			)
		)
		(duplicate_pad_numbers_are_jumpers no)
		(fp_line
			(start -0.508 -0.9398)
			(end -0.508 0.9398)
			(stroke
				(width 0.1524)
				(type default)
			)
			(layer "F.SilkS")
		)
		(fp_line
			(start 0.508 -0.9398)
			(end -0.508 -0.9398)
			(stroke
				(width 0.1524)
				(type default)
			)
			(layer "F.SilkS")
		)
		(fp_rect
			(start -0.508 0.9398)
			(end 0.508 -0.9398)
			(stroke
				(width 0)
				(type default)
			)
			(fill no)
			(layer "F.CrtYd")
		)
		(fp_rect
			(start -0.508 0.9398)
			(end 0.508 -0.9398)
			(stroke
				(width 0)
				(type default)
			)
			(fill no)
			(layer "F.Fab")
		)
		(pad "1" smd custom
			(at 0 -0.4445 270)
			(size 0.1397 0.1397)
			(layers "F.Cu" "F.Mask" "F.Paste")
			(net "SYS_RST_BTN_IN_N")
			(options
				(clearance outline)
				(anchor circle)
			)
			(primitives
				(gr_poly
					(pts
						(arc
							(start -0.1778 -0.2794)
							(mid -0.249642 -0.249642)
							(end -0.2794 -0.1778)
						)
						(arc
							(start -0.2794 0.1778)
							(mid -0.249642 0.249642)
							(end -0.1778 0.2794)
						)
						(arc
							(start 0.1778 0.2794)
							(mid 0.249642 0.249642)
							(end 0.2794 0.1778)
						)
						(arc
							(start 0.2794 -0.1778)
							(mid 0.249642 -0.249642)
							(end 0.1778 -0.2794)
						)
					)
					(width 0)
					(fill yes)
				)
			)
		)
		(pad "2" smd custom
			(at 0 0.4445 270)
			(size 0.1397 0.1397)
			(layers "F.Cu" "F.Mask" "F.Paste")
			(net "FP_RESET_RC_N")
			(options
				(clearance outline)
				(anchor circle)
			)
			(primitives
				(gr_poly
					(pts
						(arc
							(start -0.1778 -0.2794)
							(mid -0.249642 -0.249642)
							(end -0.2794 -0.1778)
						)
						(arc
							(start -0.2794 0.1778)
							(mid -0.249642 0.249642)
							(end -0.1778 0.2794)
						)
						(arc
							(start 0.1778 0.2794)
							(mid 0.249642 0.249642)
							(end 0.2794 0.1778)
						)
						(arc
							(start 0.2794 -0.1778)
							(mid 0.249642 -0.249642)
							(end 0.1778 -0.2794)
						)
					)
					(width 0)
					(fill yes)
				)
			)
		)
	)
	(footprint ""
		(layer "F.Cu")
		(at 83.358228 -88.549734 90)
		(property "Reference" "VIA13"
			(at 0 0 90)
			(layer "F.SilkS")
			(hide yes)
			(effects
				(font
					(size 1.27 1.27)
				)
			)
		)
		(property "Value" "85OHM-8L-1D6MM-L16L18-GP"
			(at 4.064 0.6096 90)
			(unlocked yes)
			(layer "F.Fab")
			(hide yes)
			(effects
				(font
					(size 1.016 1.016)
					(thickness 0.1524)
				)
			)
		)
		(property "Device Type" "VIA-PCIE-4P-368076"
			(at 4.064 -0.9144 90)
			(unlocked yes)
			(layer "F.Fab")
			(hide yes)
			(effects
				(font
					(size 1.016 1.016)
					(thickness 0.1524)
				)
			)
		)
		(duplicate_pad_numbers_are_jumpers no)
		(fp_rect
			(start -1.8415 0.381)
			(end 1.8415 -0.381)
			(stroke
				(width 0)
				(type default)
			)
			(fill no)
			(layer "F.CrtYd")
		)
		(fp_rect
			(start -1.8415 0.381)
			(end 1.8415 -0.381)
			(stroke
				(width 0)
				(type default)
			)
			(fill no)
			(layer "F.Fab")
		)
		(pad "1" thru_hole circle
			(at -1.4605 0 90)
			(size 0.508 0.508)
			(drill 0.254)
			(layers "*.Cu" "*.Mask")
			(remove_unused_layers no)
			(net "GND")
			(clearance 0.127)
			(thermal_gap 0.127)
		)
		(pad "2" thru_hole circle
			(at -0.4445 0 90)
			(size 0.508 0.508)
			(drill 0.254)
			(layers "*.Cu" "*.Mask")
			(remove_unused_layers no)
			(net "PCIE_IOM_TO_COMP_21_DP")
			(clearance 0.127)
			(thermal_gap 0.127)
		)
		(pad "3" thru_hole circle
			(at 0.4445 0 90)
			(size 0.508 0.508)
			(drill 0.254)
			(layers "*.Cu" "*.Mask")
			(remove_unused_layers no)
			(net "PCIE_IOM_TO_COMP_21_DN")
			(clearance 0.127)
			(thermal_gap 0.127)
		)
		(pad "4" thru_hole circle
			(at 1.4605 0 90)
			(size 0.508 0.508)
			(drill 0.254)
			(layers "*.Cu" "*.Mask")
			(remove_unused_layers no)
			(net "GND")
			(clearance 0.127)
			(thermal_gap 0.127)
		)
	)
	(footprint ""
		(layer "F.Cu")
		(at 10.796524 -136.715246 90)
		(property "Reference" "R208"
			(at 0 0 90)
			(layer "F.SilkS")
			(hide yes)
			(effects
				(font
					(size 1.27 1.27)
				)
			)
		)
		(property "Value" "120R2F-GP"
			(at 0.064008 -3.993896 90)
			(unlocked yes)
			(layer "F.Fab")
			(hide yes)
			(effects
				(font
					(size 1.016 1.016)
					(thickness 0.1524)
				)
			)
		)
		(property "Device Type" "R402H16"
			(at 0.064008 -5.517896 90)
			(unlocked yes)
			(layer "F.Fab")
			(hide yes)
			(effects
				(font
					(size 1.016 1.016)
					(thickness 0.1524)
				)
			)
		)
		(duplicate_pad_numbers_are_jumpers no)
		(fp_line
			(start 0.508 -0.9398)
			(end -0.508 -0.9398)
			(stroke
				(width 0.1524)
				(type default)
			)
			(layer "F.SilkS")
		)
		(fp_line
			(start -0.508 -0.9398)
			(end -0.508 0.9398)
			(stroke
				(width 0.1524)
				(type default)
			)
			(layer "F.SilkS")
		)
		(fp_rect
			(start -0.508 0.9398)
			(end 0.508 -0.9398)
			(stroke
				(width 0)
				(type default)
			)
			(fill no)
			(layer "F.CrtYd")
		)
		(fp_rect
			(start -0.508 0.9398)
			(end 0.508 -0.9398)
			(stroke
				(width 0)
				(type default)
			)
			(fill no)
			(layer "F.Fab")
		)
		(pad "1" smd custom
			(at 0 -0.4445 90)
			(size 0.1397 0.1397)
			(layers "F.Cu" "F.Mask" "F.Paste")
			(net "DDR4_RST_N")
			(options
				(clearance outline)
				(anchor circle)
			)
			(primitives
				(gr_poly
					(pts
						(arc
							(start -0.1778 -0.2794)
							(mid -0.249642 -0.249642)
							(end -0.2794 -0.1778)
						)
						(arc
							(start -0.2794 0.1778)
							(mid -0.249642 0.249642)
							(end -0.1778 0.2794)
						)
						(arc
							(start 0.1778 0.2794)
							(mid 0.249642 0.249642)
							(end 0.2794 0.1778)
						)
						(arc
							(start 0.2794 -0.1778)
							(mid 0.249642 -0.249642)
							(end 0.1778 -0.2794)
						)
					)
					(width 0)
					(fill yes)
				)
			)
		)
		(pad "2" smd custom
			(at 0 0.4445 90)
			(size 0.1397 0.1397)
			(layers "F.Cu" "F.Mask" "F.Paste")
			(net "P1V2_STBY")
			(options
				(clearance outline)
				(anchor circle)
			)
			(primitives
				(gr_poly
					(pts
						(arc
							(start -0.1778 -0.2794)
							(mid -0.249642 -0.249642)
							(end -0.2794 -0.1778)
						)
						(arc
							(start -0.2794 0.1778)
							(mid -0.249642 0.249642)
							(end -0.1778 0.2794)
						)
						(arc
							(start 0.1778 0.2794)
							(mid 0.249642 0.249642)
							(end 0.2794 0.1778)
						)
						(arc
							(start 0.2794 -0.1778)
							(mid 0.249642 -0.249642)
							(end 0.1778 -0.2794)
						)
					)
					(width 0)
					(fill yes)
				)
			)
		)
	)
	(footprint ""
		(layer "F.Cu")
		(at 120.015 -16.3068)
		(property "Reference" "R441"
			(at 0 0 0)
			(layer "F.SilkS")
			(hide yes)
			(effects
				(font
					(size 1.27 1.27)
				)
			)
		)
		(property "Value" "10R2F-L-GP"
			(at 0.064008 -3.993896 0)
			(unlocked yes)
			(layer "F.Fab")
			(hide yes)
			(effects
				(font
					(size 1.016 1.016)
					(thickness 0.1524)
				)
			)
		)
		(property "Device Type" "R402H14"
			(at 0.064008 -5.517896 0)
			(unlocked yes)
			(layer "F.Fab")
			(hide yes)
			(effects
				(font
					(size 1.016 1.016)
					(thickness 0.1524)
				)
			)
		)
		(duplicate_pad_numbers_are_jumpers no)
		(fp_line
			(start -0.508 -0.9398)
			(end -0.508 0.9398)
			(stroke
				(width 0.1524)
				(type default)
			)
			(layer "F.SilkS")
		)
		(fp_line
			(start 0.508 -0.9398)
			(end -0.508 -0.9398)
			(stroke
				(width 0.1524)
				(type default)
			)
			(layer "F.SilkS")
		)
		(fp_rect
			(start -0.508 0.9398)
			(end 0.508 -0.9398)
			(stroke
				(width 0)
				(type default)
			)
			(fill no)
			(layer "F.CrtYd")
		)
		(fp_rect
			(start -0.508 0.9398)
			(end 0.508 -0.9398)
			(stroke
				(width 0)
				(type default)
			)
			(fill no)
			(layer "F.Fab")
		)
		(pad "1" smd custom
			(at 0 -0.4445)
			(size 0.1397 0.1397)
			(layers "F.Cu" "F.Mask" "F.Paste")
			(net "MB0_CM_SENSE_R1_N")
			(options
				(clearance outline)
				(anchor circle)
			)
			(primitives
				(gr_poly
					(pts
						(arc
							(start -0.1778 -0.2794)
							(mid -0.249642 -0.249642)
							(end -0.2794 -0.1778)
						)
						(arc
							(start -0.2794 0.1778)
							(mid -0.249642 0.249642)
							(end -0.1778 0.2794)
						)
						(arc
							(start 0.1778 0.2794)
							(mid 0.249642 0.249642)
							(end 0.2794 0.1778)
						)
						(arc
							(start 0.2794 -0.1778)
							(mid 0.249642 -0.249642)
							(end 0.1778 -0.2794)
						)
					)
					(width 0)
					(fill yes)
				)
			)
		)
		(pad "2" smd custom
			(at 0 0.4445)
			(size 0.1397 0.1397)
			(layers "F.Cu" "F.Mask" "F.Paste")
			(net "MB0_CM_SENSE_N")
			(options
				(clearance outline)
				(anchor circle)
			)
			(primitives
				(gr_poly
					(pts
						(arc
							(start -0.1778 -0.2794)
							(mid -0.249642 -0.249642)
							(end -0.2794 -0.1778)
						)
						(arc
							(start -0.2794 0.1778)
							(mid -0.249642 0.249642)
							(end -0.1778 0.2794)
						)
						(arc
							(start 0.1778 0.2794)
							(mid 0.249642 0.249642)
							(end 0.2794 0.1778)
						)
						(arc
							(start 0.2794 -0.1778)
							(mid 0.249642 -0.249642)
							(end 0.1778 -0.2794)
						)
					)
					(width 0)
					(fill yes)
				)
			)
		)
	)
	(footprint ""
		(layer "F.Cu")
		(at 32.4866 -165.0238)
		(property "Reference" "R698"
			(at 0 0 0)
			(layer "F.SilkS")
			(hide yes)
			(effects
				(font
					(size 1.27 1.27)
				)
			)
		)
		(property "Value" "4K7R2F-GP"
			(at 0.064008 -3.993896 0)
			(unlocked yes)
			(layer "F.Fab")
			(hide yes)
			(effects
				(font
					(size 1.016 1.016)
					(thickness 0.1524)
				)
			)
		)
		(property "Device Type" "R402H16"
			(at 0.064008 -5.517896 0)
			(unlocked yes)
			(layer "F.Fab")
			(hide yes)
			(effects
				(font
					(size 1.016 1.016)
					(thickness 0.1524)
				)
			)
		)
		(duplicate_pad_numbers_are_jumpers no)
		(fp_line
			(start -0.508 -0.9398)
			(end -0.508 0.9398)
			(stroke
				(width 0.1524)
				(type default)
			)
			(layer "F.SilkS")
		)
		(fp_line
			(start 0.508 -0.9398)
			(end -0.508 -0.9398)
			(stroke
				(width 0.1524)
				(type default)
			)
			(layer "F.SilkS")
		)
		(fp_rect
			(start -0.508 0.9398)
			(end 0.508 -0.9398)
			(stroke
				(width 0)
				(type default)
			)
			(fill no)
			(layer "F.CrtYd")
		)
		(fp_rect
			(start -0.508 0.9398)
			(end 0.508 -0.9398)
			(stroke
				(width 0)
				(type default)
			)
			(fill no)
			(layer "F.Fab")
		)
		(pad "1" smd custom
			(at 0 -0.4445)
			(size 0.1397 0.1397)
			(layers "F.Cu" "F.Mask" "F.Paste")
			(net "P3V3_STBY")
			(options
				(clearance outline)
				(anchor circle)
			)
			(primitives
				(gr_poly
					(pts
						(arc
							(start -0.1778 -0.2794)
							(mid -0.249642 -0.249642)
							(end -0.2794 -0.1778)
						)
						(arc
							(start -0.2794 0.1778)
							(mid -0.249642 0.249642)
							(end -0.1778 0.2794)
						)
						(arc
							(start 0.1778 0.2794)
							(mid 0.249642 0.249642)
							(end 0.2794 0.1778)
						)
						(arc
							(start 0.2794 -0.1778)
							(mid 0.249642 -0.249642)
							(end 0.1778 -0.2794)
						)
					)
					(width 0)
					(fill yes)
				)
			)
		)
		(pad "2" smd custom
			(at 0 0.4445)
			(size 0.1397 0.1397)
			(layers "F.Cu" "F.Mask" "F.Paste")
			(net "IOM_TYPE1")
			(options
				(clearance outline)
				(anchor circle)
			)
			(primitives
				(gr_poly
					(pts
						(arc
							(start -0.1778 -0.2794)
							(mid -0.249642 -0.249642)
							(end -0.2794 -0.1778)
						)
						(arc
							(start -0.2794 0.1778)
							(mid -0.249642 0.249642)
							(end -0.1778 0.2794)
						)
						(arc
							(start 0.1778 0.2794)
							(mid 0.249642 0.249642)
							(end 0.2794 0.1778)
						)
						(arc
							(start 0.2794 -0.1778)
							(mid 0.249642 -0.249642)
							(end 0.1778 -0.2794)
						)
					)
					(width 0)
					(fill yes)
				)
			)
		)
	)
	(footprint ""
		(layer "F.Cu")
		(at 176.9618 -119.7864 180)
		(property "Reference" "R523"
			(at 0 0 180)
			(layer "F.SilkS")
			(hide yes)
			(effects
				(font
					(size 1.27 1.27)
				)
			)
		)
		(property "Value" "4K53R2F-1-GP"
			(at 0.064008 -3.993896 180)
			(unlocked yes)
			(layer "F.Fab")
			(hide yes)
			(effects
				(font
					(size 1.016 1.016)
					(thickness 0.1524)
				)
			)
		)
		(property "Device Type" "R402H16"
			(at 0.064008 -5.517896 180)
			(unlocked yes)
			(layer "F.Fab")
			(hide yes)
			(effects
				(font
					(size 1.016 1.016)
					(thickness 0.1524)
				)
			)
		)
		(duplicate_pad_numbers_are_jumpers no)
		(fp_line
			(start 0.508 -0.9398)
			(end -0.508 -0.9398)
			(stroke
				(width 0.1524)
				(type default)
			)
			(layer "F.SilkS")
		)
		(fp_line
			(start -0.508 -0.9398)
			(end -0.508 0.9398)
			(stroke
				(width 0.1524)
				(type default)
			)
			(layer "F.SilkS")
		)
		(fp_rect
			(start -0.508 0.9398)
			(end 0.508 -0.9398)
			(stroke
				(width 0)
				(type default)
			)
			(fill no)
			(layer "F.CrtYd")
		)
		(fp_rect
			(start -0.508 0.9398)
			(end 0.508 -0.9398)
			(stroke
				(width 0)
				(type default)
			)
			(fill no)
			(layer "F.Fab")
		)
		(pad "1" smd custom
			(at 0 -0.4445 180)
			(size 0.1397 0.1397)
			(layers "F.Cu" "F.Mask" "F.Paste")
			(net "PQ4_G")
			(options
				(clearance outline)
				(anchor circle)
			)
			(primitives
				(gr_poly
					(pts
						(arc
							(start -0.1778 -0.2794)
							(mid -0.249642 -0.249642)
							(end -0.2794 -0.1778)
						)
						(arc
							(start -0.2794 0.1778)
							(mid -0.249642 0.249642)
							(end -0.1778 0.2794)
						)
						(arc
							(start 0.1778 0.2794)
							(mid 0.249642 0.249642)
							(end 0.2794 0.1778)
						)
						(arc
							(start 0.2794 -0.1778)
							(mid 0.249642 -0.249642)
							(end 0.1778 -0.2794)
						)
					)
					(width 0)
					(fill yes)
				)
			)
		)
		(pad "2" smd custom
			(at 0 0.4445 180)
			(size 0.1397 0.1397)
			(layers "F.Cu" "F.Mask" "F.Paste")
			(net "P3V3_STBY")
			(options
				(clearance outline)
				(anchor circle)
			)
			(primitives
				(gr_poly
					(pts
						(arc
							(start -0.1778 -0.2794)
							(mid -0.249642 -0.249642)
							(end -0.2794 -0.1778)
						)
						(arc
							(start -0.2794 0.1778)
							(mid -0.249642 0.249642)
							(end -0.1778 0.2794)
						)
						(arc
							(start 0.1778 0.2794)
							(mid 0.249642 0.249642)
							(end 0.2794 0.1778)
						)
						(arc
							(start 0.2794 -0.1778)
							(mid 0.249642 -0.249642)
							(end 0.1778 -0.2794)
						)
					)
					(width 0)
					(fill yes)
				)
			)
		)
	)
	(footprint ""
		(layer "F.Cu")
		(at 205.574646 -17.357344 180)
		(property "Reference" "R609"
			(at 0 0 180)
			(layer "F.SilkS")
			(hide yes)
			(effects
				(font
					(size 1.27 1.27)
				)
			)
		)
		(property "Value" "0R2J-2-GP"
			(at 0.064008 -3.993896 180)
			(unlocked yes)
			(layer "F.Fab")
			(hide yes)
			(effects
				(font
					(size 1.016 1.016)
					(thickness 0.1524)
				)
			)
		)
		(property "Device Type" "R402H16"
			(at 0.064008 -5.517896 180)
			(unlocked yes)
			(layer "F.Fab")
			(hide yes)
			(effects
				(font
					(size 1.016 1.016)
					(thickness 0.1524)
				)
			)
		)
		(duplicate_pad_numbers_are_jumpers no)
		(fp_line
			(start 0.508 -0.9398)
			(end -0.508 -0.9398)
			(stroke
				(width 0.1524)
				(type default)
			)
			(layer "F.SilkS")
		)
		(fp_line
			(start -0.508 -0.9398)
			(end -0.508 0.9398)
			(stroke
				(width 0.1524)
				(type default)
			)
			(layer "F.SilkS")
		)
		(fp_rect
			(start -0.508 0.9398)
			(end 0.508 -0.9398)
			(stroke
				(width 0)
				(type default)
			)
			(fill no)
			(layer "F.CrtYd")
		)
		(fp_rect
			(start -0.508 0.9398)
			(end 0.508 -0.9398)
			(stroke
				(width 0)
				(type default)
			)
			(fill no)
			(layer "F.Fab")
		)
		(pad "1" smd custom
			(at 0 -0.4445 180)
			(size 0.1397 0.1397)
			(layers "F.Cu" "F.Mask" "F.Paste")
			(net "BMC_ML_PWR_YELLOW_LED_R")
			(options
				(clearance outline)
				(anchor circle)
			)
			(primitives
				(gr_poly
					(pts
						(arc
							(start -0.1778 -0.2794)
							(mid -0.249642 -0.249642)
							(end -0.2794 -0.1778)
						)
						(arc
							(start -0.2794 0.1778)
							(mid -0.249642 0.249642)
							(end -0.1778 0.2794)
						)
						(arc
							(start 0.1778 0.2794)
							(mid 0.249642 0.249642)
							(end 0.2794 0.1778)
						)
						(arc
							(start 0.2794 -0.1778)
							(mid 0.249642 -0.249642)
							(end 0.1778 -0.2794)
						)
					)
					(width 0)
					(fill yes)
				)
			)
		)
		(pad "2" smd custom
			(at 0 0.4445 180)
			(size 0.1397 0.1397)
			(layers "F.Cu" "F.Mask" "F.Paste")
			(net "BMC_ML_PWR_YELLOW_LED")
			(options
				(clearance outline)
				(anchor circle)
			)
			(primitives
				(gr_poly
					(pts
						(arc
							(start -0.1778 -0.2794)
							(mid -0.249642 -0.249642)
							(end -0.2794 -0.1778)
						)
						(arc
							(start -0.2794 0.1778)
							(mid -0.249642 0.249642)
							(end -0.1778 0.2794)
						)
						(arc
							(start 0.1778 0.2794)
							(mid 0.249642 0.249642)
							(end 0.2794 0.1778)
						)
						(arc
							(start 0.2794 -0.1778)
							(mid 0.249642 -0.249642)
							(end 0.1778 -0.2794)
						)
					)
					(width 0)
					(fill yes)
				)
			)
		)
	)
	(footprint ""
		(layer "F.Cu")
		(at 169.037 -176.911 -90)
		(property "Reference" "C165"
			(at 0 0 270)
			(layer "F.SilkS")
			(hide yes)
			(effects
				(font
					(size 1.27 1.27)
				)
			)
		)
		(property "Value" "SC10U16V5KX-7-GP-U"
			(at -0.0762 -6.1214 270)
			(unlocked yes)
			(layer "F.Fab")
			(hide yes)
			(effects
				(font
					(size 1.016 1.016)
					(thickness 0.1524)
				)
			)
		)
		(property "Device Type" "C805H58"
			(at -0.0762 -8.1534 270)
			(unlocked yes)
			(layer "F.Fab")
			(hide yes)
			(effects
				(font
					(size 1.016 1.016)
					(thickness 0.1524)
				)
			)
		)
		(duplicate_pad_numbers_are_jumpers no)
		(fp_line
			(start 0.635 0)
			(end -0.635 0)
			(stroke
				(width 0.508)
				(type default)
			)
			(layer "F.SilkS")
		)
		(fp_rect
			(start -0.9652 1.778)
			(end 0.9652 -1.778)
			(stroke
				(width 0)
				(type default)
			)
			(fill no)
			(layer "F.CrtYd")
		)
		(fp_poly
			(pts
				(xy -0.9652 -1.778) (xy 0.9652 -1.778) (xy 0.9652 1.778) (xy -0.9652 1.778)
			)
			(stroke
				(width 0)
				(type default)
			)
			(fill no)
			(layer "F.Fab")
		)
		(pad "1" smd rect
			(at 0 -0.9652 270)
			(size 1.397 1.143)
			(layers "F.Cu" "F.Mask" "F.Paste")
			(net "P5V_STBY")
		)
		(pad "2" smd rect
			(at 0 0.9652 270)
			(size 1.397 1.143)
			(layers "F.Cu" "F.Mask" "F.Paste")
			(net "GND")
		)
	)
	(footprint ""
		(layer "F.Cu")
		(at 150.876 -38.481)
		(property "Reference" "TP180"
			(at 0 0 0)
			(layer "F.SilkS")
			(hide yes)
			(effects
				(font
					(size 1.27 1.27)
				)
			)
		)
		(property "Value" "TPAD28-2-GP"
			(at -0.0127 -1.6637 0)
			(unlocked yes)
			(layer "F.Fab")
			(hide yes)
			(effects
				(font
					(size 1.016 1.016)
					(thickness 0.1524)
				)
			)
		)
		(property "Device Type" "TPAD28"
			(at -0.0127 -3.1877 0)
			(unlocked yes)
			(layer "F.Fab")
			(hide yes)
			(effects
				(font
					(size 1.016 1.016)
					(thickness 0.1524)
				)
			)
		)
		(duplicate_pad_numbers_are_jumpers no)
		(fp_poly
			(pts
				(arc
					(start 0.3556 0)
					(mid -0.3556 0)
					(end 0.3556 0)
				)
			)
			(stroke
				(width 0)
				(type default)
			)
			(fill no)
			(layer "F.CrtYd")
		)
		(fp_poly
			(pts
				(arc
					(start 0.6096 0)
					(mid -0.6096 0)
					(end 0.6096 0)
				)
			)
			(stroke
				(width 0)
				(type default)
			)
			(fill no)
			(layer "F.Fab")
		)
		(pad "1" smd circle
			(at 0 0)
			(size 0.7112 0.7112)
			(layers "F.Cu" "F.Mask" "F.Paste")
			(net "ZDEF_EXTB_TP_A2")
		)
	)
	(footprint ""
		(layer "F.Cu")
		(at 97.9424 -135.6868)
		(property "Reference" "R139"
			(at 0 0 0)
			(layer "F.SilkS")
			(hide yes)
			(effects
				(font
					(size 1.27 1.27)
				)
			)
		)
		(property "Value" "8K2R2J-3-GP"
			(at 0.064008 -3.993896 0)
			(unlocked yes)
			(layer "F.Fab")
			(hide yes)
			(effects
				(font
					(size 1.016 1.016)
					(thickness 0.1524)
				)
			)
		)
		(property "Device Type" "R402H16"
			(at 0.064008 -5.517896 0)
			(unlocked yes)
			(layer "F.Fab")
			(hide yes)
			(effects
				(font
					(size 1.016 1.016)
					(thickness 0.1524)
				)
			)
		)
		(duplicate_pad_numbers_are_jumpers no)
		(fp_line
			(start -0.508 -0.9398)
			(end -0.508 0.9398)
			(stroke
				(width 0.1524)
				(type default)
			)
			(layer "F.SilkS")
		)
		(fp_line
			(start 0.508 -0.9398)
			(end -0.508 -0.9398)
			(stroke
				(width 0.1524)
				(type default)
			)
			(layer "F.SilkS")
		)
		(fp_rect
			(start -0.508 0.9398)
			(end 0.508 -0.9398)
			(stroke
				(width 0)
				(type default)
			)
			(fill no)
			(layer "F.CrtYd")
		)
		(fp_rect
			(start -0.508 0.9398)
			(end 0.508 -0.9398)
			(stroke
				(width 0)
				(type default)
			)
			(fill no)
			(layer "F.Fab")
		)
		(pad "1" smd custom
			(at 0 -0.4445)
			(size 0.1397 0.1397)
			(layers "F.Cu" "F.Mask" "F.Paste")
			(net "EEPROM_WP")
			(options
				(clearance outline)
				(anchor circle)
			)
			(primitives
				(gr_poly
					(pts
						(arc
							(start -0.1778 -0.2794)
							(mid -0.249642 -0.249642)
							(end -0.2794 -0.1778)
						)
						(arc
							(start -0.2794 0.1778)
							(mid -0.249642 0.249642)
							(end -0.1778 0.2794)
						)
						(arc
							(start 0.1778 0.2794)
							(mid 0.249642 0.249642)
							(end 0.2794 0.1778)
						)
						(arc
							(start 0.2794 -0.1778)
							(mid 0.249642 -0.249642)
							(end 0.1778 -0.2794)
						)
					)
					(width 0)
					(fill yes)
				)
			)
		)
		(pad "2" smd custom
			(at 0 0.4445)
			(size 0.1397 0.1397)
			(layers "F.Cu" "F.Mask" "F.Paste")
			(net "GND")
			(options
				(clearance outline)
				(anchor circle)
			)
			(primitives
				(gr_poly
					(pts
						(arc
							(start -0.1778 -0.2794)
							(mid -0.249642 -0.249642)
							(end -0.2794 -0.1778)
						)
						(arc
							(start -0.2794 0.1778)
							(mid -0.249642 0.249642)
							(end -0.1778 0.2794)
						)
						(arc
							(start 0.1778 0.2794)
							(mid 0.249642 0.249642)
							(end 0.2794 0.1778)
						)
						(arc
							(start 0.2794 -0.1778)
							(mid 0.249642 -0.249642)
							(end 0.1778 -0.2794)
						)
					)
					(width 0)
					(fill yes)
				)
			)
		)
	)
	(footprint ""
		(layer "F.Cu")
		(at 93.748352 -134.411974 -90)
		(property "Reference" "U26"
			(at 0 0 270)
			(layer "F.SilkS")
			(hide yes)
			(effects
				(font
					(size 1.27 1.27)
				)
			)
		)
		(property "Value" "24LC64-I-SN-GP"
			(at -3.707384 -1.5367 270)
			(unlocked yes)
			(layer "F.Fab")
			(hide yes)
			(effects
				(font
					(size 1.016 1.016)
					(thickness 0.1524)
				)
			)
		)
		(property "Device Type" "SOIC8H69"
			(at -3.707384 -3.0607 270)
			(unlocked yes)
			(layer "F.Fab")
			(hide yes)
			(effects
				(font
					(size 1.016 1.016)
					(thickness 0.1524)
				)
			)
		)
		(duplicate_pad_numbers_are_jumpers no)
		(fp_line
			(start -2.6289 3.4417)
			(end -2.6289 1.4732)
			(stroke
				(width 0.381)
				(type default)
			)
			(layer "F.SilkS")
		)
		(fp_line
			(start -2.7432 1.4224)
			(end -2.6416 1.4224)
			(stroke
				(width 0.1524)
				(type default)
			)
			(layer "F.SilkS")
		)
		(fp_line
			(start -2.7432 1.4224)
			(end 2.1336 1.4224)
			(stroke
				(width 0.1524)
				(type default)
			)
			(layer "F.SilkS")
		)
		(fp_line
			(start 2.1336 1.4224)
			(end 2.1336 -1.4224)
			(stroke
				(width 0.1524)
				(type default)
			)
			(layer "F.SilkS")
		)
		(fp_line
			(start -2.1844 -0.0508)
			(end -2.7178 0.508)
			(stroke
				(width 0.1524)
				(type default)
			)
			(layer "F.SilkS")
		)
		(fp_line
			(start -2.7178 -0.508)
			(end -2.1844 -0.0508)
			(stroke
				(width 0.1524)
				(type default)
			)
			(layer "F.SilkS")
		)
		(fp_line
			(start -2.7432 -1.4224)
			(end -2.7432 1.4224)
			(stroke
				(width 0.1524)
				(type default)
			)
			(layer "F.SilkS")
		)
		(fp_line
			(start 2.1336 -1.4224)
			(end -2.7432 -1.4224)
			(stroke
				(width 0.1524)
				(type default)
			)
			(layer "F.SilkS")
		)
		(fp_poly
			(pts
				(xy -2.2098 -1.4224) (xy -2.2098 1.4224) (xy 2.2098 1.4224) (xy 2.2098 -1.4224)
			)
			(stroke
				(width 0)
				(type default)
			)
			(fill yes)
			(layer "F.SilkS")
		)
		(fp_rect
			(start -2.450084 2.999994)
			(end 2.450084 -2.999994)
			(stroke
				(width 0)
				(type default)
			)
			(fill no)
			(layer "F.CrtYd")
		)
		(fp_poly
			(pts
				(xy -2.8194 3.6322) (xy -2.8194 -3.6322) (xy 2.8194 -3.6322) (xy 2.8194 1.18364) (xy 2.450084 1.18364)
				(xy 2.450084 -2.999994) (xy -2.450084 -2.999994) (xy -2.450084 2.999994) (xy 2.450084 2.999994)
				(xy 2.450084 1.18618) (xy 2.8194 1.18618) (xy 2.8194 3.6322)
			)
			(stroke
				(width 0)
				(type default)
			)
			(fill no)
			(layer "F.CrtYd")
		)
		(fp_rect
			(start -2.8194 3.6322)
			(end 2.8194 -3.6322)
			(stroke
				(width 0)
				(type default)
			)
			(fill no)
			(layer "F.Fab")
		)
		(pad "1" smd rect
			(at -1.905 2.54 270)
			(size 0.635 1.651)
			(layers "F.Cu" "F.Mask" "F.Paste")
			(net "EEPROM_A0")
		)
		(pad "2" smd rect
			(at -0.635 2.54 270)
			(size 0.635 1.651)
			(layers "F.Cu" "F.Mask" "F.Paste")
			(net "EEPROM_A1")
		)
		(pad "3" smd rect
			(at 0.635 2.54 270)
			(size 0.635 1.651)
			(layers "F.Cu" "F.Mask" "F.Paste")
			(net "EEPROM_A2")
		)
		(pad "4" smd rect
			(at 1.905 2.54 270)
			(size 0.635 1.651)
			(layers "F.Cu" "F.Mask" "F.Paste")
			(net "GND")
		)
		(pad "5" smd rect
			(at 1.905 -2.54 270)
			(size 0.635 1.651)
			(layers "F.Cu" "F.Mask" "F.Paste")
			(net "I2C_IOM_SDA")
		)
		(pad "6" smd rect
			(at 0.635 -2.54 270)
			(size 0.635 1.651)
			(layers "F.Cu" "F.Mask" "F.Paste")
			(net "I2C_IOM_SCL")
		)
		(pad "7" smd rect
			(at -0.635 -2.54 270)
			(size 0.635 1.651)
			(layers "F.Cu" "F.Mask" "F.Paste")
			(net "EEPROM_WP")
		)
		(pad "8" smd rect
			(at -1.905 -2.54 270)
			(size 0.635 1.651)
			(layers "F.Cu" "F.Mask" "F.Paste")
			(net "P3V3_STBY")
		)
	)
	(footprint ""
		(layer "F.Cu")
		(at 61.6458 -131.29768 180)
		(property "Reference" "R708"
			(at 0 0 180)
			(layer "F.SilkS")
			(hide yes)
			(effects
				(font
					(size 1.27 1.27)
				)
			)
		)
		(property "Value" "10KR2F-2-GP"
			(at 0.064008 -3.993896 180)
			(unlocked yes)
			(layer "F.Fab")
			(hide yes)
			(effects
				(font
					(size 1.016 1.016)
					(thickness 0.1524)
				)
			)
		)
		(property "Device Type" "R402H16"
			(at 0.064008 -5.517896 180)
			(unlocked yes)
			(layer "F.Fab")
			(hide yes)
			(effects
				(font
					(size 1.016 1.016)
					(thickness 0.1524)
				)
			)
		)
		(duplicate_pad_numbers_are_jumpers no)
		(fp_line
			(start 0.508 -0.9398)
			(end -0.508 -0.9398)
			(stroke
				(width 0.1524)
				(type default)
			)
			(layer "F.SilkS")
		)
		(fp_line
			(start -0.508 -0.9398)
			(end -0.508 0.9398)
			(stroke
				(width 0.1524)
				(type default)
			)
			(layer "F.SilkS")
		)
		(fp_rect
			(start -0.508 0.9398)
			(end 0.508 -0.9398)
			(stroke
				(width 0)
				(type default)
			)
			(fill no)
			(layer "F.CrtYd")
		)
		(fp_rect
			(start -0.508 0.9398)
			(end 0.508 -0.9398)
			(stroke
				(width 0)
				(type default)
			)
			(fill no)
			(layer "F.Fab")
		)
		(pad "1" smd custom
			(at 0 -0.4445 180)
			(size 0.1397 0.1397)
			(layers "F.Cu" "F.Mask" "F.Paste")
			(net "SCC_STBY_PWR_EN")
			(options
				(clearance outline)
				(anchor circle)
			)
			(primitives
				(gr_poly
					(pts
						(arc
							(start -0.1778 -0.2794)
							(mid -0.249642 -0.249642)
							(end -0.2794 -0.1778)
						)
						(arc
							(start -0.2794 0.1778)
							(mid -0.249642 0.249642)
							(end -0.1778 0.2794)
						)
						(arc
							(start 0.1778 0.2794)
							(mid 0.249642 0.249642)
							(end 0.2794 0.1778)
						)
						(arc
							(start 0.2794 -0.1778)
							(mid 0.249642 -0.249642)
							(end 0.1778 -0.2794)
						)
					)
					(width 0)
					(fill yes)
				)
			)
		)
		(pad "2" smd custom
			(at 0 0.4445 180)
			(size 0.1397 0.1397)
			(layers "F.Cu" "F.Mask" "F.Paste")
			(net "GND")
			(options
				(clearance outline)
				(anchor circle)
			)
			(primitives
				(gr_poly
					(pts
						(arc
							(start -0.1778 -0.2794)
							(mid -0.249642 -0.249642)
							(end -0.2794 -0.1778)
						)
						(arc
							(start -0.2794 0.1778)
							(mid -0.249642 0.249642)
							(end -0.1778 0.2794)
						)
						(arc
							(start 0.1778 0.2794)
							(mid 0.249642 0.249642)
							(end 0.2794 0.1778)
						)
						(arc
							(start 0.2794 -0.1778)
							(mid 0.249642 -0.249642)
							(end 0.1778 -0.2794)
						)
					)
					(width 0)
					(fill yes)
				)
			)
		)
	)
	(footprint ""
		(layer "F.Cu")
		(at 191.516 -48.387)
		(property "Reference" "R652"
			(at 0 0 0)
			(layer "F.SilkS")
			(hide yes)
			(effects
				(font
					(size 1.27 1.27)
				)
			)
		)
		(property "Value" "10KR2F-2-GP"
			(at 0.064008 -3.993896 0)
			(unlocked yes)
			(layer "F.Fab")
			(hide yes)
			(effects
				(font
					(size 1.016 1.016)
					(thickness 0.1524)
				)
			)
		)
		(property "Device Type" "R402H16"
			(at 0.064008 -5.517896 0)
			(unlocked yes)
			(layer "F.Fab")
			(hide yes)
			(effects
				(font
					(size 1.016 1.016)
					(thickness 0.1524)
				)
			)
		)
		(duplicate_pad_numbers_are_jumpers no)
		(fp_line
			(start -0.508 -0.9398)
			(end -0.508 0.9398)
			(stroke
				(width 0.1524)
				(type default)
			)
			(layer "F.SilkS")
		)
		(fp_line
			(start 0.508 -0.9398)
			(end -0.508 -0.9398)
			(stroke
				(width 0.1524)
				(type default)
			)
			(layer "F.SilkS")
		)
		(fp_rect
			(start -0.508 0.9398)
			(end 0.508 -0.9398)
			(stroke
				(width 0)
				(type default)
			)
			(fill no)
			(layer "F.CrtYd")
		)
		(fp_rect
			(start -0.508 0.9398)
			(end 0.508 -0.9398)
			(stroke
				(width 0)
				(type default)
			)
			(fill no)
			(layer "F.Fab")
		)
		(pad "1" smd custom
			(at 0 -0.4445)
			(size 0.1397 0.1397)
			(layers "F.Cu" "F.Mask" "F.Paste")
			(net "LSI_SCAN_EN")
			(options
				(clearance outline)
				(anchor circle)
			)
			(primitives
				(gr_poly
					(pts
						(arc
							(start -0.1778 -0.2794)
							(mid -0.249642 -0.249642)
							(end -0.2794 -0.1778)
						)
						(arc
							(start -0.2794 0.1778)
							(mid -0.249642 0.249642)
							(end -0.1778 0.2794)
						)
						(arc
							(start 0.1778 0.2794)
							(mid 0.249642 0.249642)
							(end 0.2794 0.1778)
						)
						(arc
							(start 0.2794 -0.1778)
							(mid 0.249642 -0.249642)
							(end 0.1778 -0.2794)
						)
					)
					(width 0)
					(fill yes)
				)
			)
		)
		(pad "2" smd custom
			(at 0 0.4445)
			(size 0.1397 0.1397)
			(layers "F.Cu" "F.Mask" "F.Paste")
			(net "GND")
			(options
				(clearance outline)
				(anchor circle)
			)
			(primitives
				(gr_poly
					(pts
						(arc
							(start -0.1778 -0.2794)
							(mid -0.249642 -0.249642)
							(end -0.2794 -0.1778)
						)
						(arc
							(start -0.2794 0.1778)
							(mid -0.249642 0.249642)
							(end -0.1778 0.2794)
						)
						(arc
							(start 0.1778 0.2794)
							(mid 0.249642 0.249642)
							(end 0.2794 0.1778)
						)
						(arc
							(start 0.2794 -0.1778)
							(mid 0.249642 -0.249642)
							(end 0.1778 -0.2794)
						)
					)
					(width 0)
					(fill yes)
				)
			)
		)
	)
	(footprint ""
		(layer "F.Cu")
		(at 98.622866 -148.727922 -90)
		(property "Reference" "R35"
			(at 0 0 270)
			(layer "F.SilkS")
			(hide yes)
			(effects
				(font
					(size 1.27 1.27)
				)
			)
		)
		(property "Value" "4K7R2F-GP"
			(at 0.064008 -3.993896 270)
			(unlocked yes)
			(layer "F.Fab")
			(hide yes)
			(effects
				(font
					(size 1.016 1.016)
					(thickness 0.1524)
				)
			)
		)
		(property "Device Type" "R402H16"
			(at 0.064008 -5.517896 270)
			(unlocked yes)
			(layer "F.Fab")
			(hide yes)
			(effects
				(font
					(size 1.016 1.016)
					(thickness 0.1524)
				)
			)
		)
		(duplicate_pad_numbers_are_jumpers no)
		(fp_line
			(start -0.508 -0.9398)
			(end -0.508 0.9398)
			(stroke
				(width 0.1524)
				(type default)
			)
			(layer "F.SilkS")
		)
		(fp_line
			(start 0.508 -0.9398)
			(end -0.508 -0.9398)
			(stroke
				(width 0.1524)
				(type default)
			)
			(layer "F.SilkS")
		)
		(fp_rect
			(start -0.508 0.9398)
			(end 0.508 -0.9398)
			(stroke
				(width 0)
				(type default)
			)
			(fill no)
			(layer "F.CrtYd")
		)
		(fp_rect
			(start -0.508 0.9398)
			(end 0.508 -0.9398)
			(stroke
				(width 0)
				(type default)
			)
			(fill no)
			(layer "F.Fab")
		)
		(pad "1" smd custom
			(at 0 -0.4445 270)
			(size 0.1397 0.1397)
			(layers "F.Cu" "F.Mask" "F.Paste")
			(net "P3V3_STBY")
			(options
				(clearance outline)
				(anchor circle)
			)
			(primitives
				(gr_poly
					(pts
						(arc
							(start -0.1778 -0.2794)
							(mid -0.249642 -0.249642)
							(end -0.2794 -0.1778)
						)
						(arc
							(start -0.2794 0.1778)
							(mid -0.249642 0.249642)
							(end -0.1778 0.2794)
						)
						(arc
							(start 0.1778 0.2794)
							(mid 0.249642 0.249642)
							(end 0.2794 0.1778)
						)
						(arc
							(start 0.2794 -0.1778)
							(mid 0.249642 -0.249642)
							(end 0.1778 -0.2794)
						)
					)
					(width 0)
					(fill yes)
				)
			)
		)
		(pad "2" smd custom
			(at 0 0.4445 270)
			(size 0.1397 0.1397)
			(layers "F.Cu" "F.Mask" "F.Paste")
			(net "USB_EN_3")
			(options
				(clearance outline)
				(anchor circle)
			)
			(primitives
				(gr_poly
					(pts
						(arc
							(start -0.1778 -0.2794)
							(mid -0.249642 -0.249642)
							(end -0.2794 -0.1778)
						)
						(arc
							(start -0.2794 0.1778)
							(mid -0.249642 0.249642)
							(end -0.1778 0.2794)
						)
						(arc
							(start 0.1778 0.2794)
							(mid 0.249642 0.249642)
							(end 0.2794 0.1778)
						)
						(arc
							(start 0.2794 -0.1778)
							(mid 0.249642 -0.249642)
							(end 0.1778 -0.2794)
						)
					)
					(width 0)
					(fill yes)
				)
			)
		)
	)
	(footprint ""
		(layer "F.Cu")
		(at 145.6944 -14.9352)
		(property "Reference" "Q205"
			(at 0 0 0)
			(layer "F.SilkS")
			(hide yes)
			(effects
				(font
					(size 1.27 1.27)
				)
			)
		)
		(property "Value" "SSM6P39TU-GP"
			(at 0.0508 -11.5824 0)
			(unlocked yes)
			(layer "F.Fab")
			(hide yes)
			(effects
				(font
					(size 1.016 1.016)
					(thickness 0.1524)
				)
			)
		)
		(property "Device Type" "UMT6H30"
			(at 0.0508 -13.1572 0)
			(unlocked yes)
			(layer "F.Fab")
			(hide yes)
			(effects
				(font
					(size 1.016 1.016)
					(thickness 0.1524)
				)
			)
		)
		(duplicate_pad_numbers_are_jumpers no)
		(fp_line
			(start -1.27 -0.36449)
			(end -1.27 0.36449)
			(stroke
				(width 0.1524)
				(type default)
			)
			(layer "F.SilkS")
		)
		(fp_line
			(start -1.27 -0.36449)
			(end 1.524 -0.36449)
			(stroke
				(width 0.1524)
				(type default)
			)
			(layer "F.SilkS")
		)
		(fp_line
			(start 1.09347 0)
			(end 1.45796 0.36449)
			(stroke
				(width 0.1524)
				(type default)
			)
			(layer "F.SilkS")
		)
		(fp_line
			(start 1.45796 -0.36449)
			(end 1.09347 0)
			(stroke
				(width 0.1524)
				(type default)
			)
			(layer "F.SilkS")
		)
		(fp_line
			(start 1.524 -0.36449)
			(end 1.45796 -0.36449)
			(stroke
				(width 0.1524)
				(type default)
			)
			(layer "F.SilkS")
		)
		(fp_line
			(start 1.524 -0.36449)
			(end 1.524 -1.82245)
			(stroke
				(width 0.508)
				(type default)
			)
			(layer "F.SilkS")
		)
		(fp_line
			(start 1.524 -0.36449)
			(end 1.524 0.36449)
			(stroke
				(width 0.1524)
				(type default)
			)
			(layer "F.SilkS")
		)
		(fp_line
			(start 1.524 0.36449)
			(end -1.27 0.36449)
			(stroke
				(width 0.1524)
				(type default)
			)
			(layer "F.SilkS")
		)
		(fp_poly
			(pts
				(xy -0.65024 0.36449) (xy -0.65024 -0.36449) (xy 0.65024 -0.36449) (xy 0.65024 0.36449)
			)
			(stroke
				(width 0)
				(type default)
			)
			(fill yes)
			(layer "F.SilkS")
		)
		(fp_poly
			(pts
				(xy 1.016 -1.0668) (xy 1.016 1.0668) (xy -1.016 1.0668) (xy -1.016 -1.0668)
			)
			(stroke
				(width 0)
				(type default)
			)
			(fill no)
			(layer "F.CrtYd")
		)
		(fp_poly
			(pts
				(xy -1.524 1.905) (xy 1.524 1.905) (xy 1.524 -1.06426) (xy 1.016 -1.06426) (xy 1.016 1.0668) (xy -1.016 1.0668)
				(xy -1.016 -1.0668) (xy 1.524 -1.0668) (xy 1.524 -1.905) (xy -1.524 -1.905)
			)
			(stroke
				(width 0)
				(type default)
			)
			(fill no)
			(layer "F.CrtYd")
		)
		(fp_poly
			(pts
				(xy -1.524 -1.905) (xy -1.524 1.905) (xy 1.524 1.905) (xy 1.524 -1.905)
			)
			(stroke
				(width 0)
				(type default)
			)
			(fill no)
			(layer "F.Fab")
		)
		(pad "1" smd rect
			(at 0.65024 -1.02489)
			(size 0.4064 0.8128)
			(layers "F.Cu" "F.Mask" "F.Paste")
			(net "P3V3_STBY")
		)
		(pad "2" smd rect
			(at 0 -1.02489)
			(size 0.4064 0.8128)
			(layers "F.Cu" "F.Mask" "F.Paste")
			(net "EXT2_LED_YELLOW_G1")
		)
		(pad "3" smd rect
			(at -0.65024 -1.02489)
			(size 0.4064 0.8128)
			(layers "F.Cu" "F.Mask" "F.Paste")
			(net "EXT2_LED_BLUE_D")
		)
		(pad "4" smd rect
			(at -0.65024 1.02489)
			(size 0.4064 0.8128)
			(layers "F.Cu" "F.Mask" "F.Paste")
			(net "P5V_STBY")
		)
		(pad "5" smd rect
			(at 0 1.02489)
			(size 0.4064 0.8128)
			(layers "F.Cu" "F.Mask" "F.Paste")
			(net "EXT2_LED_BLUE_G2")
		)
		(pad "6" smd rect
			(at 0.65024 1.02489)
			(size 0.4064 0.8128)
			(layers "F.Cu" "F.Mask" "F.Paste")
			(net "EXT2_LED_YELLOW_D1")
		)
	)
	(footprint ""
		(layer "F.Cu")
		(at 50.935128 -166.472362 180)
		(property "Reference" "C520"
			(at 0 0 180)
			(layer "F.SilkS")
			(hide yes)
			(effects
				(font
					(size 1.27 1.27)
				)
			)
		)
		(property "Value" "SCD1U25V2KX-2-GP"
			(at 1.1811 -2.7051 180)
			(unlocked yes)
			(layer "F.Fab")
			(hide yes)
			(effects
				(font
					(size 1.016 1.016)
					(thickness 0.1524)
				)
			)
		)
		(property "Device Type" "C402H22"
			(at 1.1811 -4.2291 180)
			(unlocked yes)
			(layer "F.Fab")
			(hide yes)
			(effects
				(font
					(size 1.016 1.016)
					(thickness 0.1524)
				)
			)
		)
		(duplicate_pad_numbers_are_jumpers no)
		(fp_rect
			(start -0.4318 0.9525)
			(end 0.4318 -0.9525)
			(stroke
				(width 0)
				(type default)
			)
			(fill no)
			(layer "F.CrtYd")
		)
		(fp_rect
			(start -0.4318 0.9525)
			(end 0.4318 -0.9525)
			(stroke
				(width 0)
				(type default)
			)
			(fill no)
			(layer "F.Fab")
		)
		(pad "1" smd custom
			(at 0 -0.4445 180)
			(size 0.1524 0.1524)
			(layers "F.Cu" "F.Mask" "F.Paste")
			(net "ADC_P2V5_STBY")
			(options
				(clearance outline)
				(anchor circle)
			)
			(primitives
				(gr_poly
					(pts
						(arc
							(start 0.3048 -0.2032)
							(mid 0.275042 -0.275042)
							(end 0.2032 -0.3048)
						)
						(arc
							(start -0.2032 -0.3048)
							(mid -0.275042 -0.275042)
							(end -0.3048 -0.2032)
						)
						(arc
							(start -0.3048 0.2032)
							(mid -0.275042 0.275042)
							(end -0.2032 0.3048)
						)
						(arc
							(start 0.2032 0.3048)
							(mid 0.275042 0.275042)
							(end 0.3048 0.2032)
						)
					)
					(width 0)
					(fill yes)
				)
			)
		)
		(pad "2" smd custom
			(at 0 0.4445 180)
			(size 0.1524 0.1524)
			(layers "F.Cu" "F.Mask" "F.Paste")
			(net "GND")
			(options
				(clearance outline)
				(anchor circle)
			)
			(primitives
				(gr_poly
					(pts
						(arc
							(start 0.3048 -0.2032)
							(mid 0.275042 -0.275042)
							(end 0.2032 -0.3048)
						)
						(arc
							(start -0.2032 -0.3048)
							(mid -0.275042 -0.275042)
							(end -0.3048 -0.2032)
						)
						(arc
							(start -0.3048 0.2032)
							(mid -0.275042 0.275042)
							(end -0.2032 0.3048)
						)
						(arc
							(start 0.2032 0.3048)
							(mid 0.275042 0.275042)
							(end 0.3048 0.2032)
						)
					)
					(width 0)
					(fill yes)
				)
			)
		)
	)
	(footprint ""
		(layer "F.Cu")
		(at 20.4724 -174.5488)
		(property "Reference" "R532"
			(at 0 0 0)
			(layer "F.SilkS")
			(hide yes)
			(effects
				(font
					(size 1.27 1.27)
				)
			)
		)
		(property "Value" "10KR2F-2-GP"
			(at 0.064008 -3.993896 0)
			(unlocked yes)
			(layer "F.Fab")
			(hide yes)
			(effects
				(font
					(size 1.016 1.016)
					(thickness 0.1524)
				)
			)
		)
		(property "Device Type" "R402H16"
			(at 0.064008 -5.517896 0)
			(unlocked yes)
			(layer "F.Fab")
			(hide yes)
			(effects
				(font
					(size 1.016 1.016)
					(thickness 0.1524)
				)
			)
		)
		(duplicate_pad_numbers_are_jumpers no)
		(fp_line
			(start -0.508 -0.9398)
			(end -0.508 0.9398)
			(stroke
				(width 0.1524)
				(type default)
			)
			(layer "F.SilkS")
		)
		(fp_line
			(start 0.508 -0.9398)
			(end -0.508 -0.9398)
			(stroke
				(width 0.1524)
				(type default)
			)
			(layer "F.SilkS")
		)
		(fp_rect
			(start -0.508 0.9398)
			(end 0.508 -0.9398)
			(stroke
				(width 0)
				(type default)
			)
			(fill no)
			(layer "F.CrtYd")
		)
		(fp_rect
			(start -0.508 0.9398)
			(end 0.508 -0.9398)
			(stroke
				(width 0)
				(type default)
			)
			(fill no)
			(layer "F.Fab")
		)
		(pad "1" smd custom
			(at 0 -0.4445)
			(size 0.1397 0.1397)
			(layers "F.Cu" "F.Mask" "F.Paste")
			(net "P3V3_STBY")
			(options
				(clearance outline)
				(anchor circle)
			)
			(primitives
				(gr_poly
					(pts
						(arc
							(start -0.1778 -0.2794)
							(mid -0.249642 -0.249642)
							(end -0.2794 -0.1778)
						)
						(arc
							(start -0.2794 0.1778)
							(mid -0.249642 0.249642)
							(end -0.1778 0.2794)
						)
						(arc
							(start 0.1778 0.2794)
							(mid 0.249642 0.249642)
							(end 0.2794 0.1778)
						)
						(arc
							(start 0.2794 -0.1778)
							(mid 0.249642 -0.249642)
							(end 0.1778 -0.2794)
						)
					)
					(width 0)
					(fill yes)
				)
			)
		)
		(pad "2" smd custom
			(at 0 0.4445)
			(size 0.1397 0.1397)
			(layers "F.Cu" "F.Mask" "F.Paste")
			(net "PWRGD_P1V2_STBY")
			(options
				(clearance outline)
				(anchor circle)
			)
			(primitives
				(gr_poly
					(pts
						(arc
							(start -0.1778 -0.2794)
							(mid -0.249642 -0.249642)
							(end -0.2794 -0.1778)
						)
						(arc
							(start -0.2794 0.1778)
							(mid -0.249642 0.249642)
							(end -0.1778 0.2794)
						)
						(arc
							(start 0.1778 0.2794)
							(mid 0.249642 0.249642)
							(end 0.2794 0.1778)
						)
						(arc
							(start 0.2794 -0.1778)
							(mid 0.249642 -0.249642)
							(end 0.1778 -0.2794)
						)
					)
					(width 0)
					(fill yes)
				)
			)
		)
	)
	(footprint ""
		(layer "F.Cu")
		(at 185.928 -48.4378 180)
		(property "Reference" "R675"
			(at 0 0 180)
			(layer "F.SilkS")
			(hide yes)
			(effects
				(font
					(size 1.27 1.27)
				)
			)
		)
		(property "Value" "10KR2F-2-GP"
			(at 0.064008 -3.993896 180)
			(unlocked yes)
			(layer "F.Fab")
			(hide yes)
			(effects
				(font
					(size 1.016 1.016)
					(thickness 0.1524)
				)
			)
		)
		(property "Device Type" "R402H16"
			(at 0.064008 -5.517896 180)
			(unlocked yes)
			(layer "F.Fab")
			(hide yes)
			(effects
				(font
					(size 1.016 1.016)
					(thickness 0.1524)
				)
			)
		)
		(duplicate_pad_numbers_are_jumpers no)
		(fp_line
			(start 0.508 -0.9398)
			(end -0.508 -0.9398)
			(stroke
				(width 0.1524)
				(type default)
			)
			(layer "F.SilkS")
		)
		(fp_line
			(start -0.508 -0.9398)
			(end -0.508 0.9398)
			(stroke
				(width 0.1524)
				(type default)
			)
			(layer "F.SilkS")
		)
		(fp_rect
			(start -0.508 0.9398)
			(end 0.508 -0.9398)
			(stroke
				(width 0)
				(type default)
			)
			(fill no)
			(layer "F.CrtYd")
		)
		(fp_rect
			(start -0.508 0.9398)
			(end 0.508 -0.9398)
			(stroke
				(width 0)
				(type default)
			)
			(fill no)
			(layer "F.Fab")
		)
		(pad "1" smd custom
			(at 0 -0.4445 180)
			(size 0.1397 0.1397)
			(layers "F.Cu" "F.Mask" "F.Paste")
			(net "P1V8")
			(options
				(clearance outline)
				(anchor circle)
			)
			(primitives
				(gr_poly
					(pts
						(arc
							(start -0.1778 -0.2794)
							(mid -0.249642 -0.249642)
							(end -0.2794 -0.1778)
						)
						(arc
							(start -0.2794 0.1778)
							(mid -0.249642 0.249642)
							(end -0.1778 0.2794)
						)
						(arc
							(start 0.1778 0.2794)
							(mid 0.249642 0.249642)
							(end 0.2794 0.1778)
						)
						(arc
							(start 0.2794 -0.1778)
							(mid 0.249642 -0.249642)
							(end 0.1778 -0.2794)
						)
					)
					(width 0)
					(fill yes)
				)
			)
		)
		(pad "2" smd custom
			(at 0 0.4445 180)
			(size 0.1397 0.1397)
			(layers "F.Cu" "F.Mask" "F.Paste")
			(net "XM_RB")
			(options
				(clearance outline)
				(anchor circle)
			)
			(primitives
				(gr_poly
					(pts
						(arc
							(start -0.1778 -0.2794)
							(mid -0.249642 -0.249642)
							(end -0.2794 -0.1778)
						)
						(arc
							(start -0.2794 0.1778)
							(mid -0.249642 0.249642)
							(end -0.1778 0.2794)
						)
						(arc
							(start 0.1778 0.2794)
							(mid 0.249642 0.249642)
							(end 0.2794 0.1778)
						)
						(arc
							(start 0.2794 -0.1778)
							(mid 0.249642 -0.249642)
							(end 0.1778 -0.2794)
						)
					)
					(width 0)
					(fill yes)
				)
			)
		)
	)
	(footprint ""
		(layer "F.Cu")
		(at 207.946752 -102.85857)
		(property "Reference" "R608"
			(at 0 0 0)
			(layer "F.SilkS")
			(hide yes)
			(effects
				(font
					(size 1.27 1.27)
				)
			)
		)
		(property "Value" "0R2J-2-GP"
			(at 0.064008 -3.993896 0)
			(unlocked yes)
			(layer "F.Fab")
			(hide yes)
			(effects
				(font
					(size 1.016 1.016)
					(thickness 0.1524)
				)
			)
		)
		(property "Device Type" "R402H16"
			(at 0.064008 -5.517896 0)
			(unlocked yes)
			(layer "F.Fab")
			(hide yes)
			(effects
				(font
					(size 1.016 1.016)
					(thickness 0.1524)
				)
			)
		)
		(duplicate_pad_numbers_are_jumpers no)
		(fp_line
			(start -0.508 -0.9398)
			(end -0.508 0.9398)
			(stroke
				(width 0.1524)
				(type default)
			)
			(layer "F.SilkS")
		)
		(fp_line
			(start 0.508 -0.9398)
			(end -0.508 -0.9398)
			(stroke
				(width 0.1524)
				(type default)
			)
			(layer "F.SilkS")
		)
		(fp_rect
			(start -0.508 0.9398)
			(end 0.508 -0.9398)
			(stroke
				(width 0)
				(type default)
			)
			(fill no)
			(layer "F.CrtYd")
		)
		(fp_rect
			(start -0.508 0.9398)
			(end 0.508 -0.9398)
			(stroke
				(width 0)
				(type default)
			)
			(fill no)
			(layer "F.Fab")
		)
		(pad "1" smd custom
			(at 0 -0.4445)
			(size 0.1397 0.1397)
			(layers "F.Cu" "F.Mask" "F.Paste")
			(net "IOC_EEPROM_SDA")
			(options
				(clearance outline)
				(anchor circle)
			)
			(primitives
				(gr_poly
					(pts
						(arc
							(start -0.1778 -0.2794)
							(mid -0.249642 -0.249642)
							(end -0.2794 -0.1778)
						)
						(arc
							(start -0.2794 0.1778)
							(mid -0.249642 0.249642)
							(end -0.1778 0.2794)
						)
						(arc
							(start 0.1778 0.2794)
							(mid 0.249642 0.249642)
							(end 0.2794 0.1778)
						)
						(arc
							(start 0.2794 -0.1778)
							(mid 0.249642 -0.249642)
							(end 0.1778 -0.2794)
						)
					)
					(width 0)
					(fill yes)
				)
			)
		)
		(pad "2" smd custom
			(at 0 0.4445)
			(size 0.1397 0.1397)
			(layers "F.Cu" "F.Mask" "F.Paste")
			(net "SBL_SDA")
			(options
				(clearance outline)
				(anchor circle)
			)
			(primitives
				(gr_poly
					(pts
						(arc
							(start -0.1778 -0.2794)
							(mid -0.249642 -0.249642)
							(end -0.2794 -0.1778)
						)
						(arc
							(start -0.2794 0.1778)
							(mid -0.249642 0.249642)
							(end -0.1778 0.2794)
						)
						(arc
							(start 0.1778 0.2794)
							(mid 0.249642 0.249642)
							(end 0.2794 0.1778)
						)
						(arc
							(start 0.2794 -0.1778)
							(mid 0.249642 -0.249642)
							(end 0.1778 -0.2794)
						)
					)
					(width 0)
					(fill yes)
				)
			)
		)
	)
	(footprint ""
		(layer "F.Cu")
		(at 212.3567 -125.134116 180)
		(property "Reference" "C249"
			(at 0 0 180)
			(layer "F.SilkS")
			(hide yes)
			(effects
				(font
					(size 1.27 1.27)
				)
			)
		)
		(property "Value" "SC10U6D3V5KX-4GP"
			(at -0.0762 -6.1214 180)
			(unlocked yes)
			(layer "F.Fab")
			(hide yes)
			(effects
				(font
					(size 1.016 1.016)
					(thickness 0.1524)
				)
			)
		)
		(property "Device Type" "C805H58"
			(at -0.0762 -8.1534 180)
			(unlocked yes)
			(layer "F.Fab")
			(hide yes)
			(effects
				(font
					(size 1.016 1.016)
					(thickness 0.1524)
				)
			)
		)
		(duplicate_pad_numbers_are_jumpers no)
		(fp_line
			(start 0.635 0)
			(end -0.635 0)
			(stroke
				(width 0.508)
				(type default)
			)
			(layer "F.SilkS")
		)
		(fp_rect
			(start -0.9652 1.778)
			(end 0.9652 -1.778)
			(stroke
				(width 0)
				(type default)
			)
			(fill no)
			(layer "F.CrtYd")
		)
		(fp_poly
			(pts
				(xy -0.9652 -1.778) (xy 0.9652 -1.778) (xy 0.9652 1.778) (xy -0.9652 1.778)
			)
			(stroke
				(width 0)
				(type default)
			)
			(fill no)
			(layer "F.Fab")
		)
		(pad "1" smd rect
			(at 0 -0.9652 180)
			(size 1.397 1.143)
			(layers "F.Cu" "F.Mask" "F.Paste")
			(net "P1V5_OUT")
		)
		(pad "2" smd rect
			(at 0 0.9652 180)
			(size 1.397 1.143)
			(layers "F.Cu" "F.Mask" "F.Paste")
			(net "GND")
		)
	)
	(footprint ""
		(layer "F.Cu")
		(at 92.71 -179.3748 90)
		(property "Reference" "U106"
			(at 0 0 90)
			(layer "F.SilkS")
			(hide yes)
			(effects
				(font
					(size 1.27 1.27)
				)
			)
		)
		(property "Value" "SNLVC1G14DBVR-GP"
			(at 0 -5.1308 90)
			(unlocked yes)
			(layer "F.Fab")
			(hide yes)
			(effects
				(font
					(size 1.016 1.016)
					(thickness 0.1524)
				)
			)
		)
		(property "Device Type" "SOT-23-5H58"
			(at 0 -6.7564 90)
			(unlocked yes)
			(layer "F.Fab")
			(hide yes)
			(effects
				(font
					(size 1.016 1.016)
					(thickness 0.1524)
				)
			)
		)
		(duplicate_pad_numbers_are_jumpers no)
		(fp_line
			(start 1.778 -2.286)
			(end -1.778 -2.286)
			(stroke
				(width 0.1524)
				(type default)
			)
			(layer "F.SilkS")
		)
		(fp_line
			(start -1.778 -2.286)
			(end -1.778 2.286)
			(stroke
				(width 0.1524)
				(type default)
			)
			(layer "F.SilkS")
		)
		(fp_line
			(start -0.7112 2.2352)
			(end -1.7272 2.2352)
			(stroke
				(width 0.3302)
				(type default)
			)
			(layer "F.SilkS")
		)
		(fp_line
			(start -1.7272 2.2352)
			(end -1.7272 0.762)
			(stroke
				(width 0.3302)
				(type default)
			)
			(layer "F.SilkS")
		)
		(fp_line
			(start 1.778 2.286)
			(end 1.778 -2.286)
			(stroke
				(width 0.1524)
				(type default)
			)
			(layer "F.SilkS")
		)
		(fp_line
			(start -0.254 2.286)
			(end 1.778 2.286)
			(stroke
				(width 0.1524)
				(type default)
			)
			(layer "F.SilkS")
		)
		(fp_line
			(start -1.778 2.286)
			(end 1.778 2.286)
			(stroke
				(width 0.1524)
				(type default)
			)
			(layer "F.SilkS")
		)
		(fp_line
			(start -1.778 2.286)
			(end -0.254 2.286)
			(stroke
				(width 0.1524)
				(type default)
			)
			(layer "F.SilkS")
		)
		(fp_poly
			(pts
				(xy -0.9652 2.4384) (xy -1.3208 2.794) (xy -0.6096 2.794)
			)
			(stroke
				(width 0)
				(type default)
			)
			(fill yes)
			(layer "F.SilkS")
		)
		(fp_rect
			(start -1.778 2.286)
			(end 1.778 -2.286)
			(stroke
				(width 0)
				(type default)
			)
			(fill no)
			(layer "F.CrtYd")
		)
		(fp_rect
			(start -1.778 2.286)
			(end 1.778 -2.286)
			(stroke
				(width 0)
				(type default)
			)
			(fill no)
			(layer "F.Fab")
		)
		(pad "1" smd rect
			(at -0.94996 1.143 90)
			(size 0.508 1.524)
			(layers "F.Cu" "F.Mask" "F.Paste")
			(net "Net_132")
		)
		(pad "2" smd rect
			(at 0 1.143 90)
			(size 0.508 1.524)
			(layers "F.Cu" "F.Mask" "F.Paste")
			(net "PWRGD_P3V3_STBY")
		)
		(pad "3" smd rect
			(at 0.94996 1.143 90)
			(size 0.508 1.524)
			(layers "F.Cu" "F.Mask" "F.Paste")
			(net "GND")
		)
		(pad "4" smd rect
			(at 0.94996 -1.143 90)
			(size 0.508 1.524)
			(layers "F.Cu" "F.Mask" "F.Paste")
			(net "PWRGD_P3V3_STBY_N")
		)
		(pad "5" smd rect
			(at -0.94996 -1.143 90)
			(size 0.508 1.524)
			(layers "F.Cu" "F.Mask" "F.Paste")
			(net "P3V3_STBY")
		)
	)
	(footprint ""
		(layer "F.Cu")
		(at 156.464 -141.0716 -90)
		(property "Reference" "G5"
			(at 0 0 270)
			(layer "F.SilkS")
			(hide yes)
			(effects
				(font
					(size 1.27 1.27)
				)
			)
		)
		(property "Value" "COPPER-CLOSE-GP-U"
			(at 0.0762 -2.8702 270)
			(unlocked yes)
			(layer "F.Fab")
			(hide yes)
			(effects
				(font
					(size 1.016 1.016)
					(thickness 0.1524)
				)
			)
		)
		(property "Device Type" "CON2C-U"
			(at 0.0762 -4.3942 270)
			(unlocked yes)
			(layer "F.Fab")
			(hide yes)
			(effects
				(font
					(size 1.016 1.016)
					(thickness 0.1524)
				)
			)
		)
		(duplicate_pad_numbers_are_jumpers no)
		(fp_rect
			(start -0.9398 0.9652)
			(end 0.9398 -0.9652)
			(stroke
				(width 0)
				(type default)
			)
			(fill no)
			(layer "F.CrtYd")
		)
		(fp_rect
			(start -0.9398 0.9652)
			(end 0.9398 -0.9652)
			(stroke
				(width 0)
				(type default)
			)
			(fill no)
			(layer "F.Fab")
		)
		(pad "1" smd custom
			(at 0 -0.5334 270)
			(size 0.17145 0.17145)
			(layers "F.Cu" "F.Mask" "F.Paste")
			(net "AGND_P1V8_STBY")
			(options
				(clearance outline)
				(anchor circle)
			)
			(primitives
				(gr_poly
					(pts
						(xy -0.127 0.3429) (xy -0.127 0.1651) (xy -0.635 -0.3429) (xy 0.635 -0.3429) (xy 0.127 0.1651)
						(xy 0.127 0.3429)
					)
					(width 0)
					(fill yes)
				)
			)
		)
		(pad "2" smd custom
			(at 0 0.5334 270)
			(size 0.17145 0.17145)
			(layers "F.Cu" "F.Mask" "F.Paste")
			(net "GND")
			(options
				(clearance outline)
				(anchor circle)
			)
			(primitives
				(gr_poly
					(pts
						(xy -0.635 0.3429) (xy -0.127 -0.1651) (xy -0.127 -0.3429) (xy 0.127 -0.3429) (xy 0.127 -0.1651)
						(xy 0.635 0.3429)
					)
					(width 0)
					(fill yes)
				)
			)
		)
	)
	(footprint ""
		(layer "F.Cu")
		(at 200.7616 -106.1974)
		(property "Reference" "R553"
			(at 0 0 0)
			(layer "F.SilkS")
			(hide yes)
			(effects
				(font
					(size 1.27 1.27)
				)
			)
		)
		(property "Value" "10KR2F-2-GP"
			(at 0.064008 -3.993896 0)
			(unlocked yes)
			(layer "F.Fab")
			(hide yes)
			(effects
				(font
					(size 1.016 1.016)
					(thickness 0.1524)
				)
			)
		)
		(property "Device Type" "R402H16"
			(at 0.064008 -5.517896 0)
			(unlocked yes)
			(layer "F.Fab")
			(hide yes)
			(effects
				(font
					(size 1.016 1.016)
					(thickness 0.1524)
				)
			)
		)
		(duplicate_pad_numbers_are_jumpers no)
		(fp_line
			(start -0.508 -0.9398)
			(end -0.508 0.9398)
			(stroke
				(width 0.1524)
				(type default)
			)
			(layer "F.SilkS")
		)
		(fp_line
			(start 0.508 -0.9398)
			(end -0.508 -0.9398)
			(stroke
				(width 0.1524)
				(type default)
			)
			(layer "F.SilkS")
		)
		(fp_rect
			(start -0.508 0.9398)
			(end 0.508 -0.9398)
			(stroke
				(width 0)
				(type default)
			)
			(fill no)
			(layer "F.CrtYd")
		)
		(fp_rect
			(start -0.508 0.9398)
			(end 0.508 -0.9398)
			(stroke
				(width 0)
				(type default)
			)
			(fill no)
			(layer "F.Fab")
		)
		(pad "1" smd custom
			(at 0 -0.4445)
			(size 0.1397 0.1397)
			(layers "F.Cu" "F.Mask" "F.Paste")
			(net "P0V975")
			(options
				(clearance outline)
				(anchor circle)
			)
			(primitives
				(gr_poly
					(pts
						(arc
							(start -0.1778 -0.2794)
							(mid -0.249642 -0.249642)
							(end -0.2794 -0.1778)
						)
						(arc
							(start -0.2794 0.1778)
							(mid -0.249642 0.249642)
							(end -0.1778 0.2794)
						)
						(arc
							(start 0.1778 0.2794)
							(mid 0.249642 0.249642)
							(end 0.2794 0.1778)
						)
						(arc
							(start 0.2794 -0.1778)
							(mid 0.249642 -0.249642)
							(end 0.1778 -0.2794)
						)
					)
					(width 0)
					(fill yes)
				)
			)
		)
		(pad "2" smd custom
			(at 0 0.4445)
			(size 0.1397 0.1397)
			(layers "F.Cu" "F.Mask" "F.Paste")
			(net "GND")
			(options
				(clearance outline)
				(anchor circle)
			)
			(primitives
				(gr_poly
					(pts
						(arc
							(start -0.1778 -0.2794)
							(mid -0.249642 -0.249642)
							(end -0.2794 -0.1778)
						)
						(arc
							(start -0.2794 0.1778)
							(mid -0.249642 0.249642)
							(end -0.1778 0.2794)
						)
						(arc
							(start 0.1778 0.2794)
							(mid 0.249642 0.249642)
							(end 0.2794 0.1778)
						)
						(arc
							(start 0.2794 -0.1778)
							(mid 0.249642 -0.249642)
							(end 0.1778 -0.2794)
						)
					)
					(width 0)
					(fill yes)
				)
			)
		)
	)
	(footprint ""
		(layer "F.Cu")
		(at 190.4238 -105.791)
		(property "Reference" "C265"
			(at 0 0 0)
			(layer "F.SilkS")
			(hide yes)
			(effects
				(font
					(size 1.27 1.27)
				)
			)
		)
		(property "Value" "SC22U6D3V6KX-2-GP"
			(at -0.0762 -5.1308 0)
			(unlocked yes)
			(layer "F.Fab")
			(hide yes)
			(effects
				(font
					(size 1.016 1.016)
					(thickness 0.1524)
				)
			)
		)
		(property "Device Type" "C1206H71"
			(at -0.127 -6.6548 0)
			(unlocked yes)
			(layer "F.Fab")
			(hide yes)
			(effects
				(font
					(size 1.016 1.016)
					(thickness 0.1524)
				)
			)
		)
		(duplicate_pad_numbers_are_jumpers no)
		(fp_line
			(start -1.016 -2.2352)
			(end 1.016 -2.2352)
			(stroke
				(width 0.1524)
				(type default)
			)
			(layer "F.SilkS")
		)
		(fp_line
			(start -1.016 -0.8382)
			(end -1.016 -2.2352)
			(stroke
				(width 0.1524)
				(type default)
			)
			(layer "F.SilkS")
		)
		(fp_line
			(start -1.016 2.2352)
			(end -1.016 0.8382)
			(stroke
				(width 0.1524)
				(type default)
			)
			(layer "F.SilkS")
		)
		(fp_line
			(start 1.016 -2.2352)
			(end 1.016 -0.8382)
			(stroke
				(width 0.1524)
				(type default)
			)
			(layer "F.SilkS")
		)
		(fp_line
			(start 1.016 0.8382)
			(end 1.016 2.2352)
			(stroke
				(width 0.1524)
				(type default)
			)
			(layer "F.SilkS")
		)
		(fp_line
			(start 1.016 2.2352)
			(end -1.016 2.2352)
			(stroke
				(width 0.1524)
				(type default)
			)
			(layer "F.SilkS")
		)
		(fp_rect
			(start -1.0922 2.3114)
			(end 1.0922 -2.3114)
			(stroke
				(width 0)
				(type default)
			)
			(fill no)
			(layer "F.CrtYd")
		)
		(fp_poly
			(pts
				(xy 1.0922 -2.3114) (xy 1.0922 2.3114) (xy -1.0922 2.3114) (xy -1.0922 -2.3114)
			)
			(stroke
				(width 0)
				(type default)
			)
			(fill no)
			(layer "F.Fab")
		)
		(pad "1" smd rect
			(at 0 -1.397)
			(size 1.651 1.27)
			(layers "F.Cu" "F.Mask" "F.Paste")
			(net "P0V975")
		)
		(pad "2" smd rect
			(at 0 1.397)
			(size 1.651 1.27)
			(layers "F.Cu" "F.Mask" "F.Paste")
			(net "GND")
		)
	)
	(footprint ""
		(layer "F.Cu")
		(at 217.043 -75.311 -45)
		(property "Reference" "VIA42"
			(at 0 0 315)
			(layer "F.SilkS")
			(hide yes)
			(effects
				(font
					(size 1.27 1.27)
				)
			)
		)
		(property "Value" "100OHM-8L-1D6MM-L18L16-GP"
			(at -3.721059 -4.508373 315)
			(unlocked yes)
			(layer "F.Fab")
			(hide yes)
			(effects
				(font
					(size 1.016 1.016)
					(thickness 0.1524)
				)
			)
		)
		(property "Device Type" "VIA-PCIE-4P-394076"
			(at -3.721059 -6.032502 315)
			(unlocked yes)
			(layer "F.Fab")
			(hide yes)
			(effects
				(font
					(size 1.016 1.016)
					(thickness 0.1524)
				)
			)
		)
		(duplicate_pad_numbers_are_jumpers no)
		(fp_poly
			(pts
				(xy -1.968472 -0.380877) (xy 1.968528 -0.380878) (xy 1.968527 0.381122) (xy -1.968472 0.381122)
			)
			(stroke
				(width 0)
				(type default)
			)
			(fill no)
			(layer "F.CrtYd")
		)
		(fp_poly
			(pts
				(xy -1.968472 -0.380877) (xy 1.968528 -0.380878) (xy 1.968527 0.381122) (xy -1.968472 0.381122)
			)
			(stroke
				(width 0)
				(type default)
			)
			(fill no)
			(layer "F.Fab")
		)
		(pad "1" thru_hole circle
			(at -1.5875 0 315)
			(size 0.508 0.508)
			(drill 0.254)
			(layers "*.Cu" "*.Mask")
			(remove_unused_layers no)
			(net "GND")
			(clearance 0.127)
			(thermal_gap 0.127)
		)
		(pad "2" thru_hole circle
			(at -0.571501 0 315)
			(size 0.508 0.508)
			(drill 0.254)
			(layers "*.Cu" "*.Mask")
			(remove_unused_layers no)
			(net "PHY_IOC_TO_CON_A_1_DP")
			(clearance 0.127)
			(thermal_gap 0.127)
		)
		(pad "3" thru_hole circle
			(at 0.571501 0 315)
			(size 0.508 0.508)
			(drill 0.254)
			(layers "*.Cu" "*.Mask")
			(remove_unused_layers no)
			(net "PHY_IOC_TO_CON_A_1_DN")
			(clearance 0.127)
			(thermal_gap 0.127)
		)
		(pad "4" thru_hole circle
			(at 1.5875 0 315)
			(size 0.508 0.508)
			(drill 0.254)
			(layers "*.Cu" "*.Mask")
			(remove_unused_layers no)
			(net "GND")
			(clearance 0.127)
			(thermal_gap 0.127)
		)
	)
	(footprint ""
		(layer "F.Cu")
		(at 58.486548 -131.31292 180)
		(property "Reference" "R288"
			(at 0 0 180)
			(layer "F.SilkS")
			(hide yes)
			(effects
				(font
					(size 1.27 1.27)
				)
			)
		)
		(property "Value" "0R2J-2-GP"
			(at 0.064008 -3.993896 180)
			(unlocked yes)
			(layer "F.Fab")
			(hide yes)
			(effects
				(font
					(size 1.016 1.016)
					(thickness 0.1524)
				)
			)
		)
		(property "Device Type" "R402H16"
			(at 0.064008 -5.517896 180)
			(unlocked yes)
			(layer "F.Fab")
			(hide yes)
			(effects
				(font
					(size 1.016 1.016)
					(thickness 0.1524)
				)
			)
		)
		(duplicate_pad_numbers_are_jumpers no)
		(fp_line
			(start 0.508 -0.9398)
			(end -0.508 -0.9398)
			(stroke
				(width 0.1524)
				(type default)
			)
			(layer "F.SilkS")
		)
		(fp_line
			(start -0.508 -0.9398)
			(end -0.508 0.9398)
			(stroke
				(width 0.1524)
				(type default)
			)
			(layer "F.SilkS")
		)
		(fp_rect
			(start -0.508 0.9398)
			(end 0.508 -0.9398)
			(stroke
				(width 0)
				(type default)
			)
			(fill no)
			(layer "F.CrtYd")
		)
		(fp_rect
			(start -0.508 0.9398)
			(end 0.508 -0.9398)
			(stroke
				(width 0)
				(type default)
			)
			(fill no)
			(layer "F.Fab")
		)
		(pad "1" smd custom
			(at 0 -0.4445 180)
			(size 0.1397 0.1397)
			(layers "F.Cu" "F.Mask" "F.Paste")
			(net "EXP_SPARE_0")
			(options
				(clearance outline)
				(anchor circle)
			)
			(primitives
				(gr_poly
					(pts
						(arc
							(start -0.1778 -0.2794)
							(mid -0.249642 -0.249642)
							(end -0.2794 -0.1778)
						)
						(arc
							(start -0.2794 0.1778)
							(mid -0.249642 0.249642)
							(end -0.1778 0.2794)
						)
						(arc
							(start 0.1778 0.2794)
							(mid 0.249642 0.249642)
							(end 0.2794 0.1778)
						)
						(arc
							(start 0.2794 -0.1778)
							(mid 0.249642 -0.249642)
							(end 0.1778 -0.2794)
						)
					)
					(width 0)
					(fill yes)
				)
			)
		)
		(pad "2" smd custom
			(at 0 0.4445 180)
			(size 0.1397 0.1397)
			(layers "F.Cu" "F.Mask" "F.Paste")
			(net "EXP_SPARE_0_R")
			(options
				(clearance outline)
				(anchor circle)
			)
			(primitives
				(gr_poly
					(pts
						(arc
							(start -0.1778 -0.2794)
							(mid -0.249642 -0.249642)
							(end -0.2794 -0.1778)
						)
						(arc
							(start -0.2794 0.1778)
							(mid -0.249642 0.249642)
							(end -0.1778 0.2794)
						)
						(arc
							(start 0.1778 0.2794)
							(mid 0.249642 0.249642)
							(end 0.2794 0.1778)
						)
						(arc
							(start 0.2794 -0.1778)
							(mid 0.249642 -0.249642)
							(end 0.1778 -0.2794)
						)
					)
					(width 0)
					(fill yes)
				)
			)
		)
	)
	(footprint ""
		(layer "F.Cu")
		(at 162.85464 -139.583922 90)
		(property "Reference" "R516"
			(at 0 0 90)
			(layer "F.SilkS")
			(hide yes)
			(effects
				(font
					(size 1.27 1.27)
				)
			)
		)
		(property "Value" "0R2J-2-GP"
			(at 0.064008 -3.993896 90)
			(unlocked yes)
			(layer "F.Fab")
			(hide yes)
			(effects
				(font
					(size 1.016 1.016)
					(thickness 0.1524)
				)
			)
		)
		(property "Device Type" "R402H16"
			(at 0.064008 -5.517896 90)
			(unlocked yes)
			(layer "F.Fab")
			(hide yes)
			(effects
				(font
					(size 1.016 1.016)
					(thickness 0.1524)
				)
			)
		)
		(duplicate_pad_numbers_are_jumpers no)
		(fp_line
			(start 0.508 -0.9398)
			(end -0.508 -0.9398)
			(stroke
				(width 0.1524)
				(type default)
			)
			(layer "F.SilkS")
		)
		(fp_line
			(start -0.508 -0.9398)
			(end -0.508 0.9398)
			(stroke
				(width 0.1524)
				(type default)
			)
			(layer "F.SilkS")
		)
		(fp_rect
			(start -0.508 0.9398)
			(end 0.508 -0.9398)
			(stroke
				(width 0)
				(type default)
			)
			(fill no)
			(layer "F.CrtYd")
		)
		(fp_rect
			(start -0.508 0.9398)
			(end 0.508 -0.9398)
			(stroke
				(width 0)
				(type default)
			)
			(fill no)
			(layer "F.Fab")
		)
		(pad "1" smd custom
			(at 0 -0.4445 90)
			(size 0.1397 0.1397)
			(layers "F.Cu" "F.Mask" "F.Paste")
			(net "P1V8_STBY_VO")
			(options
				(clearance outline)
				(anchor circle)
			)
			(primitives
				(gr_poly
					(pts
						(arc
							(start -0.1778 -0.2794)
							(mid -0.249642 -0.249642)
							(end -0.2794 -0.1778)
						)
						(arc
							(start -0.2794 0.1778)
							(mid -0.249642 0.249642)
							(end -0.1778 0.2794)
						)
						(arc
							(start 0.1778 0.2794)
							(mid 0.249642 0.249642)
							(end 0.2794 0.1778)
						)
						(arc
							(start 0.2794 -0.1778)
							(mid 0.249642 -0.249642)
							(end 0.1778 -0.2794)
						)
					)
					(width 0)
					(fill yes)
				)
			)
		)
		(pad "2" smd custom
			(at 0 0.4445 90)
			(size 0.1397 0.1397)
			(layers "F.Cu" "F.Mask" "F.Paste")
			(net "P1V8_STBY_CC_R")
			(options
				(clearance outline)
				(anchor circle)
			)
			(primitives
				(gr_poly
					(pts
						(arc
							(start -0.1778 -0.2794)
							(mid -0.249642 -0.249642)
							(end -0.2794 -0.1778)
						)
						(arc
							(start -0.2794 0.1778)
							(mid -0.249642 0.249642)
							(end -0.1778 0.2794)
						)
						(arc
							(start 0.1778 0.2794)
							(mid 0.249642 0.249642)
							(end 0.2794 0.1778)
						)
						(arc
							(start 0.2794 -0.1778)
							(mid 0.249642 -0.249642)
							(end 0.1778 -0.2794)
						)
					)
					(width 0)
					(fill yes)
				)
			)
		)
	)
	(footprint ""
		(layer "F.Cu")
		(at 162.8648 -140.6398 -90)
		(property "Reference" "R515"
			(at 0 0 270)
			(layer "F.SilkS")
			(hide yes)
			(effects
				(font
					(size 1.27 1.27)
				)
			)
		)
		(property "Value" "13K7R2F-GP"
			(at 0.064008 -3.993896 270)
			(unlocked yes)
			(layer "F.Fab")
			(hide yes)
			(effects
				(font
					(size 1.016 1.016)
					(thickness 0.1524)
				)
			)
		)
		(property "Device Type" "R402H16"
			(at 0.064008 -5.517896 270)
			(unlocked yes)
			(layer "F.Fab")
			(hide yes)
			(effects
				(font
					(size 1.016 1.016)
					(thickness 0.1524)
				)
			)
		)
		(duplicate_pad_numbers_are_jumpers no)
		(fp_line
			(start -0.508 -0.9398)
			(end -0.508 0.9398)
			(stroke
				(width 0.1524)
				(type default)
			)
			(layer "F.SilkS")
		)
		(fp_line
			(start 0.508 -0.9398)
			(end -0.508 -0.9398)
			(stroke
				(width 0.1524)
				(type default)
			)
			(layer "F.SilkS")
		)
		(fp_rect
			(start -0.508 0.9398)
			(end 0.508 -0.9398)
			(stroke
				(width 0)
				(type default)
			)
			(fill no)
			(layer "F.CrtYd")
		)
		(fp_rect
			(start -0.508 0.9398)
			(end 0.508 -0.9398)
			(stroke
				(width 0)
				(type default)
			)
			(fill no)
			(layer "F.Fab")
		)
		(pad "1" smd custom
			(at 0 -0.4445 270)
			(size 0.1397 0.1397)
			(layers "F.Cu" "F.Mask" "F.Paste")
			(net "P1V8_STBY_CC_R")
			(options
				(clearance outline)
				(anchor circle)
			)
			(primitives
				(gr_poly
					(pts
						(arc
							(start -0.1778 -0.2794)
							(mid -0.249642 -0.249642)
							(end -0.2794 -0.1778)
						)
						(arc
							(start -0.2794 0.1778)
							(mid -0.249642 0.249642)
							(end -0.1778 0.2794)
						)
						(arc
							(start 0.1778 0.2794)
							(mid 0.249642 0.249642)
							(end 0.2794 0.1778)
						)
						(arc
							(start 0.2794 -0.1778)
							(mid 0.249642 -0.249642)
							(end 0.1778 -0.2794)
						)
					)
					(width 0)
					(fill yes)
				)
			)
		)
		(pad "2" smd custom
			(at 0 0.4445 270)
			(size 0.1397 0.1397)
			(layers "F.Cu" "F.Mask" "F.Paste")
			(net "P1V8_STBY_VFB")
			(options
				(clearance outline)
				(anchor circle)
			)
			(primitives
				(gr_poly
					(pts
						(arc
							(start -0.1778 -0.2794)
							(mid -0.249642 -0.249642)
							(end -0.2794 -0.1778)
						)
						(arc
							(start -0.2794 0.1778)
							(mid -0.249642 0.249642)
							(end -0.1778 0.2794)
						)
						(arc
							(start 0.1778 0.2794)
							(mid 0.249642 0.249642)
							(end 0.2794 0.1778)
						)
						(arc
							(start 0.2794 -0.1778)
							(mid 0.249642 -0.249642)
							(end 0.1778 -0.2794)
						)
					)
					(width 0)
					(fill yes)
				)
			)
		)
	)
	(footprint ""
		(layer "F.Cu")
		(at 29.367226 -180.33873 180)
		(property "Reference" "C182"
			(at 0 0 180)
			(layer "F.SilkS")
			(hide yes)
			(effects
				(font
					(size 1.27 1.27)
				)
			)
		)
		(property "Value" "SC1U16V3KX-5GP"
			(at 0 -2.8194 180)
			(unlocked yes)
			(layer "F.Fab")
			(hide yes)
			(effects
				(font
					(size 1.016 1.016)
					(thickness 0.1524)
				)
			)
		)
		(property "Device Type" "C603H36"
			(at 0 -4.3434 180)
			(unlocked yes)
			(layer "F.Fab")
			(hide yes)
			(effects
				(font
					(size 1.016 1.016)
					(thickness 0.1524)
				)
			)
		)
		(duplicate_pad_numbers_are_jumpers no)
		(fp_line
			(start 0.508 0)
			(end -0.508 0)
			(stroke
				(width 0.2032)
				(type default)
			)
			(layer "F.SilkS")
		)
		(fp_rect
			(start -0.5842 1.3335)
			(end 0.5842 -1.3335)
			(stroke
				(width 0)
				(type default)
			)
			(fill no)
			(layer "F.CrtYd")
		)
		(fp_rect
			(start -0.5842 1.3335)
			(end 0.5842 -1.3335)
			(stroke
				(width 0)
				(type default)
			)
			(fill no)
			(layer "F.Fab")
		)
		(pad "1" smd custom
			(at 0 -0.762 180)
			(size 0.2159 0.2159)
			(layers "F.Cu" "F.Mask" "F.Paste")
			(net "GND")
			(options
				(clearance outline)
				(anchor circle)
			)
			(primitives
				(gr_poly
					(pts
						(arc
							(start -0.3302 -0.4318)
							(mid -0.402042 -0.402042)
							(end -0.4318 -0.3302)
						)
						(arc
							(start -0.4318 0.3302)
							(mid -0.402042 0.402042)
							(end -0.3302 0.4318)
						)
						(arc
							(start 0.3302 0.4318)
							(mid 0.402042 0.402042)
							(end 0.4318 0.3302)
						)
						(arc
							(start 0.4318 -0.3302)
							(mid 0.402042 -0.402042)
							(end 0.3302 -0.4318)
						)
					)
					(width 0)
					(fill yes)
				)
			)
		)
		(pad "2" smd custom
			(at 0 0.762 180)
			(size 0.2159 0.2159)
			(layers "F.Cu" "F.Mask" "F.Paste")
			(net "P3V3_STBY_VREG")
			(options
				(clearance outline)
				(anchor circle)
			)
			(primitives
				(gr_poly
					(pts
						(arc
							(start -0.3302 -0.4318)
							(mid -0.402042 -0.402042)
							(end -0.4318 -0.3302)
						)
						(arc
							(start -0.4318 0.3302)
							(mid -0.402042 0.402042)
							(end -0.3302 0.4318)
						)
						(arc
							(start 0.3302 0.4318)
							(mid 0.402042 0.402042)
							(end 0.4318 0.3302)
						)
						(arc
							(start 0.4318 -0.3302)
							(mid 0.402042 -0.402042)
							(end 0.3302 -0.4318)
						)
					)
					(width 0)
					(fill yes)
				)
			)
		)
	)
	(footprint ""
		(layer "F.Cu")
		(at 86.854538 -57.655968 -90)
		(property "Reference" "R3"
			(at 0 0 270)
			(layer "F.SilkS")
			(hide yes)
			(effects
				(font
					(size 1.27 1.27)
				)
			)
		)
		(property "Value" "4K7R2F-GP"
			(at 0.064008 -3.993896 270)
			(unlocked yes)
			(layer "F.Fab")
			(hide yes)
			(effects
				(font
					(size 1.016 1.016)
					(thickness 0.1524)
				)
			)
		)
		(property "Device Type" "R402H16"
			(at 0.064008 -5.517896 270)
			(unlocked yes)
			(layer "F.Fab")
			(hide yes)
			(effects
				(font
					(size 1.016 1.016)
					(thickness 0.1524)
				)
			)
		)
		(duplicate_pad_numbers_are_jumpers no)
		(fp_line
			(start -0.508 -0.9398)
			(end -0.508 0.9398)
			(stroke
				(width 0.1524)
				(type default)
			)
			(layer "F.SilkS")
		)
		(fp_line
			(start 0.508 -0.9398)
			(end -0.508 -0.9398)
			(stroke
				(width 0.1524)
				(type default)
			)
			(layer "F.SilkS")
		)
		(fp_rect
			(start -0.508 0.9398)
			(end 0.508 -0.9398)
			(stroke
				(width 0)
				(type default)
			)
			(fill no)
			(layer "F.CrtYd")
		)
		(fp_rect
			(start -0.508 0.9398)
			(end 0.508 -0.9398)
			(stroke
				(width 0)
				(type default)
			)
			(fill no)
			(layer "F.Fab")
		)
		(pad "1" smd custom
			(at 0 -0.4445 270)
			(size 0.1397 0.1397)
			(layers "F.Cu" "F.Mask" "F.Paste")
			(net "I2C_MEZZ_ALERT_N")
			(options
				(clearance outline)
				(anchor circle)
			)
			(primitives
				(gr_poly
					(pts
						(arc
							(start -0.1778 -0.2794)
							(mid -0.249642 -0.249642)
							(end -0.2794 -0.1778)
						)
						(arc
							(start -0.2794 0.1778)
							(mid -0.249642 0.249642)
							(end -0.1778 0.2794)
						)
						(arc
							(start 0.1778 0.2794)
							(mid 0.249642 0.249642)
							(end 0.2794 0.1778)
						)
						(arc
							(start 0.2794 -0.1778)
							(mid 0.249642 -0.249642)
							(end 0.1778 -0.2794)
						)
					)
					(width 0)
					(fill yes)
				)
			)
		)
		(pad "2" smd custom
			(at 0 0.4445 270)
			(size 0.1397 0.1397)
			(layers "F.Cu" "F.Mask" "F.Paste")
			(net "P3V3_STBY")
			(options
				(clearance outline)
				(anchor circle)
			)
			(primitives
				(gr_poly
					(pts
						(arc
							(start -0.1778 -0.2794)
							(mid -0.249642 -0.249642)
							(end -0.2794 -0.1778)
						)
						(arc
							(start -0.2794 0.1778)
							(mid -0.249642 0.249642)
							(end -0.1778 0.2794)
						)
						(arc
							(start 0.1778 0.2794)
							(mid 0.249642 0.249642)
							(end 0.2794 0.1778)
						)
						(arc
							(start 0.2794 -0.1778)
							(mid 0.249642 -0.249642)
							(end 0.1778 -0.2794)
						)
					)
					(width 0)
					(fill yes)
				)
			)
		)
	)
	(footprint ""
		(layer "F.Cu")
		(at 202.0824 -48.2854 180)
		(property "Reference" "R632"
			(at 0 0 180)
			(layer "F.SilkS")
			(hide yes)
			(effects
				(font
					(size 1.27 1.27)
				)
			)
		)
		(property "Value" "4K7R2F-GP"
			(at 0.064008 -3.993896 180)
			(unlocked yes)
			(layer "F.Fab")
			(hide yes)
			(effects
				(font
					(size 1.016 1.016)
					(thickness 0.1524)
				)
			)
		)
		(property "Device Type" "R402H16"
			(at 0.064008 -5.517896 180)
			(unlocked yes)
			(layer "F.Fab")
			(hide yes)
			(effects
				(font
					(size 1.016 1.016)
					(thickness 0.1524)
				)
			)
		)
		(duplicate_pad_numbers_are_jumpers no)
		(fp_line
			(start 0.508 -0.9398)
			(end -0.508 -0.9398)
			(stroke
				(width 0.1524)
				(type default)
			)
			(layer "F.SilkS")
		)
		(fp_line
			(start -0.508 -0.9398)
			(end -0.508 0.9398)
			(stroke
				(width 0.1524)
				(type default)
			)
			(layer "F.SilkS")
		)
		(fp_rect
			(start -0.508 0.9398)
			(end 0.508 -0.9398)
			(stroke
				(width 0)
				(type default)
			)
			(fill no)
			(layer "F.CrtYd")
		)
		(fp_rect
			(start -0.508 0.9398)
			(end 0.508 -0.9398)
			(stroke
				(width 0)
				(type default)
			)
			(fill no)
			(layer "F.Fab")
		)
		(pad "1" smd custom
			(at 0 -0.4445 180)
			(size 0.1397 0.1397)
			(layers "F.Cu" "F.Mask" "F.Paste")
			(net "P1V8")
			(options
				(clearance outline)
				(anchor circle)
			)
			(primitives
				(gr_poly
					(pts
						(arc
							(start -0.1778 -0.2794)
							(mid -0.249642 -0.249642)
							(end -0.2794 -0.1778)
						)
						(arc
							(start -0.2794 0.1778)
							(mid -0.249642 0.249642)
							(end -0.1778 0.2794)
						)
						(arc
							(start 0.1778 0.2794)
							(mid 0.249642 0.249642)
							(end 0.2794 0.1778)
						)
						(arc
							(start 0.2794 -0.1778)
							(mid 0.249642 -0.249642)
							(end 0.1778 -0.2794)
						)
					)
					(width 0)
					(fill yes)
				)
			)
		)
		(pad "2" smd custom
			(at 0 0.4445 180)
			(size 0.1397 0.1397)
			(layers "F.Cu" "F.Mask" "F.Paste")
			(net "ICE1_TCK")
			(options
				(clearance outline)
				(anchor circle)
			)
			(primitives
				(gr_poly
					(pts
						(arc
							(start -0.1778 -0.2794)
							(mid -0.249642 -0.249642)
							(end -0.2794 -0.1778)
						)
						(arc
							(start -0.2794 0.1778)
							(mid -0.249642 0.249642)
							(end -0.1778 0.2794)
						)
						(arc
							(start 0.1778 0.2794)
							(mid 0.249642 0.249642)
							(end 0.2794 0.1778)
						)
						(arc
							(start 0.2794 -0.1778)
							(mid 0.249642 -0.249642)
							(end 0.1778 -0.2794)
						)
					)
					(width 0)
					(fill yes)
				)
			)
		)
	)
	(footprint ""
		(layer "F.Cu")
		(at 35.2044 -134.5438 90)
		(property "Reference" "R280"
			(at 0 0 90)
			(layer "F.SilkS")
			(hide yes)
			(effects
				(font
					(size 1.27 1.27)
				)
			)
		)
		(property "Value" "33R2F-3-GP"
			(at 0.064008 -3.993896 90)
			(unlocked yes)
			(layer "F.Fab")
			(hide yes)
			(effects
				(font
					(size 1.016 1.016)
					(thickness 0.1524)
				)
			)
		)
		(property "Device Type" "R402H16"
			(at 0.064008 -5.517896 90)
			(unlocked yes)
			(layer "F.Fab")
			(hide yes)
			(effects
				(font
					(size 1.016 1.016)
					(thickness 0.1524)
				)
			)
		)
		(duplicate_pad_numbers_are_jumpers no)
		(fp_line
			(start 0.508 -0.9398)
			(end -0.508 -0.9398)
			(stroke
				(width 0.1524)
				(type default)
			)
			(layer "F.SilkS")
		)
		(fp_line
			(start -0.508 -0.9398)
			(end -0.508 0.9398)
			(stroke
				(width 0.1524)
				(type default)
			)
			(layer "F.SilkS")
		)
		(fp_rect
			(start -0.508 0.9398)
			(end 0.508 -0.9398)
			(stroke
				(width 0)
				(type default)
			)
			(fill no)
			(layer "F.CrtYd")
		)
		(fp_rect
			(start -0.508 0.9398)
			(end 0.508 -0.9398)
			(stroke
				(width 0)
				(type default)
			)
			(fill no)
			(layer "F.Fab")
		)
		(pad "1" smd custom
			(at 0 -0.4445 90)
			(size 0.1397 0.1397)
			(layers "F.Cu" "F.Mask" "F.Paste")
			(net "FLA_CS_0_R")
			(options
				(clearance outline)
				(anchor circle)
			)
			(primitives
				(gr_poly
					(pts
						(arc
							(start -0.1778 -0.2794)
							(mid -0.249642 -0.249642)
							(end -0.2794 -0.1778)
						)
						(arc
							(start -0.2794 0.1778)
							(mid -0.249642 0.249642)
							(end -0.1778 0.2794)
						)
						(arc
							(start 0.1778 0.2794)
							(mid 0.249642 0.249642)
							(end 0.2794 0.1778)
						)
						(arc
							(start 0.2794 -0.1778)
							(mid 0.249642 -0.249642)
							(end 0.1778 -0.2794)
						)
					)
					(width 0)
					(fill yes)
				)
			)
		)
		(pad "2" smd custom
			(at 0 0.4445 90)
			(size 0.1397 0.1397)
			(layers "F.Cu" "F.Mask" "F.Paste")
			(net "FLA_CS_0")
			(options
				(clearance outline)
				(anchor circle)
			)
			(primitives
				(gr_poly
					(pts
						(arc
							(start -0.1778 -0.2794)
							(mid -0.249642 -0.249642)
							(end -0.2794 -0.1778)
						)
						(arc
							(start -0.2794 0.1778)
							(mid -0.249642 0.249642)
							(end -0.1778 0.2794)
						)
						(arc
							(start 0.1778 0.2794)
							(mid 0.249642 0.249642)
							(end 0.2794 0.1778)
						)
						(arc
							(start 0.2794 -0.1778)
							(mid 0.249642 -0.249642)
							(end 0.1778 -0.2794)
						)
					)
					(width 0)
					(fill yes)
				)
			)
		)
	)
	(footprint ""
		(layer "F.Cu")
		(at 213.4362 -100.6602 90)
		(property "Reference" "U38"
			(at 0 0 90)
			(layer "F.SilkS")
			(hide yes)
			(effects
				(font
					(size 1.27 1.27)
				)
			)
		)
		(property "Value" "CAT24C64WI-GT3-GP"
			(at -3.707384 -1.5367 90)
			(unlocked yes)
			(layer "F.Fab")
			(hide yes)
			(effects
				(font
					(size 1.016 1.016)
					(thickness 0.1524)
				)
			)
		)
		(property "Device Type" "SOIC8H69"
			(at -3.707384 -3.0607 90)
			(unlocked yes)
			(layer "F.Fab")
			(hide yes)
			(effects
				(font
					(size 1.016 1.016)
					(thickness 0.1524)
				)
			)
		)
		(duplicate_pad_numbers_are_jumpers no)
		(fp_line
			(start 2.1336 -1.4224)
			(end -2.7432 -1.4224)
			(stroke
				(width 0.1524)
				(type default)
			)
			(layer "F.SilkS")
		)
		(fp_line
			(start -2.7432 -1.4224)
			(end -2.7432 1.4224)
			(stroke
				(width 0.1524)
				(type default)
			)
			(layer "F.SilkS")
		)
		(fp_line
			(start -2.7178 -0.508)
			(end -2.1844 -0.0508)
			(stroke
				(width 0.1524)
				(type default)
			)
			(layer "F.SilkS")
		)
		(fp_line
			(start -2.1844 -0.0508)
			(end -2.7178 0.508)
			(stroke
				(width 0.1524)
				(type default)
			)
			(layer "F.SilkS")
		)
		(fp_line
			(start 2.1336 1.4224)
			(end 2.1336 -1.4224)
			(stroke
				(width 0.1524)
				(type default)
			)
			(layer "F.SilkS")
		)
		(fp_line
			(start -2.7432 1.4224)
			(end 2.1336 1.4224)
			(stroke
				(width 0.1524)
				(type default)
			)
			(layer "F.SilkS")
		)
		(fp_line
			(start -2.7432 1.4224)
			(end -2.6416 1.4224)
			(stroke
				(width 0.1524)
				(type default)
			)
			(layer "F.SilkS")
		)
		(fp_line
			(start -2.6289 3.4417)
			(end -2.6289 1.4732)
			(stroke
				(width 0.381)
				(type default)
			)
			(layer "F.SilkS")
		)
		(fp_poly
			(pts
				(xy -2.2098 -1.4224) (xy -2.2098 1.4224) (xy 2.2098 1.4224) (xy 2.2098 -1.4224)
			)
			(stroke
				(width 0)
				(type default)
			)
			(fill yes)
			(layer "F.SilkS")
		)
		(fp_rect
			(start -2.450084 2.999994)
			(end 2.450084 -2.999994)
			(stroke
				(width 0)
				(type default)
			)
			(fill no)
			(layer "F.CrtYd")
		)
		(fp_poly
			(pts
				(xy -2.8194 3.6322) (xy -2.8194 -3.6322) (xy 2.8194 -3.6322) (xy 2.8194 1.18364) (xy 2.450084 1.18364)
				(xy 2.450084 -2.999994) (xy -2.450084 -2.999994) (xy -2.450084 2.999994) (xy 2.450084 2.999994)
				(xy 2.450084 1.18618) (xy 2.8194 1.18618) (xy 2.8194 3.6322)
			)
			(stroke
				(width 0)
				(type default)
			)
			(fill no)
			(layer "F.CrtYd")
		)
		(fp_rect
			(start -2.8194 3.6322)
			(end 2.8194 -3.6322)
			(stroke
				(width 0)
				(type default)
			)
			(fill no)
			(layer "F.Fab")
		)
		(pad "1" smd rect
			(at -1.905 2.54 90)
			(size 0.635 1.651)
			(layers "F.Cu" "F.Mask" "F.Paste")
			(net "IOC_EEPROM_A0")
		)
		(pad "2" smd rect
			(at -0.635 2.54 90)
			(size 0.635 1.651)
			(layers "F.Cu" "F.Mask" "F.Paste")
			(net "IOC_EEPROM_A1")
		)
		(pad "3" smd rect
			(at 0.635 2.54 90)
			(size 0.635 1.651)
			(layers "F.Cu" "F.Mask" "F.Paste")
			(net "IOC_EEPROM_A2")
		)
		(pad "4" smd rect
			(at 1.905 2.54 90)
			(size 0.635 1.651)
			(layers "F.Cu" "F.Mask" "F.Paste")
			(net "GND")
		)
		(pad "5" smd rect
			(at 1.905 -2.54 90)
			(size 0.635 1.651)
			(layers "F.Cu" "F.Mask" "F.Paste")
			(net "IOC_EEPROM_SDA")
		)
		(pad "6" smd rect
			(at 0.635 -2.54 90)
			(size 0.635 1.651)
			(layers "F.Cu" "F.Mask" "F.Paste")
			(net "IOC_EEPROM_SCL")
		)
		(pad "7" smd rect
			(at -0.635 -2.54 90)
			(size 0.635 1.651)
			(layers "F.Cu" "F.Mask" "F.Paste")
			(net "IOC_EEPROM_WP")
		)
		(pad "8" smd rect
			(at -1.905 -2.54 90)
			(size 0.635 1.651)
			(layers "F.Cu" "F.Mask" "F.Paste")
			(net "P1V8")
		)
	)
	(footprint ""
		(layer "F.Cu")
		(at 80.6704 -154.5844)
		(property "Reference" "C239"
			(at 0 0 0)
			(layer "F.SilkS")
			(hide yes)
			(effects
				(font
					(size 1.27 1.27)
				)
			)
		)
		(property "Value" "SCD1U16V2KX-3GP"
			(at 1.1811 -2.7051 0)
			(unlocked yes)
			(layer "F.Fab")
			(hide yes)
			(effects
				(font
					(size 1.016 1.016)
					(thickness 0.1524)
				)
			)
		)
		(property "Device Type" "C402H22"
			(at 1.1811 -4.2291 0)
			(unlocked yes)
			(layer "F.Fab")
			(hide yes)
			(effects
				(font
					(size 1.016 1.016)
					(thickness 0.1524)
				)
			)
		)
		(duplicate_pad_numbers_are_jumpers no)
		(fp_rect
			(start -0.4318 0.9525)
			(end 0.4318 -0.9525)
			(stroke
				(width 0)
				(type default)
			)
			(fill no)
			(layer "F.CrtYd")
		)
		(fp_rect
			(start -0.4318 0.9525)
			(end 0.4318 -0.9525)
			(stroke
				(width 0)
				(type default)
			)
			(fill no)
			(layer "F.Fab")
		)
		(pad "1" smd custom
			(at 0 -0.4445)
			(size 0.1524 0.1524)
			(layers "F.Cu" "F.Mask" "F.Paste")
			(net "TPS74801_P1V15_STBY_OUT")
			(options
				(clearance outline)
				(anchor circle)
			)
			(primitives
				(gr_poly
					(pts
						(arc
							(start 0.3048 -0.2032)
							(mid 0.275042 -0.275042)
							(end 0.2032 -0.3048)
						)
						(arc
							(start -0.2032 -0.3048)
							(mid -0.275042 -0.275042)
							(end -0.3048 -0.2032)
						)
						(arc
							(start -0.3048 0.2032)
							(mid -0.275042 0.275042)
							(end -0.2032 0.3048)
						)
						(arc
							(start 0.2032 0.3048)
							(mid 0.275042 0.275042)
							(end 0.3048 0.2032)
						)
					)
					(width 0)
					(fill yes)
				)
			)
		)
		(pad "2" smd custom
			(at 0 0.4445)
			(size 0.1524 0.1524)
			(layers "F.Cu" "F.Mask" "F.Paste")
			(net "GND")
			(options
				(clearance outline)
				(anchor circle)
			)
			(primitives
				(gr_poly
					(pts
						(arc
							(start 0.3048 -0.2032)
							(mid 0.275042 -0.275042)
							(end 0.2032 -0.3048)
						)
						(arc
							(start -0.2032 -0.3048)
							(mid -0.275042 -0.275042)
							(end -0.3048 -0.2032)
						)
						(arc
							(start -0.3048 0.2032)
							(mid -0.275042 0.275042)
							(end -0.2032 0.3048)
						)
						(arc
							(start 0.2032 0.3048)
							(mid 0.275042 0.275042)
							(end 0.3048 0.2032)
						)
					)
					(width 0)
					(fill yes)
				)
			)
		)
	)
	(footprint ""
		(layer "F.Cu")
		(at 41.68902 -158.8897)
		(property "Reference" "TP186"
			(at 0 0 0)
			(layer "F.SilkS")
			(hide yes)
			(effects
				(font
					(size 1.27 1.27)
				)
			)
		)
		(property "Value" "TPAD28-2-GP"
			(at -0.0127 -1.6637 0)
			(unlocked yes)
			(layer "F.Fab")
			(hide yes)
			(effects
				(font
					(size 1.016 1.016)
					(thickness 0.1524)
				)
			)
		)
		(property "Device Type" "TPAD28"
			(at -0.0127 -3.1877 0)
			(unlocked yes)
			(layer "F.Fab")
			(hide yes)
			(effects
				(font
					(size 1.016 1.016)
					(thickness 0.1524)
				)
			)
		)
		(duplicate_pad_numbers_are_jumpers no)
		(fp_poly
			(pts
				(arc
					(start 0.3556 0)
					(mid -0.3556 0)
					(end 0.3556 0)
				)
			)
			(stroke
				(width 0)
				(type default)
			)
			(fill no)
			(layer "F.CrtYd")
		)
		(fp_poly
			(pts
				(arc
					(start 0.6096 0)
					(mid -0.6096 0)
					(end 0.6096 0)
				)
			)
			(stroke
				(width 0)
				(type default)
			)
			(fill no)
			(layer "F.Fab")
		)
		(pad "1" smd circle
			(at 0 0)
			(size 0.7112 0.7112)
			(layers "F.Cu" "F.Mask" "F.Paste")
			(net "TP_BMC_GPIOL0")
		)
	)
	(footprint ""
		(layer "F.Cu")
		(at 19.15287 -131.007358 180)
		(property "Reference" "R216"
			(at 0 0 180)
			(layer "F.SilkS")
			(hide yes)
			(effects
				(font
					(size 1.27 1.27)
				)
			)
		)
		(property "Value" "120R2F-GP"
			(at 0.064008 -3.993896 180)
			(unlocked yes)
			(layer "F.Fab")
			(hide yes)
			(effects
				(font
					(size 1.016 1.016)
					(thickness 0.1524)
				)
			)
		)
		(property "Device Type" "R402H16"
			(at 0.064008 -5.517896 180)
			(unlocked yes)
			(layer "F.Fab")
			(hide yes)
			(effects
				(font
					(size 1.016 1.016)
					(thickness 0.1524)
				)
			)
		)
		(duplicate_pad_numbers_are_jumpers no)
		(fp_line
			(start 0.508 -0.9398)
			(end -0.508 -0.9398)
			(stroke
				(width 0.1524)
				(type default)
			)
			(layer "F.SilkS")
		)
		(fp_line
			(start -0.508 -0.9398)
			(end -0.508 0.9398)
			(stroke
				(width 0.1524)
				(type default)
			)
			(layer "F.SilkS")
		)
		(fp_rect
			(start -0.508 0.9398)
			(end 0.508 -0.9398)
			(stroke
				(width 0)
				(type default)
			)
			(fill no)
			(layer "F.CrtYd")
		)
		(fp_rect
			(start -0.508 0.9398)
			(end 0.508 -0.9398)
			(stroke
				(width 0)
				(type default)
			)
			(fill no)
			(layer "F.Fab")
		)
		(pad "1" smd custom
			(at 0 -0.4445 180)
			(size 0.1397 0.1397)
			(layers "F.Cu" "F.Mask" "F.Paste")
			(net "MEMCSN")
			(options
				(clearance outline)
				(anchor circle)
			)
			(primitives
				(gr_poly
					(pts
						(arc
							(start -0.1778 -0.2794)
							(mid -0.249642 -0.249642)
							(end -0.2794 -0.1778)
						)
						(arc
							(start -0.2794 0.1778)
							(mid -0.249642 0.249642)
							(end -0.1778 0.2794)
						)
						(arc
							(start 0.1778 0.2794)
							(mid 0.249642 0.249642)
							(end 0.2794 0.1778)
						)
						(arc
							(start 0.2794 -0.1778)
							(mid 0.249642 -0.249642)
							(end 0.1778 -0.2794)
						)
					)
					(width 0)
					(fill yes)
				)
			)
		)
		(pad "2" smd custom
			(at 0 0.4445 180)
			(size 0.1397 0.1397)
			(layers "F.Cu" "F.Mask" "F.Paste")
			(net "P1V2_STBY")
			(options
				(clearance outline)
				(anchor circle)
			)
			(primitives
				(gr_poly
					(pts
						(arc
							(start -0.1778 -0.2794)
							(mid -0.249642 -0.249642)
							(end -0.2794 -0.1778)
						)
						(arc
							(start -0.2794 0.1778)
							(mid -0.249642 0.249642)
							(end -0.1778 0.2794)
						)
						(arc
							(start 0.1778 0.2794)
							(mid 0.249642 0.249642)
							(end 0.2794 0.1778)
						)
						(arc
							(start 0.2794 -0.1778)
							(mid 0.249642 -0.249642)
							(end 0.1778 -0.2794)
						)
					)
					(width 0)
					(fill yes)
				)
			)
		)
	)
	(footprint ""
		(layer "F.Cu")
		(at 193.33972 -30.44444 90)
		(property "Reference" "C526"
			(at 0 0 90)
			(layer "F.SilkS")
			(hide yes)
			(effects
				(font
					(size 1.27 1.27)
				)
			)
		)
		(property "Value" "SC1000P2KV6KX-GP-U"
			(at 0.0508 -3.5052 90)
			(unlocked yes)
			(layer "F.Fab")
			(hide yes)
			(effects
				(font
					(size 1.016 1.016)
					(thickness 0.1524)
				)
			)
		)
		(property "Device Type" "C1206H58"
			(at 0.0508 -5.0292 90)
			(unlocked yes)
			(layer "F.Fab")
			(hide yes)
			(effects
				(font
					(size 1.016 1.016)
					(thickness 0.1524)
				)
			)
		)
		(duplicate_pad_numbers_are_jumpers no)
		(fp_line
			(start 1.016 -2.2352)
			(end -1.016 -2.2352)
			(stroke
				(width 0.1524)
				(type default)
			)
			(layer "F.SilkS")
		)
		(fp_line
			(start 1.016 -2.2352)
			(end 1.016 -0.8382)
			(stroke
				(width 0.1524)
				(type default)
			)
			(layer "F.SilkS")
		)
		(fp_line
			(start -1.016 -2.2352)
			(end -1.016 -0.8382)
			(stroke
				(width 0.1524)
				(type default)
			)
			(layer "F.SilkS")
		)
		(fp_line
			(start 1.016 0.8382)
			(end 1.016 2.2352)
			(stroke
				(width 0.1524)
				(type default)
			)
			(layer "F.SilkS")
		)
		(fp_line
			(start 1.016 2.2352)
			(end -1.016 2.2352)
			(stroke
				(width 0.1524)
				(type default)
			)
			(layer "F.SilkS")
		)
		(fp_line
			(start -1.016 2.2352)
			(end -1.016 0.8128)
			(stroke
				(width 0.1524)
				(type default)
			)
			(layer "F.SilkS")
		)
		(fp_rect
			(start -1.0922 2.3114)
			(end 1.0922 -2.3114)
			(stroke
				(width 0)
				(type default)
			)
			(fill no)
			(layer "F.CrtYd")
		)
		(fp_poly
			(pts
				(xy -1.0922 -2.3114) (xy 1.0922 -2.3114) (xy 1.0922 2.3114) (xy -1.0922 2.3114)
			)
			(stroke
				(width 0)
				(type default)
			)
			(fill no)
			(layer "F.Fab")
		)
		(pad "1" smd rect
			(at 0 -1.397 90)
			(size 1.651 1.27)
			(layers "F.Cu" "F.Mask" "F.Paste")
			(net "EXT1_CONN_GND")
		)
		(pad "2" smd rect
			(at 0 1.397 90)
			(size 1.651 1.27)
			(layers "F.Cu" "F.Mask" "F.Paste")
			(net "GND")
		)
	)
	(footprint ""
		(layer "F.Cu")
		(at 188.67882 -114.9858 -90)
		(property "Reference" "C744"
			(at 0 0 270)
			(layer "F.SilkS")
			(hide yes)
			(effects
				(font
					(size 1.27 1.27)
				)
			)
		)
		(property "Value" "SC2200P50V2KX-2GP"
			(at 1.1811 -2.7051 270)
			(unlocked yes)
			(layer "F.Fab")
			(hide yes)
			(effects
				(font
					(size 1.016 1.016)
					(thickness 0.1524)
				)
			)
		)
		(property "Device Type" "C402H22"
			(at 1.1811 -4.2291 270)
			(unlocked yes)
			(layer "F.Fab")
			(hide yes)
			(effects
				(font
					(size 1.016 1.016)
					(thickness 0.1524)
				)
			)
		)
		(duplicate_pad_numbers_are_jumpers no)
		(fp_rect
			(start -0.4318 0.9525)
			(end 0.4318 -0.9525)
			(stroke
				(width 0)
				(type default)
			)
			(fill no)
			(layer "F.CrtYd")
		)
		(fp_rect
			(start -0.4318 0.9525)
			(end 0.4318 -0.9525)
			(stroke
				(width 0)
				(type default)
			)
			(fill no)
			(layer "F.Fab")
		)
		(pad "1" smd custom
			(at 0 -0.4445 270)
			(size 0.1524 0.1524)
			(layers "F.Cu" "F.Mask" "F.Paste")
			(net "N62640349")
			(options
				(clearance outline)
				(anchor circle)
			)
			(primitives
				(gr_poly
					(pts
						(arc
							(start 0.3048 -0.2032)
							(mid 0.275042 -0.275042)
							(end 0.2032 -0.3048)
						)
						(arc
							(start -0.2032 -0.3048)
							(mid -0.275042 -0.275042)
							(end -0.3048 -0.2032)
						)
						(arc
							(start -0.3048 0.2032)
							(mid -0.275042 0.275042)
							(end -0.2032 0.3048)
						)
						(arc
							(start 0.2032 0.3048)
							(mid 0.275042 0.275042)
							(end 0.3048 0.2032)
						)
					)
					(width 0)
					(fill yes)
				)
			)
		)
		(pad "2" smd custom
			(at 0 0.4445 270)
			(size 0.1524 0.1524)
			(layers "F.Cu" "F.Mask" "F.Paste")
			(net "GND")
			(options
				(clearance outline)
				(anchor circle)
			)
			(primitives
				(gr_poly
					(pts
						(arc
							(start 0.3048 -0.2032)
							(mid 0.275042 -0.275042)
							(end 0.2032 -0.3048)
						)
						(arc
							(start -0.2032 -0.3048)
							(mid -0.275042 -0.275042)
							(end -0.3048 -0.2032)
						)
						(arc
							(start -0.3048 0.2032)
							(mid -0.275042 0.275042)
							(end -0.2032 0.3048)
						)
						(arc
							(start 0.2032 0.3048)
							(mid 0.275042 0.275042)
							(end 0.3048 0.2032)
						)
					)
					(width 0)
					(fill yes)
				)
			)
		)
	)
	(footprint ""
		(layer "F.Cu")
		(at 194.3608 -83.9724 135)
		(property "Reference" "VIA21"
			(at 0 0 135)
			(layer "F.SilkS")
			(hide yes)
			(effects
				(font
					(size 1.27 1.27)
				)
			)
		)
		(property "Value" "85OHM-8L-1D6MM-L16L18-GP"
			(at 4.064105 0.609655 135)
			(unlocked yes)
			(layer "F.Fab")
			(hide yes)
			(effects
				(font
					(size 1.016 1.016)
					(thickness 0.1524)
				)
			)
		)
		(property "Device Type" "VIA-PCIE-4P-368076"
			(at 4.064105 -0.914474 135)
			(unlocked yes)
			(layer "F.Fab")
			(hide yes)
			(effects
				(font
					(size 1.016 1.016)
					(thickness 0.1524)
				)
			)
		)
		(duplicate_pad_numbers_are_jumpers no)
		(fp_poly
			(pts
				(xy -1.841491 -0.381057) (xy 1.841509 -0.381058) (xy 1.841508 0.380942) (xy -1.841491 0.380942)
			)
			(stroke
				(width 0)
				(type default)
			)
			(fill no)
			(layer "F.CrtYd")
		)
		(fp_poly
			(pts
				(xy -1.841491 -0.381057) (xy 1.841509 -0.381058) (xy 1.841508 0.380942) (xy -1.841491 0.380942)
			)
			(stroke
				(width 0)
				(type default)
			)
			(fill no)
			(layer "F.Fab")
		)
		(pad "1" thru_hole circle
			(at -1.460499 0 135)
			(size 0.508 0.508)
			(drill 0.254)
			(layers "*.Cu" "*.Mask")
			(remove_unused_layers no)
			(net "GND")
			(clearance 0.127)
			(thermal_gap 0.127)
		)
		(pad "2" thru_hole circle
			(at -0.4445 0 135)
			(size 0.508 0.508)
			(drill 0.254)
			(layers "*.Cu" "*.Mask")
			(remove_unused_layers no)
			(net "PCIE_COMP_TO_IOM_13_DP")
			(clearance 0.127)
			(thermal_gap 0.127)
		)
		(pad "3" thru_hole circle
			(at 0.4445 0 135)
			(size 0.508 0.508)
			(drill 0.254)
			(layers "*.Cu" "*.Mask")
			(remove_unused_layers no)
			(net "PCIE_COMP_TO_IOM_13_DN")
			(clearance 0.127)
			(thermal_gap 0.127)
		)
		(pad "4" thru_hole circle
			(at 1.460499 0 135)
			(size 0.508 0.508)
			(drill 0.254)
			(layers "*.Cu" "*.Mask")
			(remove_unused_layers no)
			(net "GND")
			(clearance 0.127)
			(thermal_gap 0.127)
		)
	)
	(footprint ""
		(layer "F.Cu")
		(at 102.999794 -9.99998)
		(property "Reference" ""
			(at 0 0 0)
			(layer "F.SilkS")
			(hide yes)
			(effects
				(font
					(size 1.27 1.27)
				)
			)
		)
		(property "Value" "*"
			(at -6.38175 0.19685 0)
			(unlocked yes)
			(layer "F.Fab")
			(hide yes)
			(effects
				(font
					(size 1.016 1.016)
					(thickness 0.1524)
				)
			)
		)
		(duplicate_pad_numbers_are_jumpers no)
		(fp_poly
			(pts
				(arc
					(start 5.0673 0)
					(mid -5.0673 0)
					(end 5.0673 0)
				)
			)
			(stroke
				(width 0)
				(type default)
			)
			(fill no)
			(layer "B.CrtYd")
		)
		(fp_poly
			(pts
				(arc
					(start 5.0673 0)
					(mid -5.0673 0)
					(end 5.0673 0)
				)
			)
			(stroke
				(width 0)
				(type default)
			)
			(fill no)
			(layer "F.CrtYd")
		)
		(fp_poly
			(pts
				(arc
					(start 5.0673 0)
					(mid -5.0673 0)
					(end 5.0673 0)
				)
			)
			(stroke
				(width 0)
				(type default)
			)
			(fill no)
			(layer "B.Fab")
		)
		(fp_poly
			(pts
				(arc
					(start 5.0673 0)
					(mid -5.0673 0)
					(end 5.0673 0)
				)
			)
			(stroke
				(width 0)
				(type default)
			)
			(fill no)
			(layer "F.Fab")
		)
		(pad "1" thru_hole circle
			(at 0 0)
			(size 9.525 9.525)
			(drill 3.5052)
			(layers "*.Cu" "*.Mask")
			(remove_unused_layers no)
			(net "Net_10")
			(clearance -2.5019)
			(thermal_gap 0.3048)
			(padstack
				(mode front_inner_back)
				(layer "Inner"
					(shape circle)
					(size 3.9116 3.9116)
					(clearance 0.3048)
				)
				(layer "B.Cu"
					(shape circle)
					(size 9.525 9.525)
					(clearance -2.5019)
				)
			)
		)
	)
	(footprint ""
		(layer "F.Cu")
		(at 37.112448 -130.758692 180)
		(property "Reference" "R379"
			(at 0 0 180)
			(layer "F.SilkS")
			(hide yes)
			(effects
				(font
					(size 1.27 1.27)
				)
			)
		)
		(property "Value" "4K7R2F-GP"
			(at 0.064008 -3.993896 180)
			(unlocked yes)
			(layer "F.Fab")
			(hide yes)
			(effects
				(font
					(size 1.016 1.016)
					(thickness 0.1524)
				)
			)
		)
		(property "Device Type" "R402H16"
			(at 0.064008 -5.517896 180)
			(unlocked yes)
			(layer "F.Fab")
			(hide yes)
			(effects
				(font
					(size 1.016 1.016)
					(thickness 0.1524)
				)
			)
		)
		(duplicate_pad_numbers_are_jumpers no)
		(fp_line
			(start 0.508 -0.9398)
			(end -0.508 -0.9398)
			(stroke
				(width 0.1524)
				(type default)
			)
			(layer "F.SilkS")
		)
		(fp_line
			(start -0.508 -0.9398)
			(end -0.508 0.9398)
			(stroke
				(width 0.1524)
				(type default)
			)
			(layer "F.SilkS")
		)
		(fp_rect
			(start -0.508 0.9398)
			(end 0.508 -0.9398)
			(stroke
				(width 0)
				(type default)
			)
			(fill no)
			(layer "F.CrtYd")
		)
		(fp_rect
			(start -0.508 0.9398)
			(end 0.508 -0.9398)
			(stroke
				(width 0)
				(type default)
			)
			(fill no)
			(layer "F.Fab")
		)
		(pad "1" smd custom
			(at 0 -0.4445 180)
			(size 0.1397 0.1397)
			(layers "F.Cu" "F.Mask" "F.Paste")
			(net "P3V3_STBY")
			(options
				(clearance outline)
				(anchor circle)
			)
			(primitives
				(gr_poly
					(pts
						(arc
							(start -0.1778 -0.2794)
							(mid -0.249642 -0.249642)
							(end -0.2794 -0.1778)
						)
						(arc
							(start -0.2794 0.1778)
							(mid -0.249642 0.249642)
							(end -0.1778 0.2794)
						)
						(arc
							(start 0.1778 0.2794)
							(mid 0.249642 0.249642)
							(end 0.2794 0.1778)
						)
						(arc
							(start 0.2794 -0.1778)
							(mid 0.249642 -0.249642)
							(end 0.1778 -0.2794)
						)
					)
					(width 0)
					(fill yes)
				)
			)
		)
		(pad "2" smd custom
			(at 0 0.4445 180)
			(size 0.1397 0.1397)
			(layers "F.Cu" "F.Mask" "F.Paste")
			(net "BMC_GPIOZ7")
			(options
				(clearance outline)
				(anchor circle)
			)
			(primitives
				(gr_poly
					(pts
						(arc
							(start -0.1778 -0.2794)
							(mid -0.249642 -0.249642)
							(end -0.2794 -0.1778)
						)
						(arc
							(start -0.2794 0.1778)
							(mid -0.249642 0.249642)
							(end -0.1778 0.2794)
						)
						(arc
							(start 0.1778 0.2794)
							(mid 0.249642 0.249642)
							(end 0.2794 0.1778)
						)
						(arc
							(start 0.2794 -0.1778)
							(mid 0.249642 -0.249642)
							(end 0.1778 -0.2794)
						)
					)
					(width 0)
					(fill yes)
				)
			)
		)
	)
	(footprint ""
		(layer "F.Cu")
		(at 77.283818 -80.554068 90)
		(property "Reference" "VIA4"
			(at 0 0 90)
			(layer "F.SilkS")
			(hide yes)
			(effects
				(font
					(size 1.27 1.27)
				)
			)
		)
		(property "Value" "85OHM-8L-1D6MM-L16L18-GP"
			(at 4.064 0.6096 90)
			(unlocked yes)
			(layer "F.Fab")
			(hide yes)
			(effects
				(font
					(size 1.016 1.016)
					(thickness 0.1524)
				)
			)
		)
		(property "Device Type" "VIA-PCIE-4P-368076"
			(at 4.064 -0.9144 90)
			(unlocked yes)
			(layer "F.Fab")
			(hide yes)
			(effects
				(font
					(size 1.016 1.016)
					(thickness 0.1524)
				)
			)
		)
		(duplicate_pad_numbers_are_jumpers no)
		(fp_rect
			(start -1.8415 0.381)
			(end 1.8415 -0.381)
			(stroke
				(width 0)
				(type default)
			)
			(fill no)
			(layer "F.CrtYd")
		)
		(fp_rect
			(start -1.8415 0.381)
			(end 1.8415 -0.381)
			(stroke
				(width 0)
				(type default)
			)
			(fill no)
			(layer "F.Fab")
		)
		(pad "1" thru_hole circle
			(at -1.4605 0 90)
			(size 0.508 0.508)
			(drill 0.254)
			(layers "*.Cu" "*.Mask")
			(remove_unused_layers no)
			(net "GND")
			(clearance 0.127)
			(thermal_gap 0.127)
		)
		(pad "2" thru_hole circle
			(at -0.4445 0 90)
			(size 0.508 0.508)
			(drill 0.254)
			(layers "*.Cu" "*.Mask")
			(remove_unused_layers no)
			(net "PCIE_COMP_TO_IOM_19_DP")
			(clearance 0.127)
			(thermal_gap 0.127)
		)
		(pad "3" thru_hole circle
			(at 0.4445 0 90)
			(size 0.508 0.508)
			(drill 0.254)
			(layers "*.Cu" "*.Mask")
			(remove_unused_layers no)
			(net "PCIE_COMP_TO_IOM_19_DN")
			(clearance 0.127)
			(thermal_gap 0.127)
		)
		(pad "4" thru_hole circle
			(at 1.4605 0 90)
			(size 0.508 0.508)
			(drill 0.254)
			(layers "*.Cu" "*.Mask")
			(remove_unused_layers no)
			(net "GND")
			(clearance 0.127)
			(thermal_gap 0.127)
		)
	)
	(footprint ""
		(layer "F.Cu")
		(at 68.6054 -124.5362 -90)
		(property "Reference" "R267"
			(at 0 0 270)
			(layer "F.SilkS")
			(hide yes)
			(effects
				(font
					(size 1.27 1.27)
				)
			)
		)
		(property "Value" "2K2R2J-2-GP"
			(at 0.064008 -3.993896 270)
			(unlocked yes)
			(layer "F.Fab")
			(hide yes)
			(effects
				(font
					(size 1.016 1.016)
					(thickness 0.1524)
				)
			)
		)
		(property "Device Type" "R402H16"
			(at 0.064008 -5.517896 270)
			(unlocked yes)
			(layer "F.Fab")
			(hide yes)
			(effects
				(font
					(size 1.016 1.016)
					(thickness 0.1524)
				)
			)
		)
		(duplicate_pad_numbers_are_jumpers no)
		(fp_line
			(start -0.508 -0.9398)
			(end -0.508 0.9398)
			(stroke
				(width 0.1524)
				(type default)
			)
			(layer "F.SilkS")
		)
		(fp_line
			(start 0.508 -0.9398)
			(end -0.508 -0.9398)
			(stroke
				(width 0.1524)
				(type default)
			)
			(layer "F.SilkS")
		)
		(fp_rect
			(start -0.508 0.9398)
			(end 0.508 -0.9398)
			(stroke
				(width 0)
				(type default)
			)
			(fill no)
			(layer "F.CrtYd")
		)
		(fp_rect
			(start -0.508 0.9398)
			(end 0.508 -0.9398)
			(stroke
				(width 0)
				(type default)
			)
			(fill no)
			(layer "F.Fab")
		)
		(pad "1" smd custom
			(at 0 -0.4445 270)
			(size 0.1397 0.1397)
			(layers "F.Cu" "F.Mask" "F.Paste")
			(net "P3V3_STBY")
			(options
				(clearance outline)
				(anchor circle)
			)
			(primitives
				(gr_poly
					(pts
						(arc
							(start -0.1778 -0.2794)
							(mid -0.249642 -0.249642)
							(end -0.2794 -0.1778)
						)
						(arc
							(start -0.2794 0.1778)
							(mid -0.249642 0.249642)
							(end -0.1778 0.2794)
						)
						(arc
							(start 0.1778 0.2794)
							(mid 0.249642 0.249642)
							(end 0.2794 0.1778)
						)
						(arc
							(start 0.2794 -0.1778)
							(mid 0.249642 -0.249642)
							(end 0.1778 -0.2794)
						)
					)
					(width 0)
					(fill yes)
				)
			)
		)
		(pad "2" smd custom
			(at 0 0.4445 270)
			(size 0.1397 0.1397)
			(layers "F.Cu" "F.Mask" "F.Paste")
			(net "FLA_CS_1_R")
			(options
				(clearance outline)
				(anchor circle)
			)
			(primitives
				(gr_poly
					(pts
						(arc
							(start -0.1778 -0.2794)
							(mid -0.249642 -0.249642)
							(end -0.2794 -0.1778)
						)
						(arc
							(start -0.2794 0.1778)
							(mid -0.249642 0.249642)
							(end -0.1778 0.2794)
						)
						(arc
							(start 0.1778 0.2794)
							(mid 0.249642 0.249642)
							(end 0.2794 0.1778)
						)
						(arc
							(start 0.2794 -0.1778)
							(mid 0.249642 -0.249642)
							(end 0.1778 -0.2794)
						)
					)
					(width 0)
					(fill yes)
				)
			)
		)
	)
	(footprint ""
		(layer "F.Cu")
		(at 74.934572 -167.279828 180)
		(property "Reference" "C241"
			(at 0 0 180)
			(layer "F.SilkS")
			(hide yes)
			(effects
				(font
					(size 1.27 1.27)
				)
			)
		)
		(property "Value" "SC1U16V3KX-5GP"
			(at 0 -2.8194 180)
			(unlocked yes)
			(layer "F.Fab")
			(hide yes)
			(effects
				(font
					(size 1.016 1.016)
					(thickness 0.1524)
				)
			)
		)
		(property "Device Type" "C603H36"
			(at 0 -4.3434 180)
			(unlocked yes)
			(layer "F.Fab")
			(hide yes)
			(effects
				(font
					(size 1.016 1.016)
					(thickness 0.1524)
				)
			)
		)
		(duplicate_pad_numbers_are_jumpers no)
		(fp_line
			(start 0.508 0)
			(end -0.508 0)
			(stroke
				(width 0.2032)
				(type default)
			)
			(layer "F.SilkS")
		)
		(fp_rect
			(start -0.5842 1.3335)
			(end 0.5842 -1.3335)
			(stroke
				(width 0)
				(type default)
			)
			(fill no)
			(layer "F.CrtYd")
		)
		(fp_rect
			(start -0.5842 1.3335)
			(end 0.5842 -1.3335)
			(stroke
				(width 0)
				(type default)
			)
			(fill no)
			(layer "F.Fab")
		)
		(pad "1" smd custom
			(at 0 -0.762 180)
			(size 0.2159 0.2159)
			(layers "F.Cu" "F.Mask" "F.Paste")
			(net "TPS74801_P1V15_STBY_BIAS")
			(options
				(clearance outline)
				(anchor circle)
			)
			(primitives
				(gr_poly
					(pts
						(arc
							(start -0.3302 -0.4318)
							(mid -0.402042 -0.402042)
							(end -0.4318 -0.3302)
						)
						(arc
							(start -0.4318 0.3302)
							(mid -0.402042 0.402042)
							(end -0.3302 0.4318)
						)
						(arc
							(start 0.3302 0.4318)
							(mid 0.402042 0.402042)
							(end 0.4318 0.3302)
						)
						(arc
							(start 0.4318 -0.3302)
							(mid 0.402042 -0.402042)
							(end 0.3302 -0.4318)
						)
					)
					(width 0)
					(fill yes)
				)
			)
		)
		(pad "2" smd custom
			(at 0 0.762 180)
			(size 0.2159 0.2159)
			(layers "F.Cu" "F.Mask" "F.Paste")
			(net "GND")
			(options
				(clearance outline)
				(anchor circle)
			)
			(primitives
				(gr_poly
					(pts
						(arc
							(start -0.3302 -0.4318)
							(mid -0.402042 -0.402042)
							(end -0.4318 -0.3302)
						)
						(arc
							(start -0.4318 0.3302)
							(mid -0.402042 0.402042)
							(end -0.3302 0.4318)
						)
						(arc
							(start 0.3302 0.4318)
							(mid 0.402042 0.402042)
							(end 0.4318 0.3302)
						)
						(arc
							(start 0.4318 -0.3302)
							(mid 0.402042 -0.402042)
							(end 0.3302 -0.4318)
						)
					)
					(width 0)
					(fill yes)
				)
			)
		)
	)
	(footprint ""
		(layer "F.Cu")
		(at 63.440564 -144.045432 90)
		(property "Reference" "R181"
			(at 0 0 90)
			(layer "F.SilkS")
			(hide yes)
			(effects
				(font
					(size 1.27 1.27)
				)
			)
		)
		(property "Value" "2K2R2F-GP"
			(at 0.064008 -3.993896 90)
			(unlocked yes)
			(layer "F.Fab")
			(hide yes)
			(effects
				(font
					(size 1.016 1.016)
					(thickness 0.1524)
				)
			)
		)
		(property "Device Type" "R402H16"
			(at 0.064008 -5.517896 90)
			(unlocked yes)
			(layer "F.Fab")
			(hide yes)
			(effects
				(font
					(size 1.016 1.016)
					(thickness 0.1524)
				)
			)
		)
		(duplicate_pad_numbers_are_jumpers no)
		(fp_line
			(start 0.508 -0.9398)
			(end -0.508 -0.9398)
			(stroke
				(width 0.1524)
				(type default)
			)
			(layer "F.SilkS")
		)
		(fp_line
			(start -0.508 -0.9398)
			(end -0.508 0.9398)
			(stroke
				(width 0.1524)
				(type default)
			)
			(layer "F.SilkS")
		)
		(fp_rect
			(start -0.508 0.9398)
			(end 0.508 -0.9398)
			(stroke
				(width 0)
				(type default)
			)
			(fill no)
			(layer "F.CrtYd")
		)
		(fp_rect
			(start -0.508 0.9398)
			(end 0.508 -0.9398)
			(stroke
				(width 0)
				(type default)
			)
			(fill no)
			(layer "F.Fab")
		)
		(pad "1" smd custom
			(at 0 -0.4445 90)
			(size 0.1397 0.1397)
			(layers "F.Cu" "F.Mask" "F.Paste")
			(net "I2C_SCC_SCL_OUT")
			(options
				(clearance outline)
				(anchor circle)
			)
			(primitives
				(gr_poly
					(pts
						(arc
							(start -0.1778 -0.2794)
							(mid -0.249642 -0.249642)
							(end -0.2794 -0.1778)
						)
						(arc
							(start -0.2794 0.1778)
							(mid -0.249642 0.249642)
							(end -0.1778 0.2794)
						)
						(arc
							(start 0.1778 0.2794)
							(mid 0.249642 0.249642)
							(end 0.2794 0.1778)
						)
						(arc
							(start 0.2794 -0.1778)
							(mid 0.249642 -0.249642)
							(end 0.1778 -0.2794)
						)
					)
					(width 0)
					(fill yes)
				)
			)
		)
		(pad "2" smd custom
			(at 0 0.4445 90)
			(size 0.1397 0.1397)
			(layers "F.Cu" "F.Mask" "F.Paste")
			(net "P3V3_STBY")
			(options
				(clearance outline)
				(anchor circle)
			)
			(primitives
				(gr_poly
					(pts
						(arc
							(start -0.1778 -0.2794)
							(mid -0.249642 -0.249642)
							(end -0.2794 -0.1778)
						)
						(arc
							(start -0.2794 0.1778)
							(mid -0.249642 0.249642)
							(end -0.1778 0.2794)
						)
						(arc
							(start 0.1778 0.2794)
							(mid 0.249642 0.249642)
							(end 0.2794 0.1778)
						)
						(arc
							(start 0.2794 -0.1778)
							(mid 0.249642 -0.249642)
							(end 0.1778 -0.2794)
						)
					)
					(width 0)
					(fill yes)
				)
			)
		)
	)
	(footprint ""
		(layer "F.Cu")
		(at 209.85988 -15.5702 -90)
		(property "Reference" "Q29"
			(at 0 0 270)
			(layer "F.SilkS")
			(hide yes)
			(effects
				(font
					(size 1.27 1.27)
				)
			)
		)
		(property "Value" "2N7002K-1-GP"
			(at 0.127 -8.9662 270)
			(unlocked yes)
			(layer "F.Fab")
			(hide yes)
			(effects
				(font
					(size 1.016 1.016)
					(thickness 0.1524)
				)
			)
		)
		(property "Device Type" "SOT23DGS2D4H44"
			(at 0.127 -10.4902 270)
			(unlocked yes)
			(layer "F.Fab")
			(hide yes)
			(effects
				(font
					(size 1.016 1.016)
					(thickness 0.1524)
				)
			)
		)
		(duplicate_pad_numbers_are_jumpers no)
		(fp_line
			(start -1.651 1.778)
			(end 1.651 1.778)
			(stroke
				(width 0.1524)
				(type default)
			)
			(layer "F.SilkS")
		)
		(fp_line
			(start 1.651 1.778)
			(end 1.651 -1.778)
			(stroke
				(width 0.1524)
				(type default)
			)
			(layer "F.SilkS")
		)
		(fp_line
			(start -1.651 -1.778)
			(end -1.651 1.778)
			(stroke
				(width 0.1524)
				(type default)
			)
			(layer "F.SilkS")
		)
		(fp_line
			(start 1.651 -1.778)
			(end -1.651 -1.778)
			(stroke
				(width 0.1524)
				(type default)
			)
			(layer "F.SilkS")
		)
		(fp_poly
			(pts
				(xy -1.778 1.8796) (xy -1.778 -1.8796) (xy 1.778 -1.8796) (xy 1.778 1.8796)
			)
			(stroke
				(width 0)
				(type default)
			)
			(fill no)
			(layer "F.CrtYd")
		)
		(fp_poly
			(pts
				(xy -1.778 1.8796) (xy -1.778 -1.8796) (xy 1.778 -1.8796) (xy 1.778 1.8796)
			)
			(stroke
				(width 0)
				(type default)
			)
			(fill no)
			(layer "F.Fab")
		)
		(pad "D" smd custom
			(at 0 -0.9525 270)
			(size 0.1905 0.1905)
			(layers "F.Cu" "F.Mask" "F.Paste")
			(net "BMC_ML_PWR_BLUE_LED_L")
			(options
				(clearance outline)
				(anchor circle)
			)
			(primitives
				(gr_poly
					(pts
						(arc
							(start -0.1778 0.5715)
							(mid -0.321484 0.511984)
							(end -0.381 0.3683)
						)
						(arc
							(start -0.381 -0.3683)
							(mid -0.321484 -0.511984)
							(end -0.1778 -0.5715)
						)
						(arc
							(start 0.1778 -0.5715)
							(mid 0.321484 -0.511984)
							(end 0.381 -0.3683)
						)
						(arc
							(start 0.381 0.3683)
							(mid 0.321484 0.511984)
							(end 0.1778 0.5715)
						)
					)
					(width 0)
					(fill yes)
				)
			)
		)
		(pad "G" smd custom
			(at -0.98425 0.9525 270)
			(size 0.1905 0.1905)
			(layers "F.Cu" "F.Mask" "F.Paste")
			(net "BMC_ML_PWR_BLUE_LED_R")
			(options
				(clearance outline)
				(anchor circle)
			)
			(primitives
				(gr_poly
					(pts
						(arc
							(start -0.1778 0.5715)
							(mid -0.321484 0.511984)
							(end -0.381 0.3683)
						)
						(arc
							(start -0.381 -0.3683)
							(mid -0.321484 -0.511984)
							(end -0.1778 -0.5715)
						)
						(arc
							(start 0.1778 -0.5715)
							(mid 0.321484 -0.511984)
							(end 0.381 -0.3683)
						)
						(arc
							(start 0.381 0.3683)
							(mid 0.321484 0.511984)
							(end 0.1778 0.5715)
						)
					)
					(width 0)
					(fill yes)
				)
			)
		)
		(pad "S" smd custom
			(at 0.98425 0.9525 270)
			(size 0.1905 0.1905)
			(layers "F.Cu" "F.Mask" "F.Paste")
			(net "GND")
			(options
				(clearance outline)
				(anchor circle)
			)
			(primitives
				(gr_poly
					(pts
						(arc
							(start -0.1778 0.5715)
							(mid -0.321484 0.511984)
							(end -0.381 0.3683)
						)
						(arc
							(start -0.381 -0.3683)
							(mid -0.321484 -0.511984)
							(end -0.1778 -0.5715)
						)
						(arc
							(start 0.1778 -0.5715)
							(mid 0.321484 -0.511984)
							(end 0.381 -0.3683)
						)
						(arc
							(start 0.381 0.3683)
							(mid 0.321484 0.511984)
							(end 0.1778 0.5715)
						)
					)
					(width 0)
					(fill yes)
				)
			)
		)
	)
	(footprint ""
		(layer "F.Cu")
		(at 36.9062 -158.623)
		(property "Reference" "R714"
			(at 0 0 0)
			(layer "F.SilkS")
			(hide yes)
			(effects
				(font
					(size 1.27 1.27)
				)
			)
		)
		(property "Value" "0R2J-2-GP"
			(at 0.064008 -3.993896 0)
			(unlocked yes)
			(layer "F.Fab")
			(hide yes)
			(effects
				(font
					(size 1.016 1.016)
					(thickness 0.1524)
				)
			)
		)
		(property "Device Type" "R402H16"
			(at 0.064008 -5.517896 0)
			(unlocked yes)
			(layer "F.Fab")
			(hide yes)
			(effects
				(font
					(size 1.016 1.016)
					(thickness 0.1524)
				)
			)
		)
		(duplicate_pad_numbers_are_jumpers no)
		(fp_line
			(start -0.508 -0.9398)
			(end -0.508 0.9398)
			(stroke
				(width 0.1524)
				(type default)
			)
			(layer "F.SilkS")
		)
		(fp_line
			(start 0.508 -0.9398)
			(end -0.508 -0.9398)
			(stroke
				(width 0.1524)
				(type default)
			)
			(layer "F.SilkS")
		)
		(fp_rect
			(start -0.508 0.9398)
			(end 0.508 -0.9398)
			(stroke
				(width 0)
				(type default)
			)
			(fill no)
			(layer "F.CrtYd")
		)
		(fp_rect
			(start -0.508 0.9398)
			(end 0.508 -0.9398)
			(stroke
				(width 0)
				(type default)
			)
			(fill no)
			(layer "F.Fab")
		)
		(pad "1" smd custom
			(at 0 -0.4445)
			(size 0.1397 0.1397)
			(layers "F.Cu" "F.Mask" "F.Paste")
			(net "PWM_OUT_ZONE_D")
			(options
				(clearance outline)
				(anchor circle)
			)
			(primitives
				(gr_poly
					(pts
						(arc
							(start -0.1778 -0.2794)
							(mid -0.249642 -0.249642)
							(end -0.2794 -0.1778)
						)
						(arc
							(start -0.2794 0.1778)
							(mid -0.249642 0.249642)
							(end -0.1778 0.2794)
						)
						(arc
							(start 0.1778 0.2794)
							(mid 0.249642 0.249642)
							(end 0.2794 0.1778)
						)
						(arc
							(start 0.2794 -0.1778)
							(mid 0.249642 -0.249642)
							(end 0.1778 -0.2794)
						)
					)
					(width 0)
					(fill yes)
				)
			)
		)
		(pad "2" smd custom
			(at 0 0.4445)
			(size 0.1397 0.1397)
			(layers "F.Cu" "F.Mask" "F.Paste")
			(net "FAN_PWM1_BMC")
			(options
				(clearance outline)
				(anchor circle)
			)
			(primitives
				(gr_poly
					(pts
						(arc
							(start -0.1778 -0.2794)
							(mid -0.249642 -0.249642)
							(end -0.2794 -0.1778)
						)
						(arc
							(start -0.2794 0.1778)
							(mid -0.249642 0.249642)
							(end -0.1778 0.2794)
						)
						(arc
							(start 0.1778 0.2794)
							(mid 0.249642 0.249642)
							(end 0.2794 0.1778)
						)
						(arc
							(start 0.2794 -0.1778)
							(mid 0.249642 -0.249642)
							(end 0.1778 -0.2794)
						)
					)
					(width 0)
					(fill yes)
				)
			)
		)
	)
	(footprint ""
		(layer "F.Cu")
		(at 192.303146 -133.290564)
		(property "Reference" "C280"
			(at 0 0 0)
			(layer "F.SilkS")
			(hide yes)
			(effects
				(font
					(size 1.27 1.27)
				)
			)
		)
		(property "Value" "SC1U10V2KX-1GP"
			(at 1.1811 -2.7051 0)
			(unlocked yes)
			(layer "F.Fab")
			(hide yes)
			(effects
				(font
					(size 1.016 1.016)
					(thickness 0.1524)
				)
			)
		)
		(property "Device Type" "C402H22"
			(at 1.1811 -4.2291 0)
			(unlocked yes)
			(layer "F.Fab")
			(hide yes)
			(effects
				(font
					(size 1.016 1.016)
					(thickness 0.1524)
				)
			)
		)
		(duplicate_pad_numbers_are_jumpers no)
		(fp_rect
			(start -0.4318 0.9525)
			(end 0.4318 -0.9525)
			(stroke
				(width 0)
				(type default)
			)
			(fill no)
			(layer "F.CrtYd")
		)
		(fp_rect
			(start -0.4318 0.9525)
			(end 0.4318 -0.9525)
			(stroke
				(width 0)
				(type default)
			)
			(fill no)
			(layer "F.Fab")
		)
		(pad "1" smd custom
			(at 0 -0.4445)
			(size 0.1524 0.1524)
			(layers "F.Cu" "F.Mask" "F.Paste")
			(net "GND")
			(options
				(clearance outline)
				(anchor circle)
			)
			(primitives
				(gr_poly
					(pts
						(arc
							(start 0.3048 -0.2032)
							(mid 0.275042 -0.275042)
							(end 0.2032 -0.3048)
						)
						(arc
							(start -0.2032 -0.3048)
							(mid -0.275042 -0.275042)
							(end -0.3048 -0.2032)
						)
						(arc
							(start -0.3048 0.2032)
							(mid -0.275042 0.275042)
							(end -0.2032 0.3048)
						)
						(arc
							(start 0.2032 0.3048)
							(mid 0.275042 0.275042)
							(end 0.3048 0.2032)
						)
					)
					(width 0)
					(fill yes)
				)
			)
		)
		(pad "2" smd custom
			(at 0 0.4445)
			(size 0.1524 0.1524)
			(layers "F.Cu" "F.Mask" "F.Paste")
			(net "VT235_EN")
			(options
				(clearance outline)
				(anchor circle)
			)
			(primitives
				(gr_poly
					(pts
						(arc
							(start 0.3048 -0.2032)
							(mid 0.275042 -0.275042)
							(end 0.2032 -0.3048)
						)
						(arc
							(start -0.2032 -0.3048)
							(mid -0.275042 -0.275042)
							(end -0.3048 -0.2032)
						)
						(arc
							(start -0.3048 0.2032)
							(mid -0.275042 0.275042)
							(end -0.2032 0.3048)
						)
						(arc
							(start 0.2032 0.3048)
							(mid 0.275042 0.275042)
							(end 0.3048 0.2032)
						)
					)
					(width 0)
					(fill yes)
				)
			)
		)
	)
	(footprint ""
		(layer "F.Cu")
		(at 25.844246 -186.56681 180)
		(property "Reference" "C170"
			(at 0 0 180)
			(layer "F.SilkS")
			(hide yes)
			(effects
				(font
					(size 1.27 1.27)
				)
			)
		)
		(property "Value" "SC10U16V5KX-7-GP-U"
			(at -0.0762 -6.1214 180)
			(unlocked yes)
			(layer "F.Fab")
			(hide yes)
			(effects
				(font
					(size 1.016 1.016)
					(thickness 0.1524)
				)
			)
		)
		(property "Device Type" "C805H58"
			(at -0.0762 -8.1534 180)
			(unlocked yes)
			(layer "F.Fab")
			(hide yes)
			(effects
				(font
					(size 1.016 1.016)
					(thickness 0.1524)
				)
			)
		)
		(duplicate_pad_numbers_are_jumpers no)
		(fp_line
			(start 0.635 0)
			(end -0.635 0)
			(stroke
				(width 0.508)
				(type default)
			)
			(layer "F.SilkS")
		)
		(fp_rect
			(start -0.9652 1.778)
			(end 0.9652 -1.778)
			(stroke
				(width 0)
				(type default)
			)
			(fill no)
			(layer "F.CrtYd")
		)
		(fp_poly
			(pts
				(xy -0.9652 -1.778) (xy 0.9652 -1.778) (xy 0.9652 1.778) (xy -0.9652 1.778)
			)
			(stroke
				(width 0)
				(type default)
			)
			(fill no)
			(layer "F.Fab")
		)
		(pad "1" smd rect
			(at 0 -0.9652 180)
			(size 1.397 1.143)
			(layers "F.Cu" "F.Mask" "F.Paste")
			(net "P12V_STBY_VIN_PU2")
		)
		(pad "2" smd rect
			(at 0 0.9652 180)
			(size 1.397 1.143)
			(layers "F.Cu" "F.Mask" "F.Paste")
			(net "GND")
		)
	)
	(footprint ""
		(layer "F.Cu")
		(at 28.346146 -178.17211 -90)
		(property "Reference" "R492"
			(at 0 0 270)
			(layer "F.SilkS")
			(hide yes)
			(effects
				(font
					(size 1.27 1.27)
				)
			)
		)
		(property "Value" "475KR2F-GP"
			(at 0.064008 -3.993896 270)
			(unlocked yes)
			(layer "F.Fab")
			(hide yes)
			(effects
				(font
					(size 1.016 1.016)
					(thickness 0.1524)
				)
			)
		)
		(property "Device Type" "R402H16"
			(at 0.064008 -5.517896 270)
			(unlocked yes)
			(layer "F.Fab")
			(hide yes)
			(effects
				(font
					(size 1.016 1.016)
					(thickness 0.1524)
				)
			)
		)
		(duplicate_pad_numbers_are_jumpers no)
		(fp_line
			(start -0.508 -0.9398)
			(end -0.508 0.9398)
			(stroke
				(width 0.1524)
				(type default)
			)
			(layer "F.SilkS")
		)
		(fp_line
			(start 0.508 -0.9398)
			(end -0.508 -0.9398)
			(stroke
				(width 0.1524)
				(type default)
			)
			(layer "F.SilkS")
		)
		(fp_rect
			(start -0.508 0.9398)
			(end 0.508 -0.9398)
			(stroke
				(width 0)
				(type default)
			)
			(fill no)
			(layer "F.CrtYd")
		)
		(fp_rect
			(start -0.508 0.9398)
			(end 0.508 -0.9398)
			(stroke
				(width 0)
				(type default)
			)
			(fill no)
			(layer "F.Fab")
		)
		(pad "1" smd custom
			(at 0 -0.4445 270)
			(size 0.1397 0.1397)
			(layers "F.Cu" "F.Mask" "F.Paste")
			(net "P3V3_STBY_MODE")
			(options
				(clearance outline)
				(anchor circle)
			)
			(primitives
				(gr_poly
					(pts
						(arc
							(start -0.1778 -0.2794)
							(mid -0.249642 -0.249642)
							(end -0.2794 -0.1778)
						)
						(arc
							(start -0.2794 0.1778)
							(mid -0.249642 0.249642)
							(end -0.1778 0.2794)
						)
						(arc
							(start 0.1778 0.2794)
							(mid 0.249642 0.249642)
							(end 0.2794 0.1778)
						)
						(arc
							(start 0.2794 -0.1778)
							(mid 0.249642 -0.249642)
							(end 0.1778 -0.2794)
						)
					)
					(width 0)
					(fill yes)
				)
			)
		)
		(pad "2" smd custom
			(at 0 0.4445 270)
			(size 0.1397 0.1397)
			(layers "F.Cu" "F.Mask" "F.Paste")
			(net "PWRGD_P3V3_STBY")
			(options
				(clearance outline)
				(anchor circle)
			)
			(primitives
				(gr_poly
					(pts
						(arc
							(start -0.1778 -0.2794)
							(mid -0.249642 -0.249642)
							(end -0.2794 -0.1778)
						)
						(arc
							(start -0.2794 0.1778)
							(mid -0.249642 0.249642)
							(end -0.1778 0.2794)
						)
						(arc
							(start 0.1778 0.2794)
							(mid 0.249642 0.249642)
							(end 0.2794 0.1778)
						)
						(arc
							(start 0.2794 -0.1778)
							(mid 0.249642 -0.249642)
							(end 0.1778 -0.2794)
						)
					)
					(width 0)
					(fill yes)
				)
			)
		)
	)
	(footprint ""
		(layer "F.Cu")
		(at 158.7754 -127.5588)
		(property "Reference" "L10"
			(at 0 0 0)
			(layer "F.SilkS")
			(hide yes)
			(effects
				(font
					(size 1.27 1.27)
				)
			)
		)
		(property "Value" "COIL-3D3UH-48-GP"
			(at -3.8735 -3.048 0)
			(unlocked yes)
			(layer "F.Fab")
			(hide yes)
			(effects
				(font
					(size 1.016 1.016)
					(thickness 0.1524)
				)
			)
		)
		(property "Device Type" "L4947-1215H119"
			(at -3.8735 -4.572 0)
			(unlocked yes)
			(layer "F.Fab")
			(hide yes)
			(effects
				(font
					(size 1.016 1.016)
					(thickness 0.1524)
				)
			)
		)
		(duplicate_pad_numbers_are_jumpers no)
		(fp_line
			(start -2.6035 -3.429)
			(end 2.6035 -3.429)
			(stroke
				(width 0.1524)
				(type default)
			)
			(layer "F.SilkS")
		)
		(fp_line
			(start -2.6035 3.429)
			(end -2.6035 -3.429)
			(stroke
				(width 0.1524)
				(type default)
			)
			(layer "F.SilkS")
		)
		(fp_line
			(start 2.6035 -3.429)
			(end 2.6035 3.429)
			(stroke
				(width 0.1524)
				(type default)
			)
			(layer "F.SilkS")
		)
		(fp_line
			(start 2.6035 3.429)
			(end -2.6035 3.429)
			(stroke
				(width 0.1524)
				(type default)
			)
			(layer "F.SilkS")
		)
		(fp_rect
			(start -2.3495 2.4257)
			(end 2.3495 -2.4257)
			(stroke
				(width 0)
				(type default)
			)
			(fill no)
			(layer "F.CrtYd")
		)
		(fp_poly
			(pts
				(xy -2.8575 3.5052) (xy -2.8575 2.4257) (xy 2.3495 2.4257) (xy 2.3495 -2.4257) (xy -2.3495 -2.4257)
				(xy -2.3495 2.413) (xy -2.8575 2.413) (xy -2.8575 -3.5052) (xy 2.8575 -3.5052) (xy 2.8575 3.5052)
			)
			(stroke
				(width 0)
				(type default)
			)
			(fill no)
			(layer "F.CrtYd")
		)
		(fp_rect
			(start -2.8575 3.5052)
			(end 2.8575 -3.5052)
			(stroke
				(width 0)
				(type default)
			)
			(fill no)
			(layer "F.Fab")
		)
		(pad "1" smd rect
			(at 0 -1.999996)
			(size 2.0066 2.3622)
			(layers "F.Cu" "F.Mask" "F.Paste")
			(net "P1V8_STBY_SW")
		)
		(pad "2" smd rect
			(at 0 1.999996)
			(size 2.0066 2.3622)
			(layers "F.Cu" "F.Mask" "F.Paste")
			(net "P1V8_STBY")
		)
	)
	(footprint ""
		(layer "F.Cu")
		(at 159.29864 -136.662922)
		(property "Reference" "PU4"
			(at 0 0 0)
			(layer "F.SilkS")
			(hide yes)
			(effects
				(font
					(size 1.27 1.27)
				)
			)
		)
		(property "Value" "TPS53312RGTR-GP"
			(at 4.9784 -6.9342 0)
			(unlocked yes)
			(layer "F.Fab")
			(hide yes)
			(effects
				(font
					(size 1.016 1.016)
					(thickness 0.1524)
				)
			)
		)
		(property "Device Type" "QFN16G3-G1D7H40"
			(at 4.9784 -8.4582 0)
			(unlocked yes)
			(layer "F.Fab")
			(hide yes)
			(effects
				(font
					(size 1.016 1.016)
					(thickness 0.1524)
				)
			)
		)
		(duplicate_pad_numbers_are_jumpers no)
		(fp_line
			(start -2.5146 -2.5146)
			(end -2.5146 -1.2446)
			(stroke
				(width 0.1524)
				(type default)
			)
			(layer "F.SilkS")
		)
		(fp_line
			(start -2.5146 1.2446)
			(end -2.5146 2.5146)
			(stroke
				(width 0.1524)
				(type default)
			)
			(layer "F.SilkS")
		)
		(fp_line
			(start -2.5146 2.5146)
			(end -1.2446 2.5146)
			(stroke
				(width 0.1524)
				(type default)
			)
			(layer "F.SilkS")
		)
		(fp_line
			(start -2.262124 -0.750062)
			(end -2.770124 -0.750062)
			(stroke
				(width 0.1524)
				(type default)
			)
			(layer "F.SilkS")
		)
		(fp_line
			(start -1.2446 -2.5146)
			(end -2.5146 -2.5146)
			(stroke
				(width 0.1524)
				(type default)
			)
			(layer "F.SilkS")
		)
		(fp_line
			(start -0.249936 2.262124)
			(end -0.249936 3.024124)
			(stroke
				(width 0.1524)
				(type default)
			)
			(layer "F.SilkS")
		)
		(fp_line
			(start 1.2446 2.5146)
			(end 2.5146 2.5146)
			(stroke
				(width 0.1524)
				(type default)
			)
			(layer "F.SilkS")
		)
		(fp_line
			(start 2.262124 -0.249936)
			(end 2.770124 -0.249936)
			(stroke
				(width 0.1524)
				(type default)
			)
			(layer "F.SilkS")
		)
		(fp_line
			(start 2.5146 2.5146)
			(end 2.5146 1.2446)
			(stroke
				(width 0.1524)
				(type default)
			)
			(layer "F.SilkS")
		)
		(fp_poly
			(pts
				(xy 2.5146 -2.5146) (xy 1.2446 -2.5146) (xy 2.5146 -1.2446)
			)
			(stroke
				(width 0)
				(type default)
			)
			(fill yes)
			(layer "F.SilkS")
		)
		(fp_rect
			(start -1.4986 1.4986)
			(end 1.4986 -1.4986)
			(stroke
				(width 0)
				(type default)
			)
			(fill no)
			(layer "F.CrtYd")
		)
		(fp_poly
			(pts
				(xy 2.5146 -1.4986) (xy -1.4986 -1.4986) (xy -1.4986 1.4986) (xy 1.4986 1.4986) (xy 1.4986 -1.4859)
				(xy 2.5146 -1.4859) (xy 2.5146 2.5146) (xy -2.5146 2.5146) (xy -2.5146 -2.5146) (xy 2.5146 -2.5146)
			)
			(stroke
				(width 0)
				(type default)
			)
			(fill no)
			(layer "F.CrtYd")
		)
		(fp_rect
			(start -2.5146 2.5146)
			(end 2.5146 -2.5146)
			(stroke
				(width 0)
				(type default)
			)
			(fill no)
			(layer "F.Fab")
		)
		(pad "1" smd rect
			(at 0.750062 -1.550924)
			(size 0.3048 0.9144)
			(layers "F.Cu" "F.Mask" "F.Paste")
			(net "P1V8_STBY_VFB")
		)
		(pad "2" smd rect
			(at 0.249936 -1.538224)
			(size 0.3048 0.9398)
			(layers "F.Cu" "F.Mask" "F.Paste")
			(net "P1V8_STBY_VRG5")
		)
		(pad "3" smd rect
			(at -0.249936 -1.538224)
			(size 0.3048 0.9398)
			(layers "F.Cu" "F.Mask" "F.Paste")
			(net "P1V8_STBY_SS")
		)
		(pad "4" smd rect
			(at -0.750062 -1.550924)
			(size 0.3048 0.9144)
			(layers "F.Cu" "F.Mask" "F.Paste")
			(net "AGND_P1V8_STBY")
		)
		(pad "5" smd rect
			(at -1.550924 -0.750062)
			(size 0.9144 0.3048)
			(layers "F.Cu" "F.Mask" "F.Paste")
			(net "PWRGD_P1V8_STBY")
		)
		(pad "6" smd rect
			(at -1.538224 -0.249936)
			(size 0.9398 0.3048)
			(layers "F.Cu" "F.Mask" "F.Paste")
			(net "P1V8_STBY_EN_R")
		)
		(pad "7" smd rect
			(at -1.538224 0.249936)
			(size 0.9398 0.3048)
			(layers "F.Cu" "F.Mask" "F.Paste")
			(net "GND")
		)
		(pad "8" smd rect
			(at -1.550924 0.750062)
			(size 0.9144 0.3048)
			(layers "F.Cu" "F.Mask" "F.Paste")
			(net "GND")
		)
		(pad "9" smd rect
			(at -0.750062 1.550924)
			(size 0.3048 0.9144)
			(layers "F.Cu" "F.Mask" "F.Paste")
			(net "P1V8_STBY_SW")
		)
		(pad "10" smd rect
			(at -0.249936 1.538224)
			(size 0.3048 0.9398)
			(layers "F.Cu" "F.Mask" "F.Paste")
			(net "P1V8_STBY_SW")
		)
		(pad "11" smd rect
			(at 0.249936 1.538224)
			(size 0.3048 0.9398)
			(layers "F.Cu" "F.Mask" "F.Paste")
			(net "P1V8_STBY_SW")
		)
		(pad "12" smd rect
			(at 0.750062 1.550924)
			(size 0.3048 0.9144)
			(layers "F.Cu" "F.Mask" "F.Paste")
			(net "P1V8_STBY_VBST")
		)
		(pad "13" smd rect
			(at 1.550924 0.750062)
			(size 0.9144 0.3048)
			(layers "F.Cu" "F.Mask" "F.Paste")
			(net "P12V_STBY_VIN_PU4")
		)
		(pad "14" smd rect
			(at 1.538224 0.249936)
			(size 0.9398 0.3048)
			(layers "F.Cu" "F.Mask" "F.Paste")
			(net "P12V_STBY_VIN_PU4")
		)
		(pad "15" smd rect
			(at 1.538224 -0.249936)
			(size 0.9398 0.3048)
			(layers "F.Cu" "F.Mask" "F.Paste")
			(net "P12V_STBY_VCC_PU4")
		)
		(pad "16" smd rect
			(at 1.550924 -0.750062)
			(size 0.9144 0.3048)
			(layers "F.Cu" "F.Mask" "F.Paste")
			(net "P1V8_STBY_VO")
		)
		(pad "17" smd rect
			(at 0 0)
			(size 1.6764 1.6764)
			(layers "F.Cu" "F.Mask" "F.Paste")
			(net "GND")
		)
	)
	(footprint ""
		(layer "F.Cu")
		(at 57.785 -163.5252 180)
		(property "Reference" "C120"
			(at 0 0 180)
			(layer "F.SilkS")
			(hide yes)
			(effects
				(font
					(size 1.27 1.27)
				)
			)
		)
		(property "Value" "SCD1U25V2KX-2-GP"
			(at 1.1811 -2.7051 180)
			(unlocked yes)
			(layer "F.Fab")
			(hide yes)
			(effects
				(font
					(size 1.016 1.016)
					(thickness 0.1524)
				)
			)
		)
		(property "Device Type" "C402H22"
			(at 1.1811 -4.2291 180)
			(unlocked yes)
			(layer "F.Fab")
			(hide yes)
			(effects
				(font
					(size 1.016 1.016)
					(thickness 0.1524)
				)
			)
		)
		(duplicate_pad_numbers_are_jumpers no)
		(fp_rect
			(start -0.4318 0.9525)
			(end 0.4318 -0.9525)
			(stroke
				(width 0)
				(type default)
			)
			(fill no)
			(layer "F.CrtYd")
		)
		(fp_rect
			(start -0.4318 0.9525)
			(end 0.4318 -0.9525)
			(stroke
				(width 0)
				(type default)
			)
			(fill no)
			(layer "F.Fab")
		)
		(pad "1" smd custom
			(at 0 -0.4445 180)
			(size 0.1524 0.1524)
			(layers "F.Cu" "F.Mask" "F.Paste")
			(net "ADC_P3V3_STBY")
			(options
				(clearance outline)
				(anchor circle)
			)
			(primitives
				(gr_poly
					(pts
						(arc
							(start 0.3048 -0.2032)
							(mid 0.275042 -0.275042)
							(end 0.2032 -0.3048)
						)
						(arc
							(start -0.2032 -0.3048)
							(mid -0.275042 -0.275042)
							(end -0.3048 -0.2032)
						)
						(arc
							(start -0.3048 0.2032)
							(mid -0.275042 0.275042)
							(end -0.2032 0.3048)
						)
						(arc
							(start 0.2032 0.3048)
							(mid 0.275042 0.275042)
							(end 0.3048 0.2032)
						)
					)
					(width 0)
					(fill yes)
				)
			)
		)
		(pad "2" smd custom
			(at 0 0.4445 180)
			(size 0.1524 0.1524)
			(layers "F.Cu" "F.Mask" "F.Paste")
			(net "GND")
			(options
				(clearance outline)
				(anchor circle)
			)
			(primitives
				(gr_poly
					(pts
						(arc
							(start 0.3048 -0.2032)
							(mid 0.275042 -0.275042)
							(end 0.2032 -0.3048)
						)
						(arc
							(start -0.2032 -0.3048)
							(mid -0.275042 -0.275042)
							(end -0.3048 -0.2032)
						)
						(arc
							(start -0.3048 0.2032)
							(mid -0.275042 0.275042)
							(end -0.2032 0.3048)
						)
						(arc
							(start 0.2032 0.3048)
							(mid 0.275042 0.275042)
							(end 0.3048 0.2032)
						)
					)
					(width 0)
					(fill yes)
				)
			)
		)
	)
	(footprint ""
		(layer "F.Cu")
		(at 61.1886 -139.0142)
		(property "Reference" "TP75"
			(at 0 0 0)
			(layer "F.SilkS")
			(hide yes)
			(effects
				(font
					(size 1.27 1.27)
				)
			)
		)
		(property "Value" "TPAD28-2-GP"
			(at -0.0127 -1.6637 0)
			(unlocked yes)
			(layer "F.Fab")
			(hide yes)
			(effects
				(font
					(size 1.016 1.016)
					(thickness 0.1524)
				)
			)
		)
		(property "Device Type" "TPAD28"
			(at -0.0127 -3.1877 0)
			(unlocked yes)
			(layer "F.Fab")
			(hide yes)
			(effects
				(font
					(size 1.016 1.016)
					(thickness 0.1524)
				)
			)
		)
		(duplicate_pad_numbers_are_jumpers no)
		(fp_poly
			(pts
				(arc
					(start 0.3556 0)
					(mid -0.3556 0)
					(end 0.3556 0)
				)
			)
			(stroke
				(width 0)
				(type default)
			)
			(fill no)
			(layer "F.CrtYd")
		)
		(fp_poly
			(pts
				(arc
					(start 0.6096 0)
					(mid -0.6096 0)
					(end 0.6096 0)
				)
			)
			(stroke
				(width 0)
				(type default)
			)
			(fill no)
			(layer "F.Fab")
		)
		(pad "1" smd circle
			(at 0 0)
			(size 0.7112 0.7112)
			(layers "F.Cu" "F.Mask" "F.Paste")
			(net "TP_BMC_GPIOI6")
		)
	)
	(footprint ""
		(layer "F.Cu")
		(at 224.3074 -56.6166)
		(property "Reference" "C306"
			(at 0 0 0)
			(layer "F.SilkS")
			(hide yes)
			(effects
				(font
					(size 1.27 1.27)
				)
			)
		)
		(property "Value" "SC12P50V2JN-3GP"
			(at 1.1811 -2.7051 0)
			(unlocked yes)
			(layer "F.Fab")
			(hide yes)
			(effects
				(font
					(size 1.016 1.016)
					(thickness 0.1524)
				)
			)
		)
		(property "Device Type" "C402H24"
			(at 1.1811 -4.2291 0)
			(unlocked yes)
			(layer "F.Fab")
			(hide yes)
			(effects
				(font
					(size 1.016 1.016)
					(thickness 0.1524)
				)
			)
		)
		(duplicate_pad_numbers_are_jumpers no)
		(fp_rect
			(start -0.4318 0.9525)
			(end 0.4318 -0.9525)
			(stroke
				(width 0)
				(type default)
			)
			(fill no)
			(layer "F.CrtYd")
		)
		(fp_rect
			(start -0.4318 0.9525)
			(end 0.4318 -0.9525)
			(stroke
				(width 0)
				(type default)
			)
			(fill no)
			(layer "F.Fab")
		)
		(pad "1" smd custom
			(at 0 -0.4445)
			(size 0.1524 0.1524)
			(layers "F.Cu" "F.Mask" "F.Paste")
			(net "REF_CLK")
			(options
				(clearance outline)
				(anchor circle)
			)
			(primitives
				(gr_poly
					(pts
						(arc
							(start 0.3048 -0.2032)
							(mid 0.275042 -0.275042)
							(end 0.2032 -0.3048)
						)
						(arc
							(start -0.2032 -0.3048)
							(mid -0.275042 -0.275042)
							(end -0.3048 -0.2032)
						)
						(arc
							(start -0.3048 0.2032)
							(mid -0.275042 0.275042)
							(end -0.2032 0.3048)
						)
						(arc
							(start 0.2032 0.3048)
							(mid 0.275042 0.275042)
							(end 0.3048 0.2032)
						)
					)
					(width 0)
					(fill yes)
				)
			)
		)
		(pad "2" smd custom
			(at 0 0.4445)
			(size 0.1524 0.1524)
			(layers "F.Cu" "F.Mask" "F.Paste")
			(net "GND")
			(options
				(clearance outline)
				(anchor circle)
			)
			(primitives
				(gr_poly
					(pts
						(arc
							(start 0.3048 -0.2032)
							(mid 0.275042 -0.275042)
							(end 0.2032 -0.3048)
						)
						(arc
							(start -0.2032 -0.3048)
							(mid -0.275042 -0.275042)
							(end -0.3048 -0.2032)
						)
						(arc
							(start -0.3048 0.2032)
							(mid -0.275042 0.275042)
							(end -0.2032 0.3048)
						)
						(arc
							(start 0.2032 0.3048)
							(mid 0.275042 0.275042)
							(end 0.3048 0.2032)
						)
					)
					(width 0)
					(fill yes)
				)
			)
		)
	)
	(footprint ""
		(layer "F.Cu")
		(at 64.077088 -156.179774)
		(property "Reference" "R382"
			(at 0 0 0)
			(layer "F.SilkS")
			(hide yes)
			(effects
				(font
					(size 1.27 1.27)
				)
			)
		)
		(property "Value" "4K7R2F-GP"
			(at 0.064008 -3.993896 0)
			(unlocked yes)
			(layer "F.Fab")
			(hide yes)
			(effects
				(font
					(size 1.016 1.016)
					(thickness 0.1524)
				)
			)
		)
		(property "Device Type" "R402H16"
			(at 0.064008 -5.517896 0)
			(unlocked yes)
			(layer "F.Fab")
			(hide yes)
			(effects
				(font
					(size 1.016 1.016)
					(thickness 0.1524)
				)
			)
		)
		(duplicate_pad_numbers_are_jumpers no)
		(fp_line
			(start -0.508 -0.9398)
			(end -0.508 0.9398)
			(stroke
				(width 0.1524)
				(type default)
			)
			(layer "F.SilkS")
		)
		(fp_line
			(start 0.508 -0.9398)
			(end -0.508 -0.9398)
			(stroke
				(width 0.1524)
				(type default)
			)
			(layer "F.SilkS")
		)
		(fp_rect
			(start -0.508 0.9398)
			(end 0.508 -0.9398)
			(stroke
				(width 0)
				(type default)
			)
			(fill no)
			(layer "F.CrtYd")
		)
		(fp_rect
			(start -0.508 0.9398)
			(end 0.508 -0.9398)
			(stroke
				(width 0)
				(type default)
			)
			(fill no)
			(layer "F.Fab")
		)
		(pad "1" smd custom
			(at 0 -0.4445)
			(size 0.1397 0.1397)
			(layers "F.Cu" "F.Mask" "F.Paste")
			(net "P3V3_STBY")
			(options
				(clearance outline)
				(anchor circle)
			)
			(primitives
				(gr_poly
					(pts
						(arc
							(start -0.1778 -0.2794)
							(mid -0.249642 -0.249642)
							(end -0.2794 -0.1778)
						)
						(arc
							(start -0.2794 0.1778)
							(mid -0.249642 0.249642)
							(end -0.1778 0.2794)
						)
						(arc
							(start 0.1778 0.2794)
							(mid 0.249642 0.249642)
							(end 0.2794 0.1778)
						)
						(arc
							(start 0.2794 -0.1778)
							(mid 0.249642 -0.249642)
							(end 0.1778 -0.2794)
						)
					)
					(width 0)
					(fill yes)
				)
			)
		)
		(pad "2" smd custom
			(at 0 0.4445)
			(size 0.1397 0.1397)
			(layers "F.Cu" "F.Mask" "F.Paste")
			(net "NCSI_TXD1")
			(options
				(clearance outline)
				(anchor circle)
			)
			(primitives
				(gr_poly
					(pts
						(arc
							(start -0.1778 -0.2794)
							(mid -0.249642 -0.249642)
							(end -0.2794 -0.1778)
						)
						(arc
							(start -0.2794 0.1778)
							(mid -0.249642 0.249642)
							(end -0.1778 0.2794)
						)
						(arc
							(start 0.1778 0.2794)
							(mid 0.249642 0.249642)
							(end 0.2794 0.1778)
						)
						(arc
							(start 0.2794 -0.1778)
							(mid 0.249642 -0.249642)
							(end 0.1778 -0.2794)
						)
					)
					(width 0)
					(fill yes)
				)
			)
		)
	)
	(footprint ""
		(layer "F.Cu")
		(at 77.4954 -167.5892)
		(property "Reference" "R539"
			(at 0 0 0)
			(layer "F.SilkS")
			(hide yes)
			(effects
				(font
					(size 1.27 1.27)
				)
			)
		)
		(property "Value" "10KR2F-2-GP"
			(at 0.064008 -3.993896 0)
			(unlocked yes)
			(layer "F.Fab")
			(hide yes)
			(effects
				(font
					(size 1.016 1.016)
					(thickness 0.1524)
				)
			)
		)
		(property "Device Type" "R402H16"
			(at 0.064008 -5.517896 0)
			(unlocked yes)
			(layer "F.Fab")
			(hide yes)
			(effects
				(font
					(size 1.016 1.016)
					(thickness 0.1524)
				)
			)
		)
		(duplicate_pad_numbers_are_jumpers no)
		(fp_line
			(start -0.508 -0.9398)
			(end -0.508 0.9398)
			(stroke
				(width 0.1524)
				(type default)
			)
			(layer "F.SilkS")
		)
		(fp_line
			(start 0.508 -0.9398)
			(end -0.508 -0.9398)
			(stroke
				(width 0.1524)
				(type default)
			)
			(layer "F.SilkS")
		)
		(fp_rect
			(start -0.508 0.9398)
			(end 0.508 -0.9398)
			(stroke
				(width 0)
				(type default)
			)
			(fill no)
			(layer "F.CrtYd")
		)
		(fp_rect
			(start -0.508 0.9398)
			(end 0.508 -0.9398)
			(stroke
				(width 0)
				(type default)
			)
			(fill no)
			(layer "F.Fab")
		)
		(pad "1" smd custom
			(at 0 -0.4445)
			(size 0.1397 0.1397)
			(layers "F.Cu" "F.Mask" "F.Paste")
			(net "P3V3_STBY")
			(options
				(clearance outline)
				(anchor circle)
			)
			(primitives
				(gr_poly
					(pts
						(arc
							(start -0.1778 -0.2794)
							(mid -0.249642 -0.249642)
							(end -0.2794 -0.1778)
						)
						(arc
							(start -0.2794 0.1778)
							(mid -0.249642 0.249642)
							(end -0.1778 0.2794)
						)
						(arc
							(start 0.1778 0.2794)
							(mid 0.249642 0.249642)
							(end 0.2794 0.1778)
						)
						(arc
							(start 0.2794 -0.1778)
							(mid 0.249642 -0.249642)
							(end 0.1778 -0.2794)
						)
					)
					(width 0)
					(fill yes)
				)
			)
		)
		(pad "2" smd custom
			(at 0 0.4445)
			(size 0.1397 0.1397)
			(layers "F.Cu" "F.Mask" "F.Paste")
			(net "P1V15_STBY_PG")
			(options
				(clearance outline)
				(anchor circle)
			)
			(primitives
				(gr_poly
					(pts
						(arc
							(start -0.1778 -0.2794)
							(mid -0.249642 -0.249642)
							(end -0.2794 -0.1778)
						)
						(arc
							(start -0.2794 0.1778)
							(mid -0.249642 0.249642)
							(end -0.1778 0.2794)
						)
						(arc
							(start 0.1778 0.2794)
							(mid 0.249642 0.249642)
							(end 0.2794 0.1778)
						)
						(arc
							(start 0.2794 -0.1778)
							(mid 0.249642 -0.249642)
							(end 0.1778 -0.2794)
						)
					)
					(width 0)
					(fill yes)
				)
			)
		)
	)
	(footprint ""
		(layer "F.Cu")
		(at 86.857586 -66.322448 90)
		(property "Reference" "R9"
			(at 0 0 90)
			(layer "F.SilkS")
			(hide yes)
			(effects
				(font
					(size 1.27 1.27)
				)
			)
		)
		(property "Value" "0R2J-2-GP"
			(at 0.064008 -3.993896 90)
			(unlocked yes)
			(layer "F.Fab")
			(hide yes)
			(effects
				(font
					(size 1.016 1.016)
					(thickness 0.1524)
				)
			)
		)
		(property "Device Type" "R402H16"
			(at 0.064008 -5.517896 90)
			(unlocked yes)
			(layer "F.Fab")
			(hide yes)
			(effects
				(font
					(size 1.016 1.016)
					(thickness 0.1524)
				)
			)
		)
		(duplicate_pad_numbers_are_jumpers no)
		(fp_line
			(start 0.508 -0.9398)
			(end -0.508 -0.9398)
			(stroke
				(width 0.1524)
				(type default)
			)
			(layer "F.SilkS")
		)
		(fp_line
			(start -0.508 -0.9398)
			(end -0.508 0.9398)
			(stroke
				(width 0.1524)
				(type default)
			)
			(layer "F.SilkS")
		)
		(fp_rect
			(start -0.508 0.9398)
			(end 0.508 -0.9398)
			(stroke
				(width 0)
				(type default)
			)
			(fill no)
			(layer "F.CrtYd")
		)
		(fp_rect
			(start -0.508 0.9398)
			(end 0.508 -0.9398)
			(stroke
				(width 0)
				(type default)
			)
			(fill no)
			(layer "F.Fab")
		)
		(pad "1" smd custom
			(at 0 -0.4445 90)
			(size 0.1397 0.1397)
			(layers "F.Cu" "F.Mask" "F.Paste")
			(net "NCSI_RX_ER_R")
			(options
				(clearance outline)
				(anchor circle)
			)
			(primitives
				(gr_poly
					(pts
						(arc
							(start -0.1778 -0.2794)
							(mid -0.249642 -0.249642)
							(end -0.2794 -0.1778)
						)
						(arc
							(start -0.2794 0.1778)
							(mid -0.249642 0.249642)
							(end -0.1778 0.2794)
						)
						(arc
							(start 0.1778 0.2794)
							(mid 0.249642 0.249642)
							(end 0.2794 0.1778)
						)
						(arc
							(start 0.2794 -0.1778)
							(mid 0.249642 -0.249642)
							(end 0.1778 -0.2794)
						)
					)
					(width 0)
					(fill yes)
				)
			)
		)
		(pad "2" smd custom
			(at 0 0.4445 90)
			(size 0.1397 0.1397)
			(layers "F.Cu" "F.Mask" "F.Paste")
			(net "NCSI_RX_ER")
			(options
				(clearance outline)
				(anchor circle)
			)
			(primitives
				(gr_poly
					(pts
						(arc
							(start -0.1778 -0.2794)
							(mid -0.249642 -0.249642)
							(end -0.2794 -0.1778)
						)
						(arc
							(start -0.2794 0.1778)
							(mid -0.249642 0.249642)
							(end -0.1778 0.2794)
						)
						(arc
							(start 0.1778 0.2794)
							(mid 0.249642 0.249642)
							(end 0.2794 0.1778)
						)
						(arc
							(start 0.2794 -0.1778)
							(mid 0.249642 -0.249642)
							(end 0.1778 -0.2794)
						)
					)
					(width 0)
					(fill yes)
				)
			)
		)
	)
	(footprint ""
		(layer "F.Cu")
		(at 182.9308 -124.714 180)
		(property "Reference" "C278"
			(at 0 0 180)
			(layer "F.SilkS")
			(hide yes)
			(effects
				(font
					(size 1.27 1.27)
				)
			)
		)
		(property "Value" "SC1U25V3KX-GP"
			(at 0 -2.8194 180)
			(unlocked yes)
			(layer "F.Fab")
			(hide yes)
			(effects
				(font
					(size 1.016 1.016)
					(thickness 0.1524)
				)
			)
		)
		(property "Device Type" "C603H36"
			(at 0 -4.3434 180)
			(unlocked yes)
			(layer "F.Fab")
			(hide yes)
			(effects
				(font
					(size 1.016 1.016)
					(thickness 0.1524)
				)
			)
		)
		(duplicate_pad_numbers_are_jumpers no)
		(fp_line
			(start 0.508 0)
			(end -0.508 0)
			(stroke
				(width 0.2032)
				(type default)
			)
			(layer "F.SilkS")
		)
		(fp_rect
			(start -0.5842 1.3335)
			(end 0.5842 -1.3335)
			(stroke
				(width 0)
				(type default)
			)
			(fill no)
			(layer "F.CrtYd")
		)
		(fp_rect
			(start -0.5842 1.3335)
			(end 0.5842 -1.3335)
			(stroke
				(width 0)
				(type default)
			)
			(fill no)
			(layer "F.Fab")
		)
		(pad "1" smd custom
			(at 0 -0.762 180)
			(size 0.2159 0.2159)
			(layers "F.Cu" "F.Mask" "F.Paste")
			(net "VT235_AVDD")
			(options
				(clearance outline)
				(anchor circle)
			)
			(primitives
				(gr_poly
					(pts
						(arc
							(start -0.3302 -0.4318)
							(mid -0.402042 -0.402042)
							(end -0.4318 -0.3302)
						)
						(arc
							(start -0.4318 0.3302)
							(mid -0.402042 0.402042)
							(end -0.3302 0.4318)
						)
						(arc
							(start 0.3302 0.4318)
							(mid 0.402042 0.402042)
							(end 0.4318 0.3302)
						)
						(arc
							(start 0.4318 -0.3302)
							(mid 0.402042 -0.402042)
							(end 0.3302 -0.4318)
						)
					)
					(width 0)
					(fill yes)
				)
			)
		)
		(pad "2" smd custom
			(at 0 0.762 180)
			(size 0.2159 0.2159)
			(layers "F.Cu" "F.Mask" "F.Paste")
			(net "AGND_P0V975")
			(options
				(clearance outline)
				(anchor circle)
			)
			(primitives
				(gr_poly
					(pts
						(arc
							(start -0.3302 -0.4318)
							(mid -0.402042 -0.402042)
							(end -0.4318 -0.3302)
						)
						(arc
							(start -0.4318 0.3302)
							(mid -0.402042 0.402042)
							(end -0.3302 0.4318)
						)
						(arc
							(start 0.3302 0.4318)
							(mid 0.402042 0.402042)
							(end 0.4318 0.3302)
						)
						(arc
							(start 0.4318 -0.3302)
							(mid 0.402042 -0.402042)
							(end 0.3302 -0.4318)
						)
					)
					(width 0)
					(fill yes)
				)
			)
		)
	)
	(footprint ""
		(layer "F.Cu")
		(at 118.872 -8.9916 90)
		(property "Reference" "U35"
			(at 0 0 90)
			(layer "F.SilkS")
			(hide yes)
			(effects
				(font
					(size 1.27 1.27)
				)
			)
		)
		(property "Value" "ADM1278-2ACPZ-RL-1-GP"
			(at -4.7625 -7.4422 90)
			(unlocked yes)
			(layer "F.Fab")
			(hide yes)
			(effects
				(font
					(size 1.016 1.016)
					(thickness 0.1524)
				)
			)
		)
		(property "Device Type" "QFN32-G3D45-UH32"
			(at -4.7625 -8.9662 90)
			(unlocked yes)
			(layer "F.Fab")
			(hide yes)
			(effects
				(font
					(size 1.016 1.016)
					(thickness 0.1524)
				)
			)
		)
		(duplicate_pad_numbers_are_jumpers no)
		(fp_line
			(start -0.250698 -3.7973)
			(end -0.250698 -3.2893)
			(stroke
				(width 0.1524)
				(type default)
			)
			(layer "F.SilkS")
		)
		(fp_line
			(start -3.5179 -3.5179)
			(end -2.2479 -3.5179)
			(stroke
				(width 0.1524)
				(type default)
			)
			(layer "F.SilkS")
		)
		(fp_line
			(start -3.5179 -2.2479)
			(end -3.5179 -3.5179)
			(stroke
				(width 0.1524)
				(type default)
			)
			(layer "F.SilkS")
		)
		(fp_line
			(start -4.0513 -1.24968)
			(end -3.2893 -1.24968)
			(stroke
				(width 0.1524)
				(type default)
			)
			(layer "F.SilkS")
		)
		(fp_line
			(start 4.0513 -0.749808)
			(end 3.2893 -0.749808)
			(stroke
				(width 0.1524)
				(type default)
			)
			(layer "F.SilkS")
		)
		(fp_line
			(start -3.7973 1.24968)
			(end -3.2893 1.24968)
			(stroke
				(width 0.1524)
				(type default)
			)
			(layer "F.SilkS")
		)
		(fp_line
			(start 3.7973 1.749552)
			(end 3.2893 1.749552)
			(stroke
				(width 0.1524)
				(type default)
			)
			(layer "F.SilkS")
		)
		(fp_line
			(start 3.5179 2.2479)
			(end 3.5179 3.5179)
			(stroke
				(width 0.1524)
				(type default)
			)
			(layer "F.SilkS")
		)
		(fp_line
			(start -3.5179 2.2479)
			(end -3.5179 3.5179)
			(stroke
				(width 0.1524)
				(type default)
			)
			(layer "F.SilkS")
		)
		(fp_line
			(start 3.5179 3.5179)
			(end 2.2479 3.5179)
			(stroke
				(width 0.1524)
				(type default)
			)
			(layer "F.SilkS")
		)
		(fp_line
			(start -3.5179 3.5179)
			(end -2.2479 3.5179)
			(stroke
				(width 0.1524)
				(type default)
			)
			(layer "F.SilkS")
		)
		(fp_line
			(start -0.250698 4.0513)
			(end -0.250698 3.2893)
			(stroke
				(width 0.1524)
				(type default)
			)
			(layer "F.SilkS")
		)
		(fp_poly
			(pts
				(xy 2.2479 -3.5179) (xy 3.5179 -2.2479) (xy 3.5179 -3.5179)
			)
			(stroke
				(width 0)
				(type default)
			)
			(fill yes)
			(layer "F.SilkS")
		)
		(fp_rect
			(start -2.5019 2.5019)
			(end 2.5019 -2.5019)
			(stroke
				(width 0)
				(type default)
			)
			(fill no)
			(layer "F.CrtYd")
		)
		(fp_poly
			(pts
				(xy -3.5179 3.5179) (xy -3.5179 -3.5179) (xy 3.5179 -3.5179) (xy 3.5179 3.5179) (xy -2.49682 3.5179)
				(xy -2.49682 2.5019) (xy 2.5019 2.5019) (xy 2.5019 -2.5019) (xy -2.5019 -2.5019) (xy -2.5019 3.5179)
			)
			(stroke
				(width 0)
				(type default)
			)
			(fill no)
			(layer "F.CrtYd")
		)
		(fp_rect
			(start -3.5179 3.5179)
			(end 3.5179 -3.5179)
			(stroke
				(width 0)
				(type default)
			)
			(fill no)
			(layer "F.Fab")
		)
		(pad "1" smd rect
			(at 1.75006 -2.5527 90)
			(size 0.3048 0.9144)
			(layers "F.Cu" "F.Mask" "F.Paste")
			(net "MB0_PSET_R")
		)
		(pad "2" smd rect
			(at 1.249934 -2.4765 90)
			(size 0.3048 1.0668)
			(layers "F.Cu" "F.Mask" "F.Paste")
			(net "MB0_VCAP_R")
		)
		(pad "3" smd rect
			(at 0.750062 -2.4765 90)
			(size 0.3048 1.0668)
			(layers "F.Cu" "F.Mask" "F.Paste")
			(net "MB0_ISET_R")
		)
		(pad "4" smd rect
			(at 0.249936 -2.4765 90)
			(size 0.3048 1.0668)
			(layers "F.Cu" "F.Mask" "F.Paste")
			(net "MB0_ISTART_R")
		)
		(pad "5" smd rect
			(at -0.249936 -2.4765 90)
			(size 0.3048 1.0668)
			(layers "F.Cu" "F.Mask" "F.Paste")
			(net "MB0_TIME_R")
		)
		(pad "6" smd rect
			(at -0.750062 -2.4765 90)
			(size 0.3048 1.0668)
			(layers "F.Cu" "F.Mask" "F.Paste")
			(net "Net_320")
		)
		(pad "7" smd rect
			(at -1.249934 -2.4765 90)
			(size 0.3048 1.0668)
			(layers "F.Cu" "F.Mask" "F.Paste")
			(net "MB0_CM_ADR1_R")
		)
		(pad "8" smd rect
			(at -1.75006 -2.5527 90)
			(size 0.3048 0.9144)
			(layers "F.Cu" "F.Mask" "F.Paste")
			(net "MB0_CM_ADR2_R")
		)
		(pad "9" smd rect
			(at -2.5527 -1.75006 90)
			(size 0.9144 0.3048)
			(layers "F.Cu" "F.Mask" "F.Paste")
			(net "MB0_SPISS_PD")
		)
		(pad "10" smd rect
			(at -2.4765 -1.249934 90)
			(size 1.0668 0.3048)
			(layers "F.Cu" "F.Mask" "F.Paste")
			(net "Net_324")
		)
		(pad "11" smd rect
			(at -2.4765 -0.750062 90)
			(size 1.0668 0.3048)
			(layers "F.Cu" "F.Mask" "F.Paste")
			(net "Net_323")
		)
		(pad "12" smd rect
			(at -2.4765 -0.249936 90)
			(size 1.0668 0.3048)
			(layers "F.Cu" "F.Mask" "F.Paste")
			(net "MB0_HS_ENABLE")
		)
		(pad "13" smd rect
			(at -2.4765 0.249936 90)
			(size 1.0668 0.3048)
			(layers "F.Cu" "F.Mask" "F.Paste")
			(net "Net_322")
		)
		(pad "14" smd rect
			(at -2.4765 0.750062 90)
			(size 1.0668 0.3048)
			(layers "F.Cu" "F.Mask" "F.Paste")
			(net "Net_321")
		)
		(pad "15" smd rect
			(at -2.4765 1.249934 90)
			(size 1.0668 0.3048)
			(layers "F.Cu" "F.Mask" "F.Paste")
			(net "HSW_SDA")
		)
		(pad "16" smd rect
			(at -2.5527 1.75006 90)
			(size 0.9144 0.3048)
			(layers "F.Cu" "F.Mask" "F.Paste")
			(net "HSW_SCL")
		)
		(pad "17" smd rect
			(at -1.75006 2.5527 90)
			(size 0.3048 0.9144)
			(layers "F.Cu" "F.Mask" "F.Paste")
			(net "MB0_RETRY_R")
		)
		(pad "18" smd rect
			(at -1.249934 2.4765 90)
			(size 0.3048 1.0668)
			(layers "F.Cu" "F.Mask" "F.Paste")
			(net "P12V_IOM_PGOOD")
		)
		(pad "19" smd rect
			(at -0.750062 2.4765 90)
			(size 0.3048 1.0668)
			(layers "F.Cu" "F.Mask" "F.Paste")
			(net "Net_325")
		)
		(pad "20" smd rect
			(at -0.249936 2.4765 90)
			(size 0.3048 1.0668)
			(layers "F.Cu" "F.Mask" "F.Paste")
			(net "MB0_CM_VOUT_R")
		)
		(pad "21" smd rect
			(at 0.249936 2.4765 90)
			(size 0.3048 1.0668)
			(layers "F.Cu" "F.Mask" "F.Paste")
			(net "MB0_P12V_PWGIN_R")
		)
		(pad "22" smd rect
			(at 0.750062 2.4765 90)
			(size 0.3048 1.0668)
			(layers "F.Cu" "F.Mask" "F.Paste")
			(net "AGND_CURRENT_MON")
		)
		(pad "23" smd rect
			(at 1.249934 2.4765 90)
			(size 0.3048 1.0668)
			(layers "F.Cu" "F.Mask" "F.Paste")
			(net "GND")
		)
		(pad "24" smd rect
			(at 1.75006 2.5527 90)
			(size 0.3048 0.9144)
			(layers "F.Cu" "F.Mask" "F.Paste")
			(net "MB0_CM_GATE")
		)
		(pad "25" smd rect
			(at 2.5527 1.75006 90)
			(size 0.9144 0.3048)
			(layers "F.Cu" "F.Mask" "F.Paste")
			(net "MB0_TEMP")
		)
		(pad "26" smd rect
			(at 2.4765 1.249934 90)
			(size 1.0668 0.3048)
			(layers "F.Cu" "F.Mask" "F.Paste")
			(net "MB0_CM_SENSE_N")
		)
		(pad "27" smd rect
			(at 2.4765 0.750062 90)
			(size 1.0668 0.3048)
			(layers "F.Cu" "F.Mask" "F.Paste")
			(net "ADM1278_HS_N")
		)
		(pad "28" smd rect
			(at 2.4765 0.249936 90)
			(size 1.0668 0.3048)
			(layers "F.Cu" "F.Mask" "F.Paste")
			(net "ADM1278_HS_P")
		)
		(pad "29" smd rect
			(at 2.4765 -0.249936 90)
			(size 1.0668 0.3048)
			(layers "F.Cu" "F.Mask" "F.Paste")
			(net "MB0_CM_SENSE_P")
		)
		(pad "30" smd rect
			(at 2.4765 -0.750062 90)
			(size 1.0668 0.3048)
			(layers "F.Cu" "F.Mask" "F.Paste")
			(net "MB0_VCC")
		)
		(pad "31" smd rect
			(at 2.4765 -1.249934 90)
			(size 1.0668 0.3048)
			(layers "F.Cu" "F.Mask" "F.Paste")
			(net "MB0_CM_UV_R")
		)
		(pad "32" smd rect
			(at 2.5527 -1.75006 90)
			(size 0.9144 0.3048)
			(layers "F.Cu" "F.Mask" "F.Paste")
			(net "MB0_CM_OV_R")
		)
		(pad "33" smd rect
			(at 0 0 90)
			(size 3.4544 3.4544)
			(layers "F.Cu" "F.Mask" "F.Paste")
			(net "AGND_CURRENT_MON")
		)
	)
	(footprint ""
		(layer "F.Cu")
		(at 12.6746 -170.988736)
		(property "Reference" "C233"
			(at 0 0 0)
			(layer "F.SilkS")
			(hide yes)
			(effects
				(font
					(size 1.27 1.27)
				)
			)
		)
		(property "Value" "SCD1U16V2KX-3GP"
			(at 1.1811 -2.7051 0)
			(unlocked yes)
			(layer "F.Fab")
			(hide yes)
			(effects
				(font
					(size 1.016 1.016)
					(thickness 0.1524)
				)
			)
		)
		(property "Device Type" "C402H22"
			(at 1.1811 -4.2291 0)
			(unlocked yes)
			(layer "F.Fab")
			(hide yes)
			(effects
				(font
					(size 1.016 1.016)
					(thickness 0.1524)
				)
			)
		)
		(duplicate_pad_numbers_are_jumpers no)
		(fp_rect
			(start -0.4318 0.9525)
			(end 0.4318 -0.9525)
			(stroke
				(width 0)
				(type default)
			)
			(fill no)
			(layer "F.CrtYd")
		)
		(fp_rect
			(start -0.4318 0.9525)
			(end 0.4318 -0.9525)
			(stroke
				(width 0)
				(type default)
			)
			(fill no)
			(layer "F.Fab")
		)
		(pad "1" smd custom
			(at 0 -0.4445)
			(size 0.1524 0.1524)
			(layers "F.Cu" "F.Mask" "F.Paste")
			(net "TPS74801_P1V2_STBY_EN")
			(options
				(clearance outline)
				(anchor circle)
			)
			(primitives
				(gr_poly
					(pts
						(arc
							(start 0.3048 -0.2032)
							(mid 0.275042 -0.275042)
							(end 0.2032 -0.3048)
						)
						(arc
							(start -0.2032 -0.3048)
							(mid -0.275042 -0.275042)
							(end -0.3048 -0.2032)
						)
						(arc
							(start -0.3048 0.2032)
							(mid -0.275042 0.275042)
							(end -0.2032 0.3048)
						)
						(arc
							(start 0.2032 0.3048)
							(mid 0.275042 0.275042)
							(end 0.3048 0.2032)
						)
					)
					(width 0)
					(fill yes)
				)
			)
		)
		(pad "2" smd custom
			(at 0 0.4445)
			(size 0.1524 0.1524)
			(layers "F.Cu" "F.Mask" "F.Paste")
			(net "GND")
			(options
				(clearance outline)
				(anchor circle)
			)
			(primitives
				(gr_poly
					(pts
						(arc
							(start 0.3048 -0.2032)
							(mid 0.275042 -0.275042)
							(end 0.2032 -0.3048)
						)
						(arc
							(start -0.2032 -0.3048)
							(mid -0.275042 -0.275042)
							(end -0.3048 -0.2032)
						)
						(arc
							(start -0.3048 0.2032)
							(mid -0.275042 0.275042)
							(end -0.2032 0.3048)
						)
						(arc
							(start 0.2032 0.3048)
							(mid 0.275042 0.275042)
							(end 0.3048 0.2032)
						)
					)
					(width 0)
					(fill yes)
				)
			)
		)
	)
	(footprint ""
		(layer "F.Cu")
		(at 88.9 -134.7978)
		(property "Reference" "R137"
			(at 0 0 0)
			(layer "F.SilkS")
			(hide yes)
			(effects
				(font
					(size 1.27 1.27)
				)
			)
		)
		(property "Value" "8K2R2J-3-GP"
			(at 0.064008 -3.993896 0)
			(unlocked yes)
			(layer "F.Fab")
			(hide yes)
			(effects
				(font
					(size 1.016 1.016)
					(thickness 0.1524)
				)
			)
		)
		(property "Device Type" "R402H16"
			(at 0.064008 -5.517896 0)
			(unlocked yes)
			(layer "F.Fab")
			(hide yes)
			(effects
				(font
					(size 1.016 1.016)
					(thickness 0.1524)
				)
			)
		)
		(duplicate_pad_numbers_are_jumpers no)
		(fp_line
			(start -0.508 -0.9398)
			(end -0.508 0.9398)
			(stroke
				(width 0.1524)
				(type default)
			)
			(layer "F.SilkS")
		)
		(fp_line
			(start 0.508 -0.9398)
			(end -0.508 -0.9398)
			(stroke
				(width 0.1524)
				(type default)
			)
			(layer "F.SilkS")
		)
		(fp_rect
			(start -0.508 0.9398)
			(end 0.508 -0.9398)
			(stroke
				(width 0)
				(type default)
			)
			(fill no)
			(layer "F.CrtYd")
		)
		(fp_rect
			(start -0.508 0.9398)
			(end 0.508 -0.9398)
			(stroke
				(width 0)
				(type default)
			)
			(fill no)
			(layer "F.Fab")
		)
		(pad "1" smd custom
			(at 0 -0.4445)
			(size 0.1397 0.1397)
			(layers "F.Cu" "F.Mask" "F.Paste")
			(net "EEPROM_A1")
			(options
				(clearance outline)
				(anchor circle)
			)
			(primitives
				(gr_poly
					(pts
						(arc
							(start -0.1778 -0.2794)
							(mid -0.249642 -0.249642)
							(end -0.2794 -0.1778)
						)
						(arc
							(start -0.2794 0.1778)
							(mid -0.249642 0.249642)
							(end -0.1778 0.2794)
						)
						(arc
							(start 0.1778 0.2794)
							(mid 0.249642 0.249642)
							(end 0.2794 0.1778)
						)
						(arc
							(start 0.2794 -0.1778)
							(mid 0.249642 -0.249642)
							(end 0.1778 -0.2794)
						)
					)
					(width 0)
					(fill yes)
				)
			)
		)
		(pad "2" smd custom
			(at 0 0.4445)
			(size 0.1397 0.1397)
			(layers "F.Cu" "F.Mask" "F.Paste")
			(net "GND")
			(options
				(clearance outline)
				(anchor circle)
			)
			(primitives
				(gr_poly
					(pts
						(arc
							(start -0.1778 -0.2794)
							(mid -0.249642 -0.249642)
							(end -0.2794 -0.1778)
						)
						(arc
							(start -0.2794 0.1778)
							(mid -0.249642 0.249642)
							(end -0.1778 0.2794)
						)
						(arc
							(start 0.1778 0.2794)
							(mid 0.249642 0.249642)
							(end 0.2794 0.1778)
						)
						(arc
							(start 0.2794 -0.1778)
							(mid 0.249642 -0.249642)
							(end 0.1778 -0.2794)
						)
					)
					(width 0)
					(fill yes)
				)
			)
		)
	)
	(footprint ""
		(layer "F.Cu")
		(at 200.8124 -48.2854 180)
		(property "Reference" "R634"
			(at 0 0 180)
			(layer "F.SilkS")
			(hide yes)
			(effects
				(font
					(size 1.27 1.27)
				)
			)
		)
		(property "Value" "4K7R2F-GP"
			(at 0.064008 -3.993896 180)
			(unlocked yes)
			(layer "F.Fab")
			(hide yes)
			(effects
				(font
					(size 1.016 1.016)
					(thickness 0.1524)
				)
			)
		)
		(property "Device Type" "R402H16"
			(at 0.064008 -5.517896 180)
			(unlocked yes)
			(layer "F.Fab")
			(hide yes)
			(effects
				(font
					(size 1.016 1.016)
					(thickness 0.1524)
				)
			)
		)
		(duplicate_pad_numbers_are_jumpers no)
		(fp_line
			(start 0.508 -0.9398)
			(end -0.508 -0.9398)
			(stroke
				(width 0.1524)
				(type default)
			)
			(layer "F.SilkS")
		)
		(fp_line
			(start -0.508 -0.9398)
			(end -0.508 0.9398)
			(stroke
				(width 0.1524)
				(type default)
			)
			(layer "F.SilkS")
		)
		(fp_rect
			(start -0.508 0.9398)
			(end 0.508 -0.9398)
			(stroke
				(width 0)
				(type default)
			)
			(fill no)
			(layer "F.CrtYd")
		)
		(fp_rect
			(start -0.508 0.9398)
			(end 0.508 -0.9398)
			(stroke
				(width 0)
				(type default)
			)
			(fill no)
			(layer "F.Fab")
		)
		(pad "1" smd custom
			(at 0 -0.4445 180)
			(size 0.1397 0.1397)
			(layers "F.Cu" "F.Mask" "F.Paste")
			(net "P1V8")
			(options
				(clearance outline)
				(anchor circle)
			)
			(primitives
				(gr_poly
					(pts
						(arc
							(start -0.1778 -0.2794)
							(mid -0.249642 -0.249642)
							(end -0.2794 -0.1778)
						)
						(arc
							(start -0.2794 0.1778)
							(mid -0.249642 0.249642)
							(end -0.1778 0.2794)
						)
						(arc
							(start 0.1778 0.2794)
							(mid 0.249642 0.249642)
							(end 0.2794 0.1778)
						)
						(arc
							(start 0.2794 -0.1778)
							(mid 0.249642 -0.249642)
							(end 0.1778 -0.2794)
						)
					)
					(width 0)
					(fill yes)
				)
			)
		)
		(pad "2" smd custom
			(at 0 0.4445 180)
			(size 0.1397 0.1397)
			(layers "F.Cu" "F.Mask" "F.Paste")
			(net "ICE0_TDI")
			(options
				(clearance outline)
				(anchor circle)
			)
			(primitives
				(gr_poly
					(pts
						(arc
							(start -0.1778 -0.2794)
							(mid -0.249642 -0.249642)
							(end -0.2794 -0.1778)
						)
						(arc
							(start -0.2794 0.1778)
							(mid -0.249642 0.249642)
							(end -0.1778 0.2794)
						)
						(arc
							(start 0.1778 0.2794)
							(mid 0.249642 0.249642)
							(end 0.2794 0.1778)
						)
						(arc
							(start 0.2794 -0.1778)
							(mid 0.249642 -0.249642)
							(end 0.1778 -0.2794)
						)
					)
					(width 0)
					(fill yes)
				)
			)
		)
	)
	(footprint ""
		(layer "F.Cu")
		(at 179.832 -115.443)
		(property "Reference" "C288"
			(at 0 0 0)
			(layer "F.SilkS")
			(hide yes)
			(effects
				(font
					(size 1.27 1.27)
				)
			)
		)
		(property "Value" "SCD1U50V3KX-GP"
			(at 0 -2.8194 0)
			(unlocked yes)
			(layer "F.Fab")
			(hide yes)
			(effects
				(font
					(size 1.016 1.016)
					(thickness 0.1524)
				)
			)
		)
		(property "Device Type" "C603H36"
			(at 0 -4.3434 0)
			(unlocked yes)
			(layer "F.Fab")
			(hide yes)
			(effects
				(font
					(size 1.016 1.016)
					(thickness 0.1524)
				)
			)
		)
		(duplicate_pad_numbers_are_jumpers no)
		(fp_line
			(start 0.508 0)
			(end -0.508 0)
			(stroke
				(width 0.2032)
				(type default)
			)
			(layer "F.SilkS")
		)
		(fp_rect
			(start -0.5842 1.3335)
			(end 0.5842 -1.3335)
			(stroke
				(width 0)
				(type default)
			)
			(fill no)
			(layer "F.CrtYd")
		)
		(fp_rect
			(start -0.5842 1.3335)
			(end 0.5842 -1.3335)
			(stroke
				(width 0)
				(type default)
			)
			(fill no)
			(layer "F.Fab")
		)
		(pad "1" smd custom
			(at 0 -0.762)
			(size 0.2159 0.2159)
			(layers "F.Cu" "F.Mask" "F.Paste")
			(net "P3V3_STBY")
			(options
				(clearance outline)
				(anchor circle)
			)
			(primitives
				(gr_poly
					(pts
						(arc
							(start -0.3302 -0.4318)
							(mid -0.402042 -0.402042)
							(end -0.4318 -0.3302)
						)
						(arc
							(start -0.4318 0.3302)
							(mid -0.402042 0.402042)
							(end -0.3302 0.4318)
						)
						(arc
							(start 0.3302 0.4318)
							(mid 0.402042 0.402042)
							(end 0.4318 0.3302)
						)
						(arc
							(start 0.4318 -0.3302)
							(mid 0.402042 -0.402042)
							(end 0.3302 -0.4318)
						)
					)
					(width 0)
					(fill yes)
				)
			)
		)
		(pad "2" smd custom
			(at 0 0.762)
			(size 0.2159 0.2159)
			(layers "F.Cu" "F.Mask" "F.Paste")
			(net "GND")
			(options
				(clearance outline)
				(anchor circle)
			)
			(primitives
				(gr_poly
					(pts
						(arc
							(start -0.3302 -0.4318)
							(mid -0.402042 -0.402042)
							(end -0.4318 -0.3302)
						)
						(arc
							(start -0.4318 0.3302)
							(mid -0.402042 0.402042)
							(end -0.3302 0.4318)
						)
						(arc
							(start 0.3302 0.4318)
							(mid 0.402042 0.402042)
							(end 0.4318 0.3302)
						)
						(arc
							(start 0.4318 -0.3302)
							(mid 0.402042 -0.402042)
							(end 0.3302 -0.4318)
						)
					)
					(width 0)
					(fill yes)
				)
			)
		)
	)
	(footprint ""
		(layer "F.Cu")
		(at 201.698352 -129.644648 180)
		(property "Reference" "C257"
			(at 0 0 180)
			(layer "F.SilkS")
			(hide yes)
			(effects
				(font
					(size 1.27 1.27)
				)
			)
		)
		(property "Value" "SCD1U16V2KX-3GP"
			(at 1.1811 -2.7051 180)
			(unlocked yes)
			(layer "F.Fab")
			(hide yes)
			(effects
				(font
					(size 1.016 1.016)
					(thickness 0.1524)
				)
			)
		)
		(property "Device Type" "C402H22"
			(at 1.1811 -4.2291 180)
			(unlocked yes)
			(layer "F.Fab")
			(hide yes)
			(effects
				(font
					(size 1.016 1.016)
					(thickness 0.1524)
				)
			)
		)
		(duplicate_pad_numbers_are_jumpers no)
		(fp_rect
			(start -0.4318 0.9525)
			(end 0.4318 -0.9525)
			(stroke
				(width 0)
				(type default)
			)
			(fill no)
			(layer "F.CrtYd")
		)
		(fp_rect
			(start -0.4318 0.9525)
			(end 0.4318 -0.9525)
			(stroke
				(width 0)
				(type default)
			)
			(fill no)
			(layer "F.Fab")
		)
		(pad "1" smd custom
			(at 0 -0.4445 180)
			(size 0.1524 0.1524)
			(layers "F.Cu" "F.Mask" "F.Paste")
			(net "TPS74801_1V5_EN")
			(options
				(clearance outline)
				(anchor circle)
			)
			(primitives
				(gr_poly
					(pts
						(arc
							(start 0.3048 -0.2032)
							(mid 0.275042 -0.275042)
							(end 0.2032 -0.3048)
						)
						(arc
							(start -0.2032 -0.3048)
							(mid -0.275042 -0.275042)
							(end -0.3048 -0.2032)
						)
						(arc
							(start -0.3048 0.2032)
							(mid -0.275042 0.275042)
							(end -0.2032 0.3048)
						)
						(arc
							(start 0.2032 0.3048)
							(mid 0.275042 0.275042)
							(end 0.3048 0.2032)
						)
					)
					(width 0)
					(fill yes)
				)
			)
		)
		(pad "2" smd custom
			(at 0 0.4445 180)
			(size 0.1524 0.1524)
			(layers "F.Cu" "F.Mask" "F.Paste")
			(net "GND")
			(options
				(clearance outline)
				(anchor circle)
			)
			(primitives
				(gr_poly
					(pts
						(arc
							(start 0.3048 -0.2032)
							(mid 0.275042 -0.275042)
							(end 0.2032 -0.3048)
						)
						(arc
							(start -0.2032 -0.3048)
							(mid -0.275042 -0.275042)
							(end -0.3048 -0.2032)
						)
						(arc
							(start -0.3048 0.2032)
							(mid -0.275042 0.275042)
							(end -0.2032 0.3048)
						)
						(arc
							(start 0.2032 0.3048)
							(mid 0.275042 0.275042)
							(end 0.3048 0.2032)
						)
					)
					(width 0)
					(fill yes)
				)
			)
		)
	)
	(footprint ""
		(layer "F.Cu")
		(at 119.384064 -13.65123 90)
		(property "Reference" "C133"
			(at 0 0 90)
			(layer "F.SilkS")
			(hide yes)
			(effects
				(font
					(size 1.27 1.27)
				)
			)
		)
		(property "Value" "SCD015U25V2KX-GP"
			(at 1.1811 -2.7051 90)
			(unlocked yes)
			(layer "F.Fab")
			(hide yes)
			(effects
				(font
					(size 1.016 1.016)
					(thickness 0.1524)
				)
			)
		)
		(property "Device Type" "C402H22"
			(at 1.1811 -4.2291 90)
			(unlocked yes)
			(layer "F.Fab")
			(hide yes)
			(effects
				(font
					(size 1.016 1.016)
					(thickness 0.1524)
				)
			)
		)
		(duplicate_pad_numbers_are_jumpers no)
		(fp_rect
			(start -0.4318 0.9525)
			(end 0.4318 -0.9525)
			(stroke
				(width 0)
				(type default)
			)
			(fill no)
			(layer "F.CrtYd")
		)
		(fp_rect
			(start -0.4318 0.9525)
			(end 0.4318 -0.9525)
			(stroke
				(width 0)
				(type default)
			)
			(fill no)
			(layer "F.Fab")
		)
		(pad "1" smd custom
			(at 0 -0.4445 90)
			(size 0.1524 0.1524)
			(layers "F.Cu" "F.Mask" "F.Paste")
			(net "MB0_CM_SENSE_P")
			(options
				(clearance outline)
				(anchor circle)
			)
			(primitives
				(gr_poly
					(pts
						(arc
							(start 0.3048 -0.2032)
							(mid 0.275042 -0.275042)
							(end 0.2032 -0.3048)
						)
						(arc
							(start -0.2032 -0.3048)
							(mid -0.275042 -0.275042)
							(end -0.3048 -0.2032)
						)
						(arc
							(start -0.3048 0.2032)
							(mid -0.275042 0.275042)
							(end -0.2032 0.3048)
						)
						(arc
							(start 0.2032 0.3048)
							(mid 0.275042 0.275042)
							(end 0.3048 0.2032)
						)
					)
					(width 0)
					(fill yes)
				)
			)
		)
		(pad "2" smd custom
			(at 0 0.4445 90)
			(size 0.1524 0.1524)
			(layers "F.Cu" "F.Mask" "F.Paste")
			(net "MB0_CM_SENSE_N")
			(options
				(clearance outline)
				(anchor circle)
			)
			(primitives
				(gr_poly
					(pts
						(arc
							(start 0.3048 -0.2032)
							(mid 0.275042 -0.275042)
							(end 0.2032 -0.3048)
						)
						(arc
							(start -0.2032 -0.3048)
							(mid -0.275042 -0.275042)
							(end -0.3048 -0.2032)
						)
						(arc
							(start -0.3048 0.2032)
							(mid -0.275042 0.275042)
							(end -0.2032 0.3048)
						)
						(arc
							(start 0.2032 0.3048)
							(mid 0.275042 0.275042)
							(end 0.3048 0.2032)
						)
					)
					(width 0)
					(fill yes)
				)
			)
		)
	)
	(footprint ""
		(layer "F.Cu")
		(at 23.777956 -128.105408 180)
		(property "Reference" "LED6"
			(at 0 0 180)
			(layer "F.SilkS")
			(hide yes)
			(effects
				(font
					(size 1.27 1.27)
				)
			)
		)
		(property "Value" "LED-YG-51-GP"
			(at -2.6924 -1.4224 180)
			(unlocked yes)
			(layer "F.Fab")
			(hide yes)
			(effects
				(font
					(size 1.016 1.016)
					(thickness 0.1524)
				)
			)
		)
		(property "Device Type" "LED1608AKH40"
			(at -2.6924 -2.9464 180)
			(unlocked yes)
			(layer "F.Fab")
			(hide yes)
			(effects
				(font
					(size 1.016 1.016)
					(thickness 0.1524)
				)
			)
		)
		(duplicate_pad_numbers_are_jumpers no)
		(fp_line
			(start 0.7493 1.651)
			(end 0.7493 1.1811)
			(stroke
				(width 0.3302)
				(type default)
			)
			(layer "F.SilkS")
		)
		(fp_line
			(start 0.6604 1.3716)
			(end -0.6604 1.3716)
			(stroke
				(width 0.1524)
				(type default)
			)
			(layer "F.SilkS")
		)
		(fp_line
			(start 0.6604 -1.3716)
			(end 0.6604 1.3716)
			(stroke
				(width 0.1524)
				(type default)
			)
			(layer "F.SilkS")
		)
		(fp_line
			(start -0.5969 1.5494)
			(end 0.5842 1.5494)
			(stroke
				(width 0.508)
				(type default)
			)
			(layer "F.SilkS")
		)
		(fp_line
			(start -0.6604 1.3716)
			(end -0.6604 -1.3716)
			(stroke
				(width 0.1524)
				(type default)
			)
			(layer "F.SilkS")
		)
		(fp_line
			(start -0.6604 -1.3716)
			(end 0.6604 -1.3716)
			(stroke
				(width 0.1524)
				(type default)
			)
			(layer "F.SilkS")
		)
		(fp_line
			(start -0.7493 1.651)
			(end -0.7493 1.1811)
			(stroke
				(width 0.3302)
				(type default)
			)
			(layer "F.SilkS")
		)
		(fp_rect
			(start -0.6223 1.3335)
			(end 0.6223 -1.3335)
			(stroke
				(width 0)
				(type default)
			)
			(fill no)
			(layer "F.CrtYd")
		)
		(fp_rect
			(start -0.6223 1.3335)
			(end 0.6223 -1.3335)
			(stroke
				(width 0)
				(type default)
			)
			(fill no)
			(layer "F.Fab")
		)
		(pad "A" smd custom
			(at 0 -0.762 180)
			(size 0.2159 0.2159)
			(layers "F.Cu" "F.Mask" "F.Paste")
			(net "BMC_HBLED_R")
			(options
				(clearance outline)
				(anchor circle)
			)
			(primitives
				(gr_poly
					(pts
						(arc
							(start -0.3302 -0.4318)
							(mid -0.402042 -0.402042)
							(end -0.4318 -0.3302)
						)
						(arc
							(start -0.4318 0.3302)
							(mid -0.402042 0.402042)
							(end -0.3302 0.4318)
						)
						(arc
							(start 0.3302 0.4318)
							(mid 0.402042 0.402042)
							(end 0.4318 0.3302)
						)
						(arc
							(start 0.4318 -0.3302)
							(mid 0.402042 -0.402042)
							(end 0.3302 -0.4318)
						)
					)
					(width 0)
					(fill yes)
				)
			)
		)
		(pad "K" smd custom
			(at 0 0.762 180)
			(size 0.2159 0.2159)
			(layers "F.Cu" "F.Mask" "F.Paste")
			(net "BMC_HBLED")
			(options
				(clearance outline)
				(anchor circle)
			)
			(primitives
				(gr_poly
					(pts
						(arc
							(start -0.3302 -0.4318)
							(mid -0.402042 -0.402042)
							(end -0.4318 -0.3302)
						)
						(arc
							(start -0.4318 0.3302)
							(mid -0.402042 0.402042)
							(end -0.3302 0.4318)
						)
						(arc
							(start 0.3302 0.4318)
							(mid 0.402042 0.402042)
							(end 0.4318 0.3302)
						)
						(arc
							(start 0.4318 -0.3302)
							(mid 0.402042 -0.402042)
							(end 0.3302 -0.4318)
						)
					)
					(width 0)
					(fill yes)
				)
			)
		)
	)
	(footprint ""
		(layer "F.Cu")
		(at 160.533588 -96.416114 -90)
		(property "Reference" "R597"
			(at 0 0 270)
			(layer "F.SilkS")
			(hide yes)
			(effects
				(font
					(size 1.27 1.27)
				)
			)
		)
		(property "Value" "0R2J-2-GP"
			(at 0.064008 -3.993896 270)
			(unlocked yes)
			(layer "F.Fab")
			(hide yes)
			(effects
				(font
					(size 1.016 1.016)
					(thickness 0.1524)
				)
			)
		)
		(property "Device Type" "R402H16"
			(at 0.064008 -5.517896 270)
			(unlocked yes)
			(layer "F.Fab")
			(hide yes)
			(effects
				(font
					(size 1.016 1.016)
					(thickness 0.1524)
				)
			)
		)
		(duplicate_pad_numbers_are_jumpers no)
		(fp_line
			(start -0.508 -0.9398)
			(end -0.508 0.9398)
			(stroke
				(width 0.1524)
				(type default)
			)
			(layer "F.SilkS")
		)
		(fp_line
			(start 0.508 -0.9398)
			(end -0.508 -0.9398)
			(stroke
				(width 0.1524)
				(type default)
			)
			(layer "F.SilkS")
		)
		(fp_rect
			(start -0.508 0.9398)
			(end 0.508 -0.9398)
			(stroke
				(width 0)
				(type default)
			)
			(fill no)
			(layer "F.CrtYd")
		)
		(fp_rect
			(start -0.508 0.9398)
			(end 0.508 -0.9398)
			(stroke
				(width 0)
				(type default)
			)
			(fill no)
			(layer "F.Fab")
		)
		(pad "1" smd custom
			(at 0 -0.4445 270)
			(size 0.1397 0.1397)
			(layers "F.Cu" "F.Mask" "F.Paste")
			(net "IOM_FULL_PGOOD")
			(options
				(clearance outline)
				(anchor circle)
			)
			(primitives
				(gr_poly
					(pts
						(arc
							(start -0.1778 -0.2794)
							(mid -0.249642 -0.249642)
							(end -0.2794 -0.1778)
						)
						(arc
							(start -0.2794 0.1778)
							(mid -0.249642 0.249642)
							(end -0.1778 0.2794)
						)
						(arc
							(start 0.1778 0.2794)
							(mid 0.249642 0.249642)
							(end 0.2794 0.1778)
						)
						(arc
							(start 0.2794 -0.1778)
							(mid 0.249642 -0.249642)
							(end 0.1778 -0.2794)
						)
					)
					(width 0)
					(fill yes)
				)
			)
		)
		(pad "2" smd custom
			(at 0 0.4445 270)
			(size 0.1397 0.1397)
			(layers "F.Cu" "F.Mask" "F.Paste")
			(net "U43_VREF2")
			(options
				(clearance outline)
				(anchor circle)
			)
			(primitives
				(gr_poly
					(pts
						(arc
							(start -0.1778 -0.2794)
							(mid -0.249642 -0.249642)
							(end -0.2794 -0.1778)
						)
						(arc
							(start -0.2794 0.1778)
							(mid -0.249642 0.249642)
							(end -0.1778 0.2794)
						)
						(arc
							(start 0.1778 0.2794)
							(mid 0.249642 0.249642)
							(end 0.2794 0.1778)
						)
						(arc
							(start 0.2794 -0.1778)
							(mid 0.249642 -0.249642)
							(end 0.1778 -0.2794)
						)
					)
					(width 0)
					(fill yes)
				)
			)
		)
	)
	(footprint ""
		(layer "F.Cu")
		(at 10.791698 -141.008862 90)
		(property "Reference" "R228"
			(at 0 0 90)
			(layer "F.SilkS")
			(hide yes)
			(effects
				(font
					(size 1.27 1.27)
				)
			)
		)
		(property "Value" "120R2F-GP"
			(at 0.064008 -3.993896 90)
			(unlocked yes)
			(layer "F.Fab")
			(hide yes)
			(effects
				(font
					(size 1.016 1.016)
					(thickness 0.1524)
				)
			)
		)
		(property "Device Type" "R402H16"
			(at 0.064008 -5.517896 90)
			(unlocked yes)
			(layer "F.Fab")
			(hide yes)
			(effects
				(font
					(size 1.016 1.016)
					(thickness 0.1524)
				)
			)
		)
		(duplicate_pad_numbers_are_jumpers no)
		(fp_line
			(start 0.508 -0.9398)
			(end -0.508 -0.9398)
			(stroke
				(width 0.1524)
				(type default)
			)
			(layer "F.SilkS")
		)
		(fp_line
			(start -0.508 -0.9398)
			(end -0.508 0.9398)
			(stroke
				(width 0.1524)
				(type default)
			)
			(layer "F.SilkS")
		)
		(fp_rect
			(start -0.508 0.9398)
			(end 0.508 -0.9398)
			(stroke
				(width 0)
				(type default)
			)
			(fill no)
			(layer "F.CrtYd")
		)
		(fp_rect
			(start -0.508 0.9398)
			(end 0.508 -0.9398)
			(stroke
				(width 0)
				(type default)
			)
			(fill no)
			(layer "F.Fab")
		)
		(pad "1" smd custom
			(at 0 -0.4445 90)
			(size 0.1397 0.1397)
			(layers "F.Cu" "F.Mask" "F.Paste")
			(net "MEMWEN")
			(options
				(clearance outline)
				(anchor circle)
			)
			(primitives
				(gr_poly
					(pts
						(arc
							(start -0.1778 -0.2794)
							(mid -0.249642 -0.249642)
							(end -0.2794 -0.1778)
						)
						(arc
							(start -0.2794 0.1778)
							(mid -0.249642 0.249642)
							(end -0.1778 0.2794)
						)
						(arc
							(start 0.1778 0.2794)
							(mid 0.249642 0.249642)
							(end 0.2794 0.1778)
						)
						(arc
							(start 0.2794 -0.1778)
							(mid 0.249642 -0.249642)
							(end 0.1778 -0.2794)
						)
					)
					(width 0)
					(fill yes)
				)
			)
		)
		(pad "2" smd custom
			(at 0 0.4445 90)
			(size 0.1397 0.1397)
			(layers "F.Cu" "F.Mask" "F.Paste")
			(net "P1V2_STBY")
			(options
				(clearance outline)
				(anchor circle)
			)
			(primitives
				(gr_poly
					(pts
						(arc
							(start -0.1778 -0.2794)
							(mid -0.249642 -0.249642)
							(end -0.2794 -0.1778)
						)
						(arc
							(start -0.2794 0.1778)
							(mid -0.249642 0.249642)
							(end -0.1778 0.2794)
						)
						(arc
							(start 0.1778 0.2794)
							(mid 0.249642 0.249642)
							(end 0.2794 0.1778)
						)
						(arc
							(start 0.2794 -0.1778)
							(mid 0.249642 -0.249642)
							(end 0.1778 -0.2794)
						)
					)
					(width 0)
					(fill yes)
				)
			)
		)
	)
	(footprint ""
		(layer "F.Cu")
		(at 52.8066 -162.4838 180)
		(property "Reference" "C122"
			(at 0 0 180)
			(layer "F.SilkS")
			(hide yes)
			(effects
				(font
					(size 1.27 1.27)
				)
			)
		)
		(property "Value" "SCD1U25V2KX-2-GP"
			(at 1.1811 -2.7051 180)
			(unlocked yes)
			(layer "F.Fab")
			(hide yes)
			(effects
				(font
					(size 1.016 1.016)
					(thickness 0.1524)
				)
			)
		)
		(property "Device Type" "C402H22"
			(at 1.1811 -4.2291 180)
			(unlocked yes)
			(layer "F.Fab")
			(hide yes)
			(effects
				(font
					(size 1.016 1.016)
					(thickness 0.1524)
				)
			)
		)
		(duplicate_pad_numbers_are_jumpers no)
		(fp_rect
			(start -0.4318 0.9525)
			(end 0.4318 -0.9525)
			(stroke
				(width 0)
				(type default)
			)
			(fill no)
			(layer "F.CrtYd")
		)
		(fp_rect
			(start -0.4318 0.9525)
			(end 0.4318 -0.9525)
			(stroke
				(width 0)
				(type default)
			)
			(fill no)
			(layer "F.Fab")
		)
		(pad "1" smd custom
			(at 0 -0.4445 180)
			(size 0.1524 0.1524)
			(layers "F.Cu" "F.Mask" "F.Paste")
			(net "ADC_P3V3")
			(options
				(clearance outline)
				(anchor circle)
			)
			(primitives
				(gr_poly
					(pts
						(arc
							(start 0.3048 -0.2032)
							(mid 0.275042 -0.275042)
							(end 0.2032 -0.3048)
						)
						(arc
							(start -0.2032 -0.3048)
							(mid -0.275042 -0.275042)
							(end -0.3048 -0.2032)
						)
						(arc
							(start -0.3048 0.2032)
							(mid -0.275042 0.275042)
							(end -0.2032 0.3048)
						)
						(arc
							(start 0.2032 0.3048)
							(mid 0.275042 0.275042)
							(end 0.3048 0.2032)
						)
					)
					(width 0)
					(fill yes)
				)
			)
		)
		(pad "2" smd custom
			(at 0 0.4445 180)
			(size 0.1524 0.1524)
			(layers "F.Cu" "F.Mask" "F.Paste")
			(net "GND")
			(options
				(clearance outline)
				(anchor circle)
			)
			(primitives
				(gr_poly
					(pts
						(arc
							(start 0.3048 -0.2032)
							(mid 0.275042 -0.275042)
							(end 0.2032 -0.3048)
						)
						(arc
							(start -0.2032 -0.3048)
							(mid -0.275042 -0.275042)
							(end -0.3048 -0.2032)
						)
						(arc
							(start -0.3048 0.2032)
							(mid -0.275042 0.275042)
							(end -0.2032 0.3048)
						)
						(arc
							(start 0.2032 0.3048)
							(mid 0.275042 0.275042)
							(end 0.3048 0.2032)
						)
					)
					(width 0)
					(fill yes)
				)
			)
		)
	)
	(footprint ""
		(layer "F.Cu")
		(at 194.3862 -26.162 180)
		(property "Reference" "U48"
			(at 0 0 180)
			(layer "F.SilkS")
			(hide yes)
			(effects
				(font
					(size 1.27 1.27)
				)
			)
		)
		(property "Value" "SN74LVC1G08DCKR-GP"
			(at -2.3368 -8.6868 180)
			(unlocked yes)
			(layer "F.Fab")
			(hide yes)
			(effects
				(font
					(size 1.016 1.016)
					(thickness 0.1524)
				)
			)
		)
		(property "Device Type" "SC70-5H44"
			(at -2.3114 -10.414 180)
			(unlocked yes)
			(layer "F.Fab")
			(hide yes)
			(effects
				(font
					(size 1.016 1.016)
					(thickness 0.1524)
				)
			)
		)
		(duplicate_pad_numbers_are_jumpers no)
		(fp_line
			(start 1.3843 -1.8034)
			(end 1.3843 -1.1176)
			(stroke
				(width 0.3302)
				(type default)
			)
			(layer "F.SilkS")
		)
		(fp_line
			(start 1.27 1.7018)
			(end -1.27 1.7018)
			(stroke
				(width 0.1524)
				(type default)
			)
			(layer "F.SilkS")
		)
		(fp_line
			(start 1.27 -1.7018)
			(end 1.27 1.7018)
			(stroke
				(width 0.1524)
				(type default)
			)
			(layer "F.SilkS")
		)
		(fp_line
			(start 0.6604 -1.8034)
			(end 1.3843 -1.8034)
			(stroke
				(width 0.3302)
				(type default)
			)
			(layer "F.SilkS")
		)
		(fp_line
			(start -1.27 1.7018)
			(end -1.27 -1.7018)
			(stroke
				(width 0.1524)
				(type default)
			)
			(layer "F.SilkS")
		)
		(fp_line
			(start -1.27 -1.7018)
			(end 1.27 -1.7018)
			(stroke
				(width 0.1524)
				(type default)
			)
			(layer "F.SilkS")
		)
		(fp_rect
			(start -1.524 1.9558)
			(end 1.524 -1.9558)
			(stroke
				(width 0)
				(type default)
			)
			(fill no)
			(layer "F.CrtYd")
		)
		(fp_poly
			(pts
				(xy -1.524 -1.9558) (xy 1.524 -1.9558) (xy 1.524 1.9558) (xy -1.524 1.9558)
			)
			(stroke
				(width 0)
				(type default)
			)
			(fill no)
			(layer "F.Fab")
		)
		(pad "1" smd rect
			(at 0.65024 -0.8255 180)
			(size 0.4064 1.2192)
			(layers "F.Cu" "F.Mask" "F.Paste")
			(net "BMC_EXT1_LED_Y")
		)
		(pad "2" smd rect
			(at 0 -0.8255 180)
			(size 0.4064 1.2192)
			(layers "F.Cu" "F.Mask" "F.Paste")
			(net "IOC_EXT1_LED_B")
		)
		(pad "3" smd rect
			(at -0.65024 -0.8255 180)
			(size 0.4064 1.2192)
			(layers "F.Cu" "F.Mask" "F.Paste")
			(net "GND")
		)
		(pad "4" smd rect
			(at -0.65024 0.8255 180)
			(size 0.4064 1.2192)
			(layers "F.Cu" "F.Mask" "F.Paste")
			(net "EXT1_LED_BLUE_G_Q24")
		)
		(pad "5" smd rect
			(at 0.65024 0.8255 180)
			(size 0.4064 1.2192)
			(layers "F.Cu" "F.Mask" "F.Paste")
			(net "P1V8")
		)
	)
	(footprint ""
		(layer "F.Cu")
		(at 199.176894 -31.77921)
		(property "Reference" "R730"
			(at 0 0 0)
			(layer "F.SilkS")
			(hide yes)
			(effects
				(font
					(size 1.27 1.27)
				)
			)
		)
		(property "Value" "1KR2F-3-GP"
			(at 0.064008 -3.993896 0)
			(unlocked yes)
			(layer "F.Fab")
			(hide yes)
			(effects
				(font
					(size 1.016 1.016)
					(thickness 0.1524)
				)
			)
		)
		(property "Device Type" "R402H16"
			(at 0.064008 -5.517896 0)
			(unlocked yes)
			(layer "F.Fab")
			(hide yes)
			(effects
				(font
					(size 1.016 1.016)
					(thickness 0.1524)
				)
			)
		)
		(duplicate_pad_numbers_are_jumpers no)
		(fp_line
			(start -0.508 -0.9398)
			(end -0.508 0.9398)
			(stroke
				(width 0.1524)
				(type default)
			)
			(layer "F.SilkS")
		)
		(fp_line
			(start 0.508 -0.9398)
			(end -0.508 -0.9398)
			(stroke
				(width 0.1524)
				(type default)
			)
			(layer "F.SilkS")
		)
		(fp_rect
			(start -0.508 0.9398)
			(end 0.508 -0.9398)
			(stroke
				(width 0)
				(type default)
			)
			(fill no)
			(layer "F.CrtYd")
		)
		(fp_rect
			(start -0.508 0.9398)
			(end 0.508 -0.9398)
			(stroke
				(width 0)
				(type default)
			)
			(fill no)
			(layer "F.Fab")
		)
		(pad "1" smd custom
			(at 0 -0.4445)
			(size 0.1397 0.1397)
			(layers "F.Cu" "F.Mask" "F.Paste")
			(net "P5V_STBY")
			(options
				(clearance outline)
				(anchor circle)
			)
			(primitives
				(gr_poly
					(pts
						(arc
							(start -0.1778 -0.2794)
							(mid -0.249642 -0.249642)
							(end -0.2794 -0.1778)
						)
						(arc
							(start -0.2794 0.1778)
							(mid -0.249642 0.249642)
							(end -0.1778 0.2794)
						)
						(arc
							(start 0.1778 0.2794)
							(mid 0.249642 0.249642)
							(end 0.2794 0.1778)
						)
						(arc
							(start 0.2794 -0.1778)
							(mid 0.249642 -0.249642)
							(end 0.1778 -0.2794)
						)
					)
					(width 0)
					(fill yes)
				)
			)
		)
		(pad "2" smd custom
			(at 0 0.4445)
			(size 0.1397 0.1397)
			(layers "F.Cu" "F.Mask" "F.Paste")
			(net "EXT2_LED_BLUE_G2")
			(options
				(clearance outline)
				(anchor circle)
			)
			(primitives
				(gr_poly
					(pts
						(arc
							(start -0.1778 -0.2794)
							(mid -0.249642 -0.249642)
							(end -0.2794 -0.1778)
						)
						(arc
							(start -0.2794 0.1778)
							(mid -0.249642 0.249642)
							(end -0.1778 0.2794)
						)
						(arc
							(start 0.1778 0.2794)
							(mid 0.249642 0.249642)
							(end 0.2794 0.1778)
						)
						(arc
							(start 0.2794 -0.1778)
							(mid 0.249642 -0.249642)
							(end 0.1778 -0.2794)
						)
					)
					(width 0)
					(fill yes)
				)
			)
		)
	)
	(footprint ""
		(layer "F.Cu")
		(at 79.840582 -135.980678 90)
		(property "Reference" "R98"
			(at 0 0 90)
			(layer "F.SilkS")
			(hide yes)
			(effects
				(font
					(size 1.27 1.27)
				)
			)
		)
		(property "Value" "0R2J-2-GP"
			(at 0.064008 -3.993896 90)
			(unlocked yes)
			(layer "F.Fab")
			(hide yes)
			(effects
				(font
					(size 1.016 1.016)
					(thickness 0.1524)
				)
			)
		)
		(property "Device Type" "R402H16"
			(at 0.064008 -5.517896 90)
			(unlocked yes)
			(layer "F.Fab")
			(hide yes)
			(effects
				(font
					(size 1.016 1.016)
					(thickness 0.1524)
				)
			)
		)
		(duplicate_pad_numbers_are_jumpers no)
		(fp_line
			(start 0.508 -0.9398)
			(end -0.508 -0.9398)
			(stroke
				(width 0.1524)
				(type default)
			)
			(layer "F.SilkS")
		)
		(fp_line
			(start -0.508 -0.9398)
			(end -0.508 0.9398)
			(stroke
				(width 0.1524)
				(type default)
			)
			(layer "F.SilkS")
		)
		(fp_rect
			(start -0.508 0.9398)
			(end 0.508 -0.9398)
			(stroke
				(width 0)
				(type default)
			)
			(fill no)
			(layer "F.CrtYd")
		)
		(fp_rect
			(start -0.508 0.9398)
			(end 0.508 -0.9398)
			(stroke
				(width 0)
				(type default)
			)
			(fill no)
			(layer "F.Fab")
		)
		(pad "1" smd custom
			(at 0 -0.4445 90)
			(size 0.1397 0.1397)
			(layers "F.Cu" "F.Mask" "F.Paste")
			(net "UART_SEL_MUX")
			(options
				(clearance outline)
				(anchor circle)
			)
			(primitives
				(gr_poly
					(pts
						(arc
							(start -0.1778 -0.2794)
							(mid -0.249642 -0.249642)
							(end -0.2794 -0.1778)
						)
						(arc
							(start -0.2794 0.1778)
							(mid -0.249642 0.249642)
							(end -0.1778 0.2794)
						)
						(arc
							(start 0.1778 0.2794)
							(mid 0.249642 0.249642)
							(end 0.2794 0.1778)
						)
						(arc
							(start 0.2794 -0.1778)
							(mid 0.249642 -0.249642)
							(end 0.1778 -0.2794)
						)
					)
					(width 0)
					(fill yes)
				)
			)
		)
		(pad "2" smd custom
			(at 0 0.4445 90)
			(size 0.1397 0.1397)
			(layers "F.Cu" "F.Mask" "F.Paste")
			(net "D_FLIP_Q")
			(options
				(clearance outline)
				(anchor circle)
			)
			(primitives
				(gr_poly
					(pts
						(arc
							(start -0.1778 -0.2794)
							(mid -0.249642 -0.249642)
							(end -0.2794 -0.1778)
						)
						(arc
							(start -0.2794 0.1778)
							(mid -0.249642 0.249642)
							(end -0.1778 0.2794)
						)
						(arc
							(start 0.1778 0.2794)
							(mid 0.249642 0.249642)
							(end 0.2794 0.1778)
						)
						(arc
							(start 0.2794 -0.1778)
							(mid 0.249642 -0.249642)
							(end 0.1778 -0.2794)
						)
					)
					(width 0)
					(fill yes)
				)
			)
		)
	)
	(footprint ""
		(layer "F.Cu")
		(at 151.1808 -94.8182 90)
		(property "Reference" "R639"
			(at 0 0 90)
			(layer "F.SilkS")
			(hide yes)
			(effects
				(font
					(size 1.27 1.27)
				)
			)
		)
		(property "Value" "4K7R2F-GP"
			(at 0.064008 -3.993896 90)
			(unlocked yes)
			(layer "F.Fab")
			(hide yes)
			(effects
				(font
					(size 1.016 1.016)
					(thickness 0.1524)
				)
			)
		)
		(property "Device Type" "R402H16"
			(at 0.064008 -5.517896 90)
			(unlocked yes)
			(layer "F.Fab")
			(hide yes)
			(effects
				(font
					(size 1.016 1.016)
					(thickness 0.1524)
				)
			)
		)
		(duplicate_pad_numbers_are_jumpers no)
		(fp_line
			(start 0.508 -0.9398)
			(end -0.508 -0.9398)
			(stroke
				(width 0.1524)
				(type default)
			)
			(layer "F.SilkS")
		)
		(fp_line
			(start -0.508 -0.9398)
			(end -0.508 0.9398)
			(stroke
				(width 0.1524)
				(type default)
			)
			(layer "F.SilkS")
		)
		(fp_rect
			(start -0.508 0.9398)
			(end 0.508 -0.9398)
			(stroke
				(width 0)
				(type default)
			)
			(fill no)
			(layer "F.CrtYd")
		)
		(fp_rect
			(start -0.508 0.9398)
			(end 0.508 -0.9398)
			(stroke
				(width 0)
				(type default)
			)
			(fill no)
			(layer "F.Fab")
		)
		(pad "1" smd custom
			(at 0 -0.4445 90)
			(size 0.1397 0.1397)
			(layers "F.Cu" "F.Mask" "F.Paste")
			(net "P3V3_STBY_G")
			(options
				(clearance outline)
				(anchor circle)
			)
			(primitives
				(gr_poly
					(pts
						(arc
							(start -0.1778 -0.2794)
							(mid -0.249642 -0.249642)
							(end -0.2794 -0.1778)
						)
						(arc
							(start -0.2794 0.1778)
							(mid -0.249642 0.249642)
							(end -0.1778 0.2794)
						)
						(arc
							(start 0.1778 0.2794)
							(mid 0.249642 0.249642)
							(end 0.2794 0.1778)
						)
						(arc
							(start 0.2794 -0.1778)
							(mid 0.249642 -0.249642)
							(end 0.1778 -0.2794)
						)
					)
					(width 0)
					(fill yes)
				)
			)
		)
		(pad "2" smd custom
			(at 0 0.4445 90)
			(size 0.1397 0.1397)
			(layers "F.Cu" "F.Mask" "F.Paste")
			(net "P3V3_STBY")
			(options
				(clearance outline)
				(anchor circle)
			)
			(primitives
				(gr_poly
					(pts
						(arc
							(start -0.1778 -0.2794)
							(mid -0.249642 -0.249642)
							(end -0.2794 -0.1778)
						)
						(arc
							(start -0.2794 0.1778)
							(mid -0.249642 0.249642)
							(end -0.1778 0.2794)
						)
						(arc
							(start 0.1778 0.2794)
							(mid 0.249642 0.249642)
							(end 0.2794 0.1778)
						)
						(arc
							(start 0.2794 -0.1778)
							(mid 0.249642 -0.249642)
							(end 0.1778 -0.2794)
						)
					)
					(width 0)
					(fill yes)
				)
			)
		)
	)
	(footprint ""
		(layer "F.Cu")
		(at 160.687512 -141.307058)
		(property "Reference" "R513"
			(at 0 0 0)
			(layer "F.SilkS")
			(hide yes)
			(effects
				(font
					(size 1.27 1.27)
				)
			)
		)
		(property "Value" "10KR2F-2-GP"
			(at 0.064008 -3.993896 0)
			(unlocked yes)
			(layer "F.Fab")
			(hide yes)
			(effects
				(font
					(size 1.016 1.016)
					(thickness 0.1524)
				)
			)
		)
		(property "Device Type" "R402H16"
			(at 0.064008 -5.517896 0)
			(unlocked yes)
			(layer "F.Fab")
			(hide yes)
			(effects
				(font
					(size 1.016 1.016)
					(thickness 0.1524)
				)
			)
		)
		(duplicate_pad_numbers_are_jumpers no)
		(fp_line
			(start -0.508 -0.9398)
			(end -0.508 0.9398)
			(stroke
				(width 0.1524)
				(type default)
			)
			(layer "F.SilkS")
		)
		(fp_line
			(start 0.508 -0.9398)
			(end -0.508 -0.9398)
			(stroke
				(width 0.1524)
				(type default)
			)
			(layer "F.SilkS")
		)
		(fp_rect
			(start -0.508 0.9398)
			(end 0.508 -0.9398)
			(stroke
				(width 0)
				(type default)
			)
			(fill no)
			(layer "F.CrtYd")
		)
		(fp_rect
			(start -0.508 0.9398)
			(end 0.508 -0.9398)
			(stroke
				(width 0)
				(type default)
			)
			(fill no)
			(layer "F.Fab")
		)
		(pad "1" smd custom
			(at 0 -0.4445)
			(size 0.1397 0.1397)
			(layers "F.Cu" "F.Mask" "F.Paste")
			(net "AGND_P1V8_STBY")
			(options
				(clearance outline)
				(anchor circle)
			)
			(primitives
				(gr_poly
					(pts
						(arc
							(start -0.1778 -0.2794)
							(mid -0.249642 -0.249642)
							(end -0.2794 -0.1778)
						)
						(arc
							(start -0.2794 0.1778)
							(mid -0.249642 0.249642)
							(end -0.1778 0.2794)
						)
						(arc
							(start 0.1778 0.2794)
							(mid 0.249642 0.249642)
							(end 0.2794 0.1778)
						)
						(arc
							(start 0.2794 -0.1778)
							(mid 0.249642 -0.249642)
							(end 0.1778 -0.2794)
						)
					)
					(width 0)
					(fill yes)
				)
			)
		)
		(pad "2" smd custom
			(at 0 0.4445)
			(size 0.1397 0.1397)
			(layers "F.Cu" "F.Mask" "F.Paste")
			(net "P1V8_STBY_VFB")
			(options
				(clearance outline)
				(anchor circle)
			)
			(primitives
				(gr_poly
					(pts
						(arc
							(start -0.1778 -0.2794)
							(mid -0.249642 -0.249642)
							(end -0.2794 -0.1778)
						)
						(arc
							(start -0.2794 0.1778)
							(mid -0.249642 0.249642)
							(end -0.1778 0.2794)
						)
						(arc
							(start 0.1778 0.2794)
							(mid 0.249642 0.249642)
							(end 0.2794 0.1778)
						)
						(arc
							(start 0.2794 -0.1778)
							(mid 0.249642 -0.249642)
							(end 0.1778 -0.2794)
						)
					)
					(width 0)
					(fill yes)
				)
			)
		)
	)
	(footprint ""
		(layer "F.Cu")
		(at 199.898 -17.907)
		(property "Reference" "Q21"
			(at 0 0 0)
			(layer "F.SilkS")
			(hide yes)
			(effects
				(font
					(size 1.27 1.27)
				)
			)
		)
		(property "Value" "SSM3K324R-GP"
			(at 0.127 -8.9662 0)
			(unlocked yes)
			(layer "F.Fab")
			(hide yes)
			(effects
				(font
					(size 1.016 1.016)
					(thickness 0.1524)
				)
			)
		)
		(property "Device Type" "SOT23DGS2D4H35"
			(at 0.127 -10.4902 0)
			(unlocked yes)
			(layer "F.Fab")
			(hide yes)
			(effects
				(font
					(size 1.016 1.016)
					(thickness 0.1524)
				)
			)
		)
		(duplicate_pad_numbers_are_jumpers no)
		(fp_line
			(start -1.651 -1.778)
			(end -1.651 1.778)
			(stroke
				(width 0.1524)
				(type default)
			)
			(layer "F.SilkS")
		)
		(fp_line
			(start -1.651 1.778)
			(end 1.651 1.778)
			(stroke
				(width 0.1524)
				(type default)
			)
			(layer "F.SilkS")
		)
		(fp_line
			(start 1.651 -1.778)
			(end -1.651 -1.778)
			(stroke
				(width 0.1524)
				(type default)
			)
			(layer "F.SilkS")
		)
		(fp_line
			(start 1.651 1.778)
			(end 1.651 -1.778)
			(stroke
				(width 0.1524)
				(type default)
			)
			(layer "F.SilkS")
		)
		(fp_poly
			(pts
				(xy -1.778 1.8796) (xy -1.778 -1.8796) (xy 1.778 -1.8796) (xy 1.778 1.8796)
			)
			(stroke
				(width 0)
				(type default)
			)
			(fill no)
			(layer "F.CrtYd")
		)
		(fp_poly
			(pts
				(xy -1.778 1.8796) (xy -1.778 -1.8796) (xy 1.778 -1.8796) (xy 1.778 1.8796)
			)
			(stroke
				(width 0)
				(type default)
			)
			(fill no)
			(layer "F.Fab")
		)
		(pad "D" smd custom
			(at 0 -0.9525)
			(size 0.1905 0.1905)
			(layers "F.Cu" "F.Mask" "F.Paste")
			(net "EXT1_LED_YELLOW_D")
			(options
				(clearance outline)
				(anchor circle)
			)
			(primitives
				(gr_poly
					(pts
						(arc
							(start -0.1778 0.5715)
							(mid -0.321484 0.511984)
							(end -0.381 0.3683)
						)
						(arc
							(start -0.381 -0.3683)
							(mid -0.321484 -0.511984)
							(end -0.1778 -0.5715)
						)
						(arc
							(start 0.1778 -0.5715)
							(mid 0.321484 -0.511984)
							(end 0.381 -0.3683)
						)
						(arc
							(start 0.381 0.3683)
							(mid 0.321484 0.511984)
							(end 0.1778 0.5715)
						)
					)
					(width 0)
					(fill yes)
				)
			)
		)
		(pad "G" smd custom
			(at -0.98425 0.9525)
			(size 0.1905 0.1905)
			(layers "F.Cu" "F.Mask" "F.Paste")
			(net "IOC_EXT1_LED_Y_XOR")
			(options
				(clearance outline)
				(anchor circle)
			)
			(primitives
				(gr_poly
					(pts
						(arc
							(start -0.1778 0.5715)
							(mid -0.321484 0.511984)
							(end -0.381 0.3683)
						)
						(arc
							(start -0.381 -0.3683)
							(mid -0.321484 -0.511984)
							(end -0.1778 -0.5715)
						)
						(arc
							(start 0.1778 -0.5715)
							(mid 0.321484 -0.511984)
							(end 0.381 -0.3683)
						)
						(arc
							(start 0.381 0.3683)
							(mid 0.321484 0.511984)
							(end 0.1778 0.5715)
						)
					)
					(width 0)
					(fill yes)
				)
			)
		)
		(pad "S" smd custom
			(at 0.98425 0.9525)
			(size 0.1905 0.1905)
			(layers "F.Cu" "F.Mask" "F.Paste")
			(net "GND")
			(options
				(clearance outline)
				(anchor circle)
			)
			(primitives
				(gr_poly
					(pts
						(arc
							(start -0.1778 0.5715)
							(mid -0.321484 0.511984)
							(end -0.381 0.3683)
						)
						(arc
							(start -0.381 -0.3683)
							(mid -0.321484 -0.511984)
							(end -0.1778 -0.5715)
						)
						(arc
							(start 0.1778 -0.5715)
							(mid 0.321484 -0.511984)
							(end 0.381 -0.3683)
						)
						(arc
							(start 0.381 0.3683)
							(mid 0.321484 0.511984)
							(end 0.1778 0.5715)
						)
					)
					(width 0)
					(fill yes)
				)
			)
		)
	)
	(footprint ""
		(layer "F.Cu")
		(at 50.5714 -127.7112 90)
		(property "Reference" "R87"
			(at 0 0 90)
			(layer "F.SilkS")
			(hide yes)
			(effects
				(font
					(size 1.27 1.27)
				)
			)
		)
		(property "Value" "100KR2F-L1-GP"
			(at 0.064008 -3.993896 90)
			(unlocked yes)
			(layer "F.Fab")
			(hide yes)
			(effects
				(font
					(size 1.016 1.016)
					(thickness 0.1524)
				)
			)
		)
		(property "Device Type" "R402H16"
			(at 0.064008 -5.517896 90)
			(unlocked yes)
			(layer "F.Fab")
			(hide yes)
			(effects
				(font
					(size 1.016 1.016)
					(thickness 0.1524)
				)
			)
		)
		(duplicate_pad_numbers_are_jumpers no)
		(fp_line
			(start 0.508 -0.9398)
			(end -0.508 -0.9398)
			(stroke
				(width 0.1524)
				(type default)
			)
			(layer "F.SilkS")
		)
		(fp_line
			(start -0.508 -0.9398)
			(end -0.508 0.9398)
			(stroke
				(width 0.1524)
				(type default)
			)
			(layer "F.SilkS")
		)
		(fp_rect
			(start -0.508 0.9398)
			(end 0.508 -0.9398)
			(stroke
				(width 0)
				(type default)
			)
			(fill no)
			(layer "F.CrtYd")
		)
		(fp_rect
			(start -0.508 0.9398)
			(end 0.508 -0.9398)
			(stroke
				(width 0)
				(type default)
			)
			(fill no)
			(layer "F.Fab")
		)
		(pad "1" smd custom
			(at 0 -0.4445 90)
			(size 0.1397 0.1397)
			(layers "F.Cu" "F.Mask" "F.Paste")
			(net "SCC_RMT_FULL_PWR_EN")
			(options
				(clearance outline)
				(anchor circle)
			)
			(primitives
				(gr_poly
					(pts
						(arc
							(start -0.1778 -0.2794)
							(mid -0.249642 -0.249642)
							(end -0.2794 -0.1778)
						)
						(arc
							(start -0.2794 0.1778)
							(mid -0.249642 0.249642)
							(end -0.1778 0.2794)
						)
						(arc
							(start 0.1778 0.2794)
							(mid 0.249642 0.249642)
							(end 0.2794 0.1778)
						)
						(arc
							(start 0.2794 -0.1778)
							(mid 0.249642 -0.249642)
							(end 0.1778 -0.2794)
						)
					)
					(width 0)
					(fill yes)
				)
			)
		)
		(pad "2" smd custom
			(at 0 0.4445 90)
			(size 0.1397 0.1397)
			(layers "F.Cu" "F.Mask" "F.Paste")
			(net "GND")
			(options
				(clearance outline)
				(anchor circle)
			)
			(primitives
				(gr_poly
					(pts
						(arc
							(start -0.1778 -0.2794)
							(mid -0.249642 -0.249642)
							(end -0.2794 -0.1778)
						)
						(arc
							(start -0.2794 0.1778)
							(mid -0.249642 0.249642)
							(end -0.1778 0.2794)
						)
						(arc
							(start 0.1778 0.2794)
							(mid 0.249642 0.249642)
							(end 0.2794 0.1778)
						)
						(arc
							(start 0.2794 -0.1778)
							(mid 0.249642 -0.249642)
							(end 0.1778 -0.2794)
						)
					)
					(width 0)
					(fill yes)
				)
			)
		)
	)
	(footprint ""
		(layer "F.Cu")
		(at 199.5424 -48.2854 180)
		(property "Reference" "R633"
			(at 0 0 180)
			(layer "F.SilkS")
			(hide yes)
			(effects
				(font
					(size 1.27 1.27)
				)
			)
		)
		(property "Value" "4K7R2F-GP"
			(at 0.064008 -3.993896 180)
			(unlocked yes)
			(layer "F.Fab")
			(hide yes)
			(effects
				(font
					(size 1.016 1.016)
					(thickness 0.1524)
				)
			)
		)
		(property "Device Type" "R402H16"
			(at 0.064008 -5.517896 180)
			(unlocked yes)
			(layer "F.Fab")
			(hide yes)
			(effects
				(font
					(size 1.016 1.016)
					(thickness 0.1524)
				)
			)
		)
		(duplicate_pad_numbers_are_jumpers no)
		(fp_line
			(start 0.508 -0.9398)
			(end -0.508 -0.9398)
			(stroke
				(width 0.1524)
				(type default)
			)
			(layer "F.SilkS")
		)
		(fp_line
			(start -0.508 -0.9398)
			(end -0.508 0.9398)
			(stroke
				(width 0.1524)
				(type default)
			)
			(layer "F.SilkS")
		)
		(fp_rect
			(start -0.508 0.9398)
			(end 0.508 -0.9398)
			(stroke
				(width 0)
				(type default)
			)
			(fill no)
			(layer "F.CrtYd")
		)
		(fp_rect
			(start -0.508 0.9398)
			(end 0.508 -0.9398)
			(stroke
				(width 0)
				(type default)
			)
			(fill no)
			(layer "F.Fab")
		)
		(pad "1" smd custom
			(at 0 -0.4445 180)
			(size 0.1397 0.1397)
			(layers "F.Cu" "F.Mask" "F.Paste")
			(net "P1V8")
			(options
				(clearance outline)
				(anchor circle)
			)
			(primitives
				(gr_poly
					(pts
						(arc
							(start -0.1778 -0.2794)
							(mid -0.249642 -0.249642)
							(end -0.2794 -0.1778)
						)
						(arc
							(start -0.2794 0.1778)
							(mid -0.249642 0.249642)
							(end -0.1778 0.2794)
						)
						(arc
							(start 0.1778 0.2794)
							(mid 0.249642 0.249642)
							(end 0.2794 0.1778)
						)
						(arc
							(start 0.2794 -0.1778)
							(mid 0.249642 -0.249642)
							(end 0.1778 -0.2794)
						)
					)
					(width 0)
					(fill yes)
				)
			)
		)
		(pad "2" smd custom
			(at 0 0.4445 180)
			(size 0.1397 0.1397)
			(layers "F.Cu" "F.Mask" "F.Paste")
			(net "ICE0_TRST#")
			(options
				(clearance outline)
				(anchor circle)
			)
			(primitives
				(gr_poly
					(pts
						(arc
							(start -0.1778 -0.2794)
							(mid -0.249642 -0.249642)
							(end -0.2794 -0.1778)
						)
						(arc
							(start -0.2794 0.1778)
							(mid -0.249642 0.249642)
							(end -0.1778 0.2794)
						)
						(arc
							(start 0.1778 0.2794)
							(mid 0.249642 0.249642)
							(end 0.2794 0.1778)
						)
						(arc
							(start 0.2794 -0.1778)
							(mid 0.249642 -0.249642)
							(end 0.1778 -0.2794)
						)
					)
					(width 0)
					(fill yes)
				)
			)
		)
	)
	(footprint ""
		(layer "F.Cu")
		(at 53.96103 -166.443152 180)
		(property "Reference" "C519"
			(at 0 0 180)
			(layer "F.SilkS")
			(hide yes)
			(effects
				(font
					(size 1.27 1.27)
				)
			)
		)
		(property "Value" "SCD1U25V2KX-2-GP"
			(at 1.1811 -2.7051 180)
			(unlocked yes)
			(layer "F.Fab")
			(hide yes)
			(effects
				(font
					(size 1.016 1.016)
					(thickness 0.1524)
				)
			)
		)
		(property "Device Type" "C402H22"
			(at 1.1811 -4.2291 180)
			(unlocked yes)
			(layer "F.Fab")
			(hide yes)
			(effects
				(font
					(size 1.016 1.016)
					(thickness 0.1524)
				)
			)
		)
		(duplicate_pad_numbers_are_jumpers no)
		(fp_rect
			(start -0.4318 0.9525)
			(end 0.4318 -0.9525)
			(stroke
				(width 0)
				(type default)
			)
			(fill no)
			(layer "F.CrtYd")
		)
		(fp_rect
			(start -0.4318 0.9525)
			(end 0.4318 -0.9525)
			(stroke
				(width 0)
				(type default)
			)
			(fill no)
			(layer "F.Fab")
		)
		(pad "1" smd custom
			(at 0 -0.4445 180)
			(size 0.1524 0.1524)
			(layers "F.Cu" "F.Mask" "F.Paste")
			(net "ADC_P1V2_STBY")
			(options
				(clearance outline)
				(anchor circle)
			)
			(primitives
				(gr_poly
					(pts
						(arc
							(start 0.3048 -0.2032)
							(mid 0.275042 -0.275042)
							(end 0.2032 -0.3048)
						)
						(arc
							(start -0.2032 -0.3048)
							(mid -0.275042 -0.275042)
							(end -0.3048 -0.2032)
						)
						(arc
							(start -0.3048 0.2032)
							(mid -0.275042 0.275042)
							(end -0.2032 0.3048)
						)
						(arc
							(start 0.2032 0.3048)
							(mid 0.275042 0.275042)
							(end 0.3048 0.2032)
						)
					)
					(width 0)
					(fill yes)
				)
			)
		)
		(pad "2" smd custom
			(at 0 0.4445 180)
			(size 0.1524 0.1524)
			(layers "F.Cu" "F.Mask" "F.Paste")
			(net "GND")
			(options
				(clearance outline)
				(anchor circle)
			)
			(primitives
				(gr_poly
					(pts
						(arc
							(start 0.3048 -0.2032)
							(mid 0.275042 -0.275042)
							(end 0.2032 -0.3048)
						)
						(arc
							(start -0.2032 -0.3048)
							(mid -0.275042 -0.275042)
							(end -0.3048 -0.2032)
						)
						(arc
							(start -0.3048 0.2032)
							(mid -0.275042 0.275042)
							(end -0.2032 0.3048)
						)
						(arc
							(start 0.2032 0.3048)
							(mid 0.275042 0.275042)
							(end 0.3048 0.2032)
						)
					)
					(width 0)
					(fill yes)
				)
			)
		)
	)
	(footprint ""
		(layer "F.Cu")
		(at 46.035976 -116.780818 -90)
		(property "Reference" "R86"
			(at 0 0 270)
			(layer "F.SilkS")
			(hide yes)
			(effects
				(font
					(size 1.27 1.27)
				)
			)
		)
		(property "Value" "2K2R2J-2-GP"
			(at 0.064008 -3.993896 270)
			(unlocked yes)
			(layer "F.Fab")
			(hide yes)
			(effects
				(font
					(size 1.016 1.016)
					(thickness 0.1524)
				)
			)
		)
		(property "Device Type" "R402H16"
			(at 0.064008 -5.517896 270)
			(unlocked yes)
			(layer "F.Fab")
			(hide yes)
			(effects
				(font
					(size 1.016 1.016)
					(thickness 0.1524)
				)
			)
		)
		(duplicate_pad_numbers_are_jumpers no)
		(fp_line
			(start -0.508 -0.9398)
			(end -0.508 0.9398)
			(stroke
				(width 0.1524)
				(type default)
			)
			(layer "F.SilkS")
		)
		(fp_line
			(start 0.508 -0.9398)
			(end -0.508 -0.9398)
			(stroke
				(width 0.1524)
				(type default)
			)
			(layer "F.SilkS")
		)
		(fp_rect
			(start -0.508 0.9398)
			(end 0.508 -0.9398)
			(stroke
				(width 0)
				(type default)
			)
			(fill no)
			(layer "F.CrtYd")
		)
		(fp_rect
			(start -0.508 0.9398)
			(end 0.508 -0.9398)
			(stroke
				(width 0)
				(type default)
			)
			(fill no)
			(layer "F.Fab")
		)
		(pad "1" smd custom
			(at 0 -0.4445 270)
			(size 0.1397 0.1397)
			(layers "F.Cu" "F.Mask" "F.Paste")
			(net "P3V3_STBY")
			(options
				(clearance outline)
				(anchor circle)
			)
			(primitives
				(gr_poly
					(pts
						(arc
							(start -0.1778 -0.2794)
							(mid -0.249642 -0.249642)
							(end -0.2794 -0.1778)
						)
						(arc
							(start -0.2794 0.1778)
							(mid -0.249642 0.249642)
							(end -0.1778 0.2794)
						)
						(arc
							(start 0.1778 0.2794)
							(mid 0.249642 0.249642)
							(end 0.2794 0.1778)
						)
						(arc
							(start 0.2794 -0.1778)
							(mid 0.249642 -0.249642)
							(end 0.1778 -0.2794)
						)
					)
					(width 0)
					(fill yes)
				)
			)
		)
		(pad "2" smd custom
			(at 0 0.4445 270)
			(size 0.1397 0.1397)
			(layers "F.Cu" "F.Mask" "F.Paste")
			(net "FLA0_SPI_HOLD_N")
			(options
				(clearance outline)
				(anchor circle)
			)
			(primitives
				(gr_poly
					(pts
						(arc
							(start -0.1778 -0.2794)
							(mid -0.249642 -0.249642)
							(end -0.2794 -0.1778)
						)
						(arc
							(start -0.2794 0.1778)
							(mid -0.249642 0.249642)
							(end -0.1778 0.2794)
						)
						(arc
							(start 0.1778 0.2794)
							(mid 0.249642 0.249642)
							(end 0.2794 0.1778)
						)
						(arc
							(start 0.2794 -0.1778)
							(mid 0.249642 -0.249642)
							(end 0.1778 -0.2794)
						)
					)
					(width 0)
					(fill yes)
				)
			)
		)
	)
	(footprint ""
		(layer "F.Cu")
		(at 172.942504 -142.171166 -90)
		(property "Reference" "C155"
			(at 0 0 270)
			(layer "F.SilkS")
			(hide yes)
			(effects
				(font
					(size 1.27 1.27)
				)
			)
		)
		(property "Value" "SC10U16V5KX-7-GP-U"
			(at -0.0762 -6.1214 270)
			(unlocked yes)
			(layer "F.Fab")
			(hide yes)
			(effects
				(font
					(size 1.016 1.016)
					(thickness 0.1524)
				)
			)
		)
		(property "Device Type" "C805H58"
			(at -0.0762 -8.1534 270)
			(unlocked yes)
			(layer "F.Fab")
			(hide yes)
			(effects
				(font
					(size 1.016 1.016)
					(thickness 0.1524)
				)
			)
		)
		(duplicate_pad_numbers_are_jumpers no)
		(fp_line
			(start 0.635 0)
			(end -0.635 0)
			(stroke
				(width 0.508)
				(type default)
			)
			(layer "F.SilkS")
		)
		(fp_rect
			(start -0.9652 1.778)
			(end 0.9652 -1.778)
			(stroke
				(width 0)
				(type default)
			)
			(fill no)
			(layer "F.CrtYd")
		)
		(fp_poly
			(pts
				(xy -0.9652 -1.778) (xy 0.9652 -1.778) (xy 0.9652 1.778) (xy -0.9652 1.778)
			)
			(stroke
				(width 0)
				(type default)
			)
			(fill no)
			(layer "F.Fab")
		)
		(pad "1" smd rect
			(at 0 -0.9652 270)
			(size 1.397 1.143)
			(layers "F.Cu" "F.Mask" "F.Paste")
			(net "P12V_STBY_VIN_PU1")
		)
		(pad "2" smd rect
			(at 0 0.9652 270)
			(size 1.397 1.143)
			(layers "F.Cu" "F.Mask" "F.Paste")
			(net "GND")
		)
	)
	(footprint ""
		(layer "F.Cu")
		(at 78.122018 -70.952868 90)
		(property "Reference" "VIA1"
			(at 0 0 90)
			(layer "F.SilkS")
			(hide yes)
			(effects
				(font
					(size 1.27 1.27)
				)
			)
		)
		(property "Value" "85OHM-8L-1D6MM-L16L18-GP"
			(at 4.064 0.6096 90)
			(unlocked yes)
			(layer "F.Fab")
			(hide yes)
			(effects
				(font
					(size 1.016 1.016)
					(thickness 0.1524)
				)
			)
		)
		(property "Device Type" "VIA-PCIE-4P-368076"
			(at 4.064 -0.9144 90)
			(unlocked yes)
			(layer "F.Fab")
			(hide yes)
			(effects
				(font
					(size 1.016 1.016)
					(thickness 0.1524)
				)
			)
		)
		(duplicate_pad_numbers_are_jumpers no)
		(fp_rect
			(start -1.8415 0.381)
			(end 1.8415 -0.381)
			(stroke
				(width 0)
				(type default)
			)
			(fill no)
			(layer "F.CrtYd")
		)
		(fp_rect
			(start -1.8415 0.381)
			(end 1.8415 -0.381)
			(stroke
				(width 0)
				(type default)
			)
			(fill no)
			(layer "F.Fab")
		)
		(pad "1" thru_hole circle
			(at -1.4605 0 90)
			(size 0.508 0.508)
			(drill 0.254)
			(layers "*.Cu" "*.Mask")
			(remove_unused_layers no)
			(net "GND")
			(clearance 0.127)
			(thermal_gap 0.127)
		)
		(pad "2" thru_hole circle
			(at -0.4445 0 90)
			(size 0.508 0.508)
			(drill 0.254)
			(layers "*.Cu" "*.Mask")
			(remove_unused_layers no)
			(net "PCIE_COMP_TO_IOM_16_DP")
			(clearance 0.127)
			(thermal_gap 0.127)
		)
		(pad "3" thru_hole circle
			(at 0.4445 0 90)
			(size 0.508 0.508)
			(drill 0.254)
			(layers "*.Cu" "*.Mask")
			(remove_unused_layers no)
			(net "PCIE_COMP_TO_IOM_16_DN")
			(clearance 0.127)
			(thermal_gap 0.127)
		)
		(pad "4" thru_hole circle
			(at 1.4605 0 90)
			(size 0.508 0.508)
			(drill 0.254)
			(layers "*.Cu" "*.Mask")
			(remove_unused_layers no)
			(net "GND")
			(clearance 0.127)
			(thermal_gap 0.127)
		)
	)
	(footprint ""
		(layer "F.Cu")
		(at 28.194 -153.67 -90)
		(property "Reference" "R771"
			(at 0 0 270)
			(layer "F.SilkS")
			(hide yes)
			(effects
				(font
					(size 1.27 1.27)
				)
			)
		)
		(property "Value" "0R2J-2-GP"
			(at 0.064008 -3.993896 270)
			(unlocked yes)
			(layer "F.Fab")
			(hide yes)
			(effects
				(font
					(size 1.016 1.016)
					(thickness 0.1524)
				)
			)
		)
		(property "Device Type" "R402H16"
			(at 0.064008 -5.517896 270)
			(unlocked yes)
			(layer "F.Fab")
			(hide yes)
			(effects
				(font
					(size 1.016 1.016)
					(thickness 0.1524)
				)
			)
		)
		(duplicate_pad_numbers_are_jumpers no)
		(fp_line
			(start -0.508 -0.9398)
			(end -0.508 0.9398)
			(stroke
				(width 0.1524)
				(type default)
			)
			(layer "F.SilkS")
		)
		(fp_line
			(start 0.508 -0.9398)
			(end -0.508 -0.9398)
			(stroke
				(width 0.1524)
				(type default)
			)
			(layer "F.SilkS")
		)
		(fp_rect
			(start -0.508 0.9398)
			(end 0.508 -0.9398)
			(stroke
				(width 0)
				(type default)
			)
			(fill no)
			(layer "F.CrtYd")
		)
		(fp_rect
			(start -0.508 0.9398)
			(end 0.508 -0.9398)
			(stroke
				(width 0)
				(type default)
			)
			(fill no)
			(layer "F.Fab")
		)
		(pad "1" smd custom
			(at 0 -0.4445 270)
			(size 0.1397 0.1397)
			(layers "F.Cu" "F.Mask" "F.Paste")
			(net "DEBUG_GPIO_BMC_R_4")
			(options
				(clearance outline)
				(anchor circle)
			)
			(primitives
				(gr_poly
					(pts
						(arc
							(start -0.1778 -0.2794)
							(mid -0.249642 -0.249642)
							(end -0.2794 -0.1778)
						)
						(arc
							(start -0.2794 0.1778)
							(mid -0.249642 0.249642)
							(end -0.1778 0.2794)
						)
						(arc
							(start 0.1778 0.2794)
							(mid 0.249642 0.249642)
							(end 0.2794 0.1778)
						)
						(arc
							(start 0.2794 -0.1778)
							(mid 0.249642 -0.249642)
							(end 0.1778 -0.2794)
						)
					)
					(width 0)
					(fill yes)
				)
			)
		)
		(pad "2" smd custom
			(at 0 0.4445 270)
			(size 0.1397 0.1397)
			(layers "F.Cu" "F.Mask" "F.Paste")
			(net "DEBUG_GPIO_BMC_4")
			(options
				(clearance outline)
				(anchor circle)
			)
			(primitives
				(gr_poly
					(pts
						(arc
							(start -0.1778 -0.2794)
							(mid -0.249642 -0.249642)
							(end -0.2794 -0.1778)
						)
						(arc
							(start -0.2794 0.1778)
							(mid -0.249642 0.249642)
							(end -0.1778 0.2794)
						)
						(arc
							(start 0.1778 0.2794)
							(mid 0.249642 0.249642)
							(end 0.2794 0.1778)
						)
						(arc
							(start 0.2794 -0.1778)
							(mid 0.249642 -0.249642)
							(end 0.1778 -0.2794)
						)
					)
					(width 0)
					(fill yes)
				)
			)
		)
	)
	(footprint ""
		(layer "F.Cu")
		(at 33.964372 -156.889958 -90)
		(property "Reference" "R320"
			(at 0 0 270)
			(layer "F.SilkS")
			(hide yes)
			(effects
				(font
					(size 1.27 1.27)
				)
			)
		)
		(property "Value" "0R2J-2-GP"
			(at 0.064008 -3.993896 270)
			(unlocked yes)
			(layer "F.Fab")
			(hide yes)
			(effects
				(font
					(size 1.016 1.016)
					(thickness 0.1524)
				)
			)
		)
		(property "Device Type" "R402H16"
			(at 0.064008 -5.517896 270)
			(unlocked yes)
			(layer "F.Fab")
			(hide yes)
			(effects
				(font
					(size 1.016 1.016)
					(thickness 0.1524)
				)
			)
		)
		(duplicate_pad_numbers_are_jumpers no)
		(fp_line
			(start -0.508 -0.9398)
			(end -0.508 0.9398)
			(stroke
				(width 0.1524)
				(type default)
			)
			(layer "F.SilkS")
		)
		(fp_line
			(start 0.508 -0.9398)
			(end -0.508 -0.9398)
			(stroke
				(width 0.1524)
				(type default)
			)
			(layer "F.SilkS")
		)
		(fp_rect
			(start -0.508 0.9398)
			(end 0.508 -0.9398)
			(stroke
				(width 0)
				(type default)
			)
			(fill no)
			(layer "F.CrtYd")
		)
		(fp_rect
			(start -0.508 0.9398)
			(end 0.508 -0.9398)
			(stroke
				(width 0)
				(type default)
			)
			(fill no)
			(layer "F.Fab")
		)
		(pad "1" smd custom
			(at 0 -0.4445 270)
			(size 0.1397 0.1397)
			(layers "F.Cu" "F.Mask" "F.Paste")
			(net "SCC_A_HB_IN_R")
			(options
				(clearance outline)
				(anchor circle)
			)
			(primitives
				(gr_poly
					(pts
						(arc
							(start -0.1778 -0.2794)
							(mid -0.249642 -0.249642)
							(end -0.2794 -0.1778)
						)
						(arc
							(start -0.2794 0.1778)
							(mid -0.249642 0.249642)
							(end -0.1778 0.2794)
						)
						(arc
							(start 0.1778 0.2794)
							(mid 0.249642 0.249642)
							(end 0.2794 0.1778)
						)
						(arc
							(start 0.2794 -0.1778)
							(mid 0.249642 -0.249642)
							(end 0.1778 -0.2794)
						)
					)
					(width 0)
					(fill yes)
				)
			)
		)
		(pad "2" smd custom
			(at 0 0.4445 270)
			(size 0.1397 0.1397)
			(layers "F.Cu" "F.Mask" "F.Paste")
			(net "SCC_LOC_HEARTBEAT")
			(options
				(clearance outline)
				(anchor circle)
			)
			(primitives
				(gr_poly
					(pts
						(arc
							(start -0.1778 -0.2794)
							(mid -0.249642 -0.249642)
							(end -0.2794 -0.1778)
						)
						(arc
							(start -0.2794 0.1778)
							(mid -0.249642 0.249642)
							(end -0.1778 0.2794)
						)
						(arc
							(start 0.1778 0.2794)
							(mid 0.249642 0.249642)
							(end 0.2794 0.1778)
						)
						(arc
							(start 0.2794 -0.1778)
							(mid 0.249642 -0.249642)
							(end 0.1778 -0.2794)
						)
					)
					(width 0)
					(fill yes)
				)
			)
		)
	)
	(footprint ""
		(layer "F.Cu")
		(at 64.3382 -149.9108 90)
		(property "Reference" "C82"
			(at 0 0 90)
			(layer "F.SilkS")
			(hide yes)
			(effects
				(font
					(size 1.27 1.27)
				)
			)
		)
		(property "Value" "SC33P50V2JN-3GP"
			(at 1.180846 -2.7051 90)
			(unlocked yes)
			(layer "F.Fab")
			(hide yes)
			(effects
				(font
					(size 1.016 1.016)
					(thickness 0.1524)
				)
			)
		)
		(property "Device Type" "C402H22"
			(at 1.180846 -4.228846 90)
			(unlocked yes)
			(layer "F.Fab")
			(hide yes)
			(effects
				(font
					(size 1.016 1.016)
					(thickness 0.1524)
				)
			)
		)
		(duplicate_pad_numbers_are_jumpers no)
		(fp_rect
			(start -0.4318 0.9525)
			(end 0.4318 -0.9525)
			(stroke
				(width 0)
				(type default)
			)
			(fill no)
			(layer "F.CrtYd")
		)
		(fp_rect
			(start -0.4318 0.9525)
			(end 0.4318 -0.9525)
			(stroke
				(width 0)
				(type default)
			)
			(fill no)
			(layer "F.Fab")
		)
		(pad "1" smd custom
			(at 0 -0.4445 90)
			(size 0.1524 0.1524)
			(layers "F.Cu" "F.Mask" "F.Paste")
			(net "PD_USB2AVRES")
			(options
				(clearance outline)
				(anchor circle)
			)
			(primitives
				(gr_poly
					(pts
						(arc
							(start 0.3048 -0.2032)
							(mid 0.275042 -0.275042)
							(end 0.2032 -0.3048)
						)
						(arc
							(start -0.2032 -0.3048)
							(mid -0.275042 -0.275042)
							(end -0.3048 -0.2032)
						)
						(arc
							(start -0.3048 0.2032)
							(mid -0.275042 0.275042)
							(end -0.2032 0.3048)
						)
						(arc
							(start 0.2032 0.3048)
							(mid 0.275042 0.275042)
							(end 0.3048 0.2032)
						)
					)
					(width 0)
					(fill yes)
				)
			)
		)
		(pad "2" smd custom
			(at 0 0.4445 90)
			(size 0.1524 0.1524)
			(layers "F.Cu" "F.Mask" "F.Paste")
			(net "GND")
			(options
				(clearance outline)
				(anchor circle)
			)
			(primitives
				(gr_poly
					(pts
						(arc
							(start 0.3048 -0.2032)
							(mid 0.275042 -0.275042)
							(end 0.2032 -0.3048)
						)
						(arc
							(start -0.2032 -0.3048)
							(mid -0.275042 -0.275042)
							(end -0.3048 -0.2032)
						)
						(arc
							(start -0.3048 0.2032)
							(mid -0.275042 0.275042)
							(end -0.2032 0.3048)
						)
						(arc
							(start 0.2032 0.3048)
							(mid 0.275042 0.275042)
							(end 0.3048 0.2032)
						)
					)
					(width 0)
					(fill yes)
				)
			)
		)
	)
	(footprint ""
		(layer "F.Cu")
		(at 164.179758 -104.022398)
		(property "Reference" "LED5"
			(at 0 0 0)
			(layer "F.SilkS")
			(hide yes)
			(effects
				(font
					(size 1.27 1.27)
				)
			)
		)
		(property "Value" "LED-YG-51-GP"
			(at -2.6924 -1.4224 0)
			(unlocked yes)
			(layer "F.Fab")
			(hide yes)
			(effects
				(font
					(size 1.016 1.016)
					(thickness 0.1524)
				)
			)
		)
		(property "Device Type" "LED1608AKH40"
			(at -2.6924 -2.9464 0)
			(unlocked yes)
			(layer "F.Fab")
			(hide yes)
			(effects
				(font
					(size 1.016 1.016)
					(thickness 0.1524)
				)
			)
		)
		(duplicate_pad_numbers_are_jumpers no)
		(fp_line
			(start -0.7493 1.651)
			(end -0.7493 1.1811)
			(stroke
				(width 0.3302)
				(type default)
			)
			(layer "F.SilkS")
		)
		(fp_line
			(start -0.6604 -1.3716)
			(end 0.6604 -1.3716)
			(stroke
				(width 0.1524)
				(type default)
			)
			(layer "F.SilkS")
		)
		(fp_line
			(start -0.6604 1.3716)
			(end -0.6604 -1.3716)
			(stroke
				(width 0.1524)
				(type default)
			)
			(layer "F.SilkS")
		)
		(fp_line
			(start -0.5969 1.5494)
			(end 0.5842 1.5494)
			(stroke
				(width 0.508)
				(type default)
			)
			(layer "F.SilkS")
		)
		(fp_line
			(start 0.6604 -1.3716)
			(end 0.6604 1.3716)
			(stroke
				(width 0.1524)
				(type default)
			)
			(layer "F.SilkS")
		)
		(fp_line
			(start 0.6604 1.3716)
			(end -0.6604 1.3716)
			(stroke
				(width 0.1524)
				(type default)
			)
			(layer "F.SilkS")
		)
		(fp_line
			(start 0.7493 1.651)
			(end 0.7493 1.1811)
			(stroke
				(width 0.3302)
				(type default)
			)
			(layer "F.SilkS")
		)
		(fp_rect
			(start -0.6223 1.3335)
			(end 0.6223 -1.3335)
			(stroke
				(width 0)
				(type default)
			)
			(fill no)
			(layer "F.CrtYd")
		)
		(fp_rect
			(start -0.6223 1.3335)
			(end 0.6223 -1.3335)
			(stroke
				(width 0)
				(type default)
			)
			(fill no)
			(layer "F.Fab")
		)
		(pad "A" smd custom
			(at 0 -0.762)
			(size 0.2159 0.2159)
			(layers "F.Cu" "F.Mask" "F.Paste")
			(net "SYS_HB_LED_R")
			(options
				(clearance outline)
				(anchor circle)
			)
			(primitives
				(gr_poly
					(pts
						(arc
							(start -0.3302 -0.4318)
							(mid -0.402042 -0.402042)
							(end -0.4318 -0.3302)
						)
						(arc
							(start -0.4318 0.3302)
							(mid -0.402042 0.402042)
							(end -0.3302 0.4318)
						)
						(arc
							(start 0.3302 0.4318)
							(mid 0.402042 0.402042)
							(end 0.4318 0.3302)
						)
						(arc
							(start 0.4318 -0.3302)
							(mid 0.402042 -0.402042)
							(end 0.3302 -0.4318)
						)
					)
					(width 0)
					(fill yes)
				)
			)
		)
		(pad "K" smd custom
			(at 0 0.762)
			(size 0.2159 0.2159)
			(layers "F.Cu" "F.Mask" "F.Paste")
			(net "SYS_HB_LED_D")
			(options
				(clearance outline)
				(anchor circle)
			)
			(primitives
				(gr_poly
					(pts
						(arc
							(start -0.3302 -0.4318)
							(mid -0.402042 -0.402042)
							(end -0.4318 -0.3302)
						)
						(arc
							(start -0.4318 0.3302)
							(mid -0.402042 0.402042)
							(end -0.3302 0.4318)
						)
						(arc
							(start 0.3302 0.4318)
							(mid 0.402042 0.402042)
							(end 0.4318 0.3302)
						)
						(arc
							(start 0.4318 -0.3302)
							(mid 0.402042 -0.402042)
							(end 0.3302 -0.4318)
						)
					)
					(width 0)
					(fill yes)
				)
			)
		)
	)
	(footprint ""
		(layer "F.Cu")
		(at 61.6966 -172.0596)
		(property "Reference" "R74"
			(at 0 0 0)
			(layer "F.SilkS")
			(hide yes)
			(effects
				(font
					(size 1.27 1.27)
				)
			)
		)
		(property "Value" "0R2J-2-GP"
			(at 0.064008 -3.993896 0)
			(unlocked yes)
			(layer "F.Fab")
			(hide yes)
			(effects
				(font
					(size 1.016 1.016)
					(thickness 0.1524)
				)
			)
		)
		(property "Device Type" "R402H16"
			(at 0.064008 -5.517896 0)
			(unlocked yes)
			(layer "F.Fab")
			(hide yes)
			(effects
				(font
					(size 1.016 1.016)
					(thickness 0.1524)
				)
			)
		)
		(duplicate_pad_numbers_are_jumpers no)
		(fp_line
			(start -0.508 -0.9398)
			(end -0.508 0.9398)
			(stroke
				(width 0.1524)
				(type default)
			)
			(layer "F.SilkS")
		)
		(fp_line
			(start 0.508 -0.9398)
			(end -0.508 -0.9398)
			(stroke
				(width 0.1524)
				(type default)
			)
			(layer "F.SilkS")
		)
		(fp_rect
			(start -0.508 0.9398)
			(end 0.508 -0.9398)
			(stroke
				(width 0)
				(type default)
			)
			(fill no)
			(layer "F.CrtYd")
		)
		(fp_rect
			(start -0.508 0.9398)
			(end 0.508 -0.9398)
			(stroke
				(width 0)
				(type default)
			)
			(fill no)
			(layer "F.Fab")
		)
		(pad "1" smd custom
			(at 0 -0.4445)
			(size 0.1397 0.1397)
			(layers "F.Cu" "F.Mask" "F.Paste")
			(net "FM_TPM_PRSNT_RST_N_C")
			(options
				(clearance outline)
				(anchor circle)
			)
			(primitives
				(gr_poly
					(pts
						(arc
							(start -0.1778 -0.2794)
							(mid -0.249642 -0.249642)
							(end -0.2794 -0.1778)
						)
						(arc
							(start -0.2794 0.1778)
							(mid -0.249642 0.249642)
							(end -0.1778 0.2794)
						)
						(arc
							(start 0.1778 0.2794)
							(mid 0.249642 0.249642)
							(end 0.2794 0.1778)
						)
						(arc
							(start 0.2794 -0.1778)
							(mid 0.249642 -0.249642)
							(end 0.1778 -0.2794)
						)
					)
					(width 0)
					(fill yes)
				)
			)
		)
		(pad "2" smd custom
			(at 0 0.4445)
			(size 0.1397 0.1397)
			(layers "F.Cu" "F.Mask" "F.Paste")
			(net "FM_TPM_PRSNT_RST_N")
			(options
				(clearance outline)
				(anchor circle)
			)
			(primitives
				(gr_poly
					(pts
						(arc
							(start -0.1778 -0.2794)
							(mid -0.249642 -0.249642)
							(end -0.2794 -0.1778)
						)
						(arc
							(start -0.2794 0.1778)
							(mid -0.249642 0.249642)
							(end -0.1778 0.2794)
						)
						(arc
							(start 0.1778 0.2794)
							(mid 0.249642 0.249642)
							(end 0.2794 0.1778)
						)
						(arc
							(start 0.2794 -0.1778)
							(mid 0.249642 -0.249642)
							(end 0.1778 -0.2794)
						)
					)
					(width 0)
					(fill yes)
				)
			)
		)
	)
	(footprint ""
		(layer "F.Cu")
		(at 48.5394 -131.6228 180)
		(property "Reference" "R178"
			(at 0 0 180)
			(layer "F.SilkS")
			(hide yes)
			(effects
				(font
					(size 1.27 1.27)
				)
			)
		)
		(property "Value" "0R2J-2-GP"
			(at 0.064008 -3.993896 180)
			(unlocked yes)
			(layer "F.Fab")
			(hide yes)
			(effects
				(font
					(size 1.016 1.016)
					(thickness 0.1524)
				)
			)
		)
		(property "Device Type" "R402H16"
			(at 0.064008 -5.517896 180)
			(unlocked yes)
			(layer "F.Fab")
			(hide yes)
			(effects
				(font
					(size 1.016 1.016)
					(thickness 0.1524)
				)
			)
		)
		(duplicate_pad_numbers_are_jumpers no)
		(fp_line
			(start 0.508 -0.9398)
			(end -0.508 -0.9398)
			(stroke
				(width 0.1524)
				(type default)
			)
			(layer "F.SilkS")
		)
		(fp_line
			(start -0.508 -0.9398)
			(end -0.508 0.9398)
			(stroke
				(width 0.1524)
				(type default)
			)
			(layer "F.SilkS")
		)
		(fp_rect
			(start -0.508 0.9398)
			(end 0.508 -0.9398)
			(stroke
				(width 0)
				(type default)
			)
			(fill no)
			(layer "F.CrtYd")
		)
		(fp_rect
			(start -0.508 0.9398)
			(end 0.508 -0.9398)
			(stroke
				(width 0)
				(type default)
			)
			(fill no)
			(layer "F.Fab")
		)
		(pad "1" smd custom
			(at 0 -0.4445 180)
			(size 0.1397 0.1397)
			(layers "F.Cu" "F.Mask" "F.Paste")
			(net "I2C_TPM_SDA")
			(options
				(clearance outline)
				(anchor circle)
			)
			(primitives
				(gr_poly
					(pts
						(arc
							(start -0.1778 -0.2794)
							(mid -0.249642 -0.249642)
							(end -0.2794 -0.1778)
						)
						(arc
							(start -0.2794 0.1778)
							(mid -0.249642 0.249642)
							(end -0.1778 0.2794)
						)
						(arc
							(start 0.1778 0.2794)
							(mid 0.249642 0.249642)
							(end 0.2794 0.1778)
						)
						(arc
							(start 0.2794 -0.1778)
							(mid 0.249642 -0.249642)
							(end 0.1778 -0.2794)
						)
					)
					(width 0)
					(fill yes)
				)
			)
		)
		(pad "2" smd custom
			(at 0 0.4445 180)
			(size 0.1397 0.1397)
			(layers "F.Cu" "F.Mask" "F.Paste")
			(net "BMC_SMB14_DAT")
			(options
				(clearance outline)
				(anchor circle)
			)
			(primitives
				(gr_poly
					(pts
						(arc
							(start -0.1778 -0.2794)
							(mid -0.249642 -0.249642)
							(end -0.2794 -0.1778)
						)
						(arc
							(start -0.2794 0.1778)
							(mid -0.249642 0.249642)
							(end -0.1778 0.2794)
						)
						(arc
							(start 0.1778 0.2794)
							(mid 0.249642 0.249642)
							(end 0.2794 0.1778)
						)
						(arc
							(start 0.2794 -0.1778)
							(mid 0.249642 -0.249642)
							(end 0.1778 -0.2794)
						)
					)
					(width 0)
					(fill yes)
				)
			)
		)
	)
	(footprint ""
		(layer "F.Cu")
		(at 90.02776 -123.83262)
		(property "Reference" "R725"
			(at 0 0 0)
			(layer "F.SilkS")
			(hide yes)
			(effects
				(font
					(size 1.27 1.27)
				)
			)
		)
		(property "Value" "4K7R2F-GP"
			(at 0.064008 -3.993896 0)
			(unlocked yes)
			(layer "F.Fab")
			(hide yes)
			(effects
				(font
					(size 1.016 1.016)
					(thickness 0.1524)
				)
			)
		)
		(property "Device Type" "R402H16"
			(at 0.064008 -5.517896 0)
			(unlocked yes)
			(layer "F.Fab")
			(hide yes)
			(effects
				(font
					(size 1.016 1.016)
					(thickness 0.1524)
				)
			)
		)
		(duplicate_pad_numbers_are_jumpers no)
		(fp_line
			(start -0.508 -0.9398)
			(end -0.508 0.9398)
			(stroke
				(width 0.1524)
				(type default)
			)
			(layer "F.SilkS")
		)
		(fp_line
			(start 0.508 -0.9398)
			(end -0.508 -0.9398)
			(stroke
				(width 0.1524)
				(type default)
			)
			(layer "F.SilkS")
		)
		(fp_rect
			(start -0.508 0.9398)
			(end 0.508 -0.9398)
			(stroke
				(width 0)
				(type default)
			)
			(fill no)
			(layer "F.CrtYd")
		)
		(fp_rect
			(start -0.508 0.9398)
			(end 0.508 -0.9398)
			(stroke
				(width 0)
				(type default)
			)
			(fill no)
			(layer "F.Fab")
		)
		(pad "1" smd custom
			(at 0 -0.4445)
			(size 0.1397 0.1397)
			(layers "F.Cu" "F.Mask" "F.Paste")
			(net "P3V3_STBY")
			(options
				(clearance outline)
				(anchor circle)
			)
			(primitives
				(gr_poly
					(pts
						(arc
							(start -0.1778 -0.2794)
							(mid -0.249642 -0.249642)
							(end -0.2794 -0.1778)
						)
						(arc
							(start -0.2794 0.1778)
							(mid -0.249642 0.249642)
							(end -0.1778 0.2794)
						)
						(arc
							(start 0.1778 0.2794)
							(mid 0.249642 0.249642)
							(end 0.2794 0.1778)
						)
						(arc
							(start 0.2794 -0.1778)
							(mid 0.249642 -0.249642)
							(end 0.1778 -0.2794)
						)
					)
					(width 0)
					(fill yes)
				)
			)
		)
		(pad "2" smd custom
			(at 0 0.4445)
			(size 0.1397 0.1397)
			(layers "F.Cu" "F.Mask" "F.Paste")
			(net "UART_COMP_IN_RX")
			(options
				(clearance outline)
				(anchor circle)
			)
			(primitives
				(gr_poly
					(pts
						(arc
							(start -0.1778 -0.2794)
							(mid -0.249642 -0.249642)
							(end -0.2794 -0.1778)
						)
						(arc
							(start -0.2794 0.1778)
							(mid -0.249642 0.249642)
							(end -0.1778 0.2794)
						)
						(arc
							(start 0.1778 0.2794)
							(mid 0.249642 0.249642)
							(end 0.2794 0.1778)
						)
						(arc
							(start 0.2794 -0.1778)
							(mid 0.249642 -0.249642)
							(end 0.1778 -0.2794)
						)
					)
					(width 0)
					(fill yes)
				)
			)
		)
	)
	(footprint ""
		(layer "F.Cu")
		(at 61.3918 -146.5326 -90)
		(property "Reference" "R166"
			(at 0 0 270)
			(layer "F.SilkS")
			(hide yes)
			(effects
				(font
					(size 1.27 1.27)
				)
			)
		)
		(property "Value" "0R2J-2-GP"
			(at 0.064008 -3.993896 270)
			(unlocked yes)
			(layer "F.Fab")
			(hide yes)
			(effects
				(font
					(size 1.016 1.016)
					(thickness 0.1524)
				)
			)
		)
		(property "Device Type" "R402H16"
			(at 0.064008 -5.517896 270)
			(unlocked yes)
			(layer "F.Fab")
			(hide yes)
			(effects
				(font
					(size 1.016 1.016)
					(thickness 0.1524)
				)
			)
		)
		(duplicate_pad_numbers_are_jumpers no)
		(fp_line
			(start -0.508 -0.9398)
			(end -0.508 0.9398)
			(stroke
				(width 0.1524)
				(type default)
			)
			(layer "F.SilkS")
		)
		(fp_line
			(start 0.508 -0.9398)
			(end -0.508 -0.9398)
			(stroke
				(width 0.1524)
				(type default)
			)
			(layer "F.SilkS")
		)
		(fp_rect
			(start -0.508 0.9398)
			(end 0.508 -0.9398)
			(stroke
				(width 0)
				(type default)
			)
			(fill no)
			(layer "F.CrtYd")
		)
		(fp_rect
			(start -0.508 0.9398)
			(end 0.508 -0.9398)
			(stroke
				(width 0)
				(type default)
			)
			(fill no)
			(layer "F.Fab")
		)
		(pad "1" smd custom
			(at 0 -0.4445 270)
			(size 0.1397 0.1397)
			(layers "F.Cu" "F.Mask" "F.Paste")
			(net "I2C_BMC_COMP_SDA_OUT")
			(options
				(clearance outline)
				(anchor circle)
			)
			(primitives
				(gr_poly
					(pts
						(arc
							(start -0.1778 -0.2794)
							(mid -0.249642 -0.249642)
							(end -0.2794 -0.1778)
						)
						(arc
							(start -0.2794 0.1778)
							(mid -0.249642 0.249642)
							(end -0.1778 0.2794)
						)
						(arc
							(start 0.1778 0.2794)
							(mid 0.249642 0.249642)
							(end 0.2794 0.1778)
						)
						(arc
							(start 0.2794 -0.1778)
							(mid 0.249642 -0.249642)
							(end 0.1778 -0.2794)
						)
					)
					(width 0)
					(fill yes)
				)
			)
		)
		(pad "2" smd custom
			(at 0 0.4445 270)
			(size 0.1397 0.1397)
			(layers "F.Cu" "F.Mask" "F.Paste")
			(net "BMC_SMB4_DAT")
			(options
				(clearance outline)
				(anchor circle)
			)
			(primitives
				(gr_poly
					(pts
						(arc
							(start -0.1778 -0.2794)
							(mid -0.249642 -0.249642)
							(end -0.2794 -0.1778)
						)
						(arc
							(start -0.2794 0.1778)
							(mid -0.249642 0.249642)
							(end -0.1778 0.2794)
						)
						(arc
							(start 0.1778 0.2794)
							(mid 0.249642 0.249642)
							(end 0.2794 0.1778)
						)
						(arc
							(start 0.2794 -0.1778)
							(mid 0.249642 -0.249642)
							(end 0.1778 -0.2794)
						)
					)
					(width 0)
					(fill yes)
				)
			)
		)
	)
	(footprint ""
		(layer "F.Cu")
		(at 193.7258 -13.72743)
		(property "Reference" "Q206"
			(at 0 0 0)
			(layer "F.SilkS")
			(hide yes)
			(effects
				(font
					(size 1.27 1.27)
				)
			)
		)
		(property "Value" "SSM6P39TU-GP"
			(at 0.0508 -11.5824 0)
			(unlocked yes)
			(layer "F.Fab")
			(hide yes)
			(effects
				(font
					(size 1.016 1.016)
					(thickness 0.1524)
				)
			)
		)
		(property "Device Type" "UMT6H30"
			(at 0.0508 -13.1572 0)
			(unlocked yes)
			(layer "F.Fab")
			(hide yes)
			(effects
				(font
					(size 1.016 1.016)
					(thickness 0.1524)
				)
			)
		)
		(duplicate_pad_numbers_are_jumpers no)
		(fp_line
			(start -1.27 -0.36449)
			(end -1.27 0.36449)
			(stroke
				(width 0.1524)
				(type default)
			)
			(layer "F.SilkS")
		)
		(fp_line
			(start -1.27 -0.36449)
			(end 1.524 -0.36449)
			(stroke
				(width 0.1524)
				(type default)
			)
			(layer "F.SilkS")
		)
		(fp_line
			(start 1.09347 0)
			(end 1.45796 0.36449)
			(stroke
				(width 0.1524)
				(type default)
			)
			(layer "F.SilkS")
		)
		(fp_line
			(start 1.45796 -0.36449)
			(end 1.09347 0)
			(stroke
				(width 0.1524)
				(type default)
			)
			(layer "F.SilkS")
		)
		(fp_line
			(start 1.524 -0.36449)
			(end 1.45796 -0.36449)
			(stroke
				(width 0.1524)
				(type default)
			)
			(layer "F.SilkS")
		)
		(fp_line
			(start 1.524 -0.36449)
			(end 1.524 -1.82245)
			(stroke
				(width 0.508)
				(type default)
			)
			(layer "F.SilkS")
		)
		(fp_line
			(start 1.524 -0.36449)
			(end 1.524 0.36449)
			(stroke
				(width 0.1524)
				(type default)
			)
			(layer "F.SilkS")
		)
		(fp_line
			(start 1.524 0.36449)
			(end -1.27 0.36449)
			(stroke
				(width 0.1524)
				(type default)
			)
			(layer "F.SilkS")
		)
		(fp_poly
			(pts
				(xy -0.65024 0.36449) (xy -0.65024 -0.36449) (xy 0.65024 -0.36449) (xy 0.65024 0.36449)
			)
			(stroke
				(width 0)
				(type default)
			)
			(fill yes)
			(layer "F.SilkS")
		)
		(fp_poly
			(pts
				(xy 1.016 -1.0668) (xy 1.016 1.0668) (xy -1.016 1.0668) (xy -1.016 -1.0668)
			)
			(stroke
				(width 0)
				(type default)
			)
			(fill no)
			(layer "F.CrtYd")
		)
		(fp_poly
			(pts
				(xy -1.524 1.905) (xy 1.524 1.905) (xy 1.524 -1.06426) (xy 1.016 -1.06426) (xy 1.016 1.0668) (xy -1.016 1.0668)
				(xy -1.016 -1.0668) (xy 1.524 -1.0668) (xy 1.524 -1.905) (xy -1.524 -1.905)
			)
			(stroke
				(width 0)
				(type default)
			)
			(fill no)
			(layer "F.CrtYd")
		)
		(fp_poly
			(pts
				(xy -1.524 -1.905) (xy -1.524 1.905) (xy 1.524 1.905) (xy 1.524 -1.905)
			)
			(stroke
				(width 0)
				(type default)
			)
			(fill no)
			(layer "F.Fab")
		)
		(pad "1" smd rect
			(at 0.65024 -1.02489)
			(size 0.4064 0.8128)
			(layers "F.Cu" "F.Mask" "F.Paste")
			(net "P3V3_STBY")
		)
		(pad "2" smd rect
			(at 0 -1.02489)
			(size 0.4064 0.8128)
			(layers "F.Cu" "F.Mask" "F.Paste")
			(net "EXT1_LED_YELLOW_G1")
		)
		(pad "3" smd rect
			(at -0.65024 -1.02489)
			(size 0.4064 0.8128)
			(layers "F.Cu" "F.Mask" "F.Paste")
			(net "EXT1_LED_BLUE_D")
		)
		(pad "4" smd rect
			(at -0.65024 1.02489)
			(size 0.4064 0.8128)
			(layers "F.Cu" "F.Mask" "F.Paste")
			(net "P5V_STBY")
		)
		(pad "5" smd rect
			(at 0 1.02489)
			(size 0.4064 0.8128)
			(layers "F.Cu" "F.Mask" "F.Paste")
			(net "EXT1_LED_BLUE_G2")
		)
		(pad "6" smd rect
			(at 0.65024 1.02489)
			(size 0.4064 0.8128)
			(layers "F.Cu" "F.Mask" "F.Paste")
			(net "EXT1_LED_YELLOW_D1")
		)
	)
	(footprint ""
		(layer "F.Cu")
		(at 208.055972 -73.3552 90)
		(property "Reference" "C311"
			(at 0 0 90)
			(layer "F.SilkS")
			(hide yes)
			(effects
				(font
					(size 1.27 1.27)
				)
			)
		)
		(property "Value" "SCD01U16V1KX-GP"
			(at -2.8321 -1.7399 90)
			(unlocked yes)
			(layer "F.Fab")
			(hide yes)
			(effects
				(font
					(size 1.016 1.016)
					(thickness 0.1524)
				)
			)
		)
		(property "Device Type" "C0201H13"
			(at -2.8321 -3.2639 90)
			(unlocked yes)
			(layer "F.Fab")
			(hide yes)
			(effects
				(font
					(size 1.016 1.016)
					(thickness 0.1524)
				)
			)
		)
		(duplicate_pad_numbers_are_jumpers no)
		(fp_rect
			(start -0.2794 0.6477)
			(end 0.2794 -0.6477)
			(stroke
				(width 0)
				(type default)
			)
			(fill no)
			(layer "F.CrtYd")
		)
		(fp_rect
			(start -0.2794 0.6477)
			(end 0.2794 -0.6477)
			(stroke
				(width 0)
				(type default)
			)
			(fill no)
			(layer "F.Fab")
		)
		(pad "1" smd custom
			(at 0 -0.2794 90)
			(size 0.0762 0.0762)
			(layers "F.Cu" "F.Mask" "F.Paste")
			(net "PHY_IOC_TO_CON_A_2_DP_C")
			(options
				(clearance outline)
				(anchor circle)
			)
			(primitives
				(gr_poly
					(pts
						(arc
							(start 0.1524 -0.127)
							(mid 0.137521 -0.162921)
							(end 0.1016 -0.1778)
						)
						(arc
							(start -0.1016 -0.1778)
							(mid -0.137521 -0.162921)
							(end -0.1524 -0.127)
						)
						(arc
							(start -0.1524 0.127)
							(mid -0.137521 0.162921)
							(end -0.1016 0.1778)
						)
						(arc
							(start 0.1016 0.1778)
							(mid 0.137521 0.162921)
							(end 0.1524 0.127)
						)
					)
					(width 0)
					(fill yes)
				)
			)
		)
		(pad "2" smd custom
			(at 0 0.2794 90)
			(size 0.0762 0.0762)
			(layers "F.Cu" "F.Mask" "F.Paste")
			(net "PHY_IOC_TO_CON_A_2_DP")
			(options
				(clearance outline)
				(anchor circle)
			)
			(primitives
				(gr_poly
					(pts
						(arc
							(start 0.1524 -0.127)
							(mid 0.137521 -0.162921)
							(end 0.1016 -0.1778)
						)
						(arc
							(start -0.1016 -0.1778)
							(mid -0.137521 -0.162921)
							(end -0.1524 -0.127)
						)
						(arc
							(start -0.1524 0.127)
							(mid -0.137521 0.162921)
							(end -0.1016 0.1778)
						)
						(arc
							(start 0.1016 0.1778)
							(mid 0.137521 0.162921)
							(end 0.1524 0.127)
						)
					)
					(width 0)
					(fill yes)
				)
			)
		)
	)
	(footprint ""
		(layer "F.Cu")
		(at 43.942 -161.3662 180)
		(property "Reference" "R188"
			(at 0 0 180)
			(layer "F.SilkS")
			(hide yes)
			(effects
				(font
					(size 1.27 1.27)
				)
			)
		)
		(property "Value" "2K2R2F-GP"
			(at 0.064008 -3.993896 180)
			(unlocked yes)
			(layer "F.Fab")
			(hide yes)
			(effects
				(font
					(size 1.016 1.016)
					(thickness 0.1524)
				)
			)
		)
		(property "Device Type" "R402H16"
			(at 0.064008 -5.517896 180)
			(unlocked yes)
			(layer "F.Fab")
			(hide yes)
			(effects
				(font
					(size 1.016 1.016)
					(thickness 0.1524)
				)
			)
		)
		(duplicate_pad_numbers_are_jumpers no)
		(fp_line
			(start 0.508 -0.9398)
			(end -0.508 -0.9398)
			(stroke
				(width 0.1524)
				(type default)
			)
			(layer "F.SilkS")
		)
		(fp_line
			(start -0.508 -0.9398)
			(end -0.508 0.9398)
			(stroke
				(width 0.1524)
				(type default)
			)
			(layer "F.SilkS")
		)
		(fp_rect
			(start -0.508 0.9398)
			(end 0.508 -0.9398)
			(stroke
				(width 0)
				(type default)
			)
			(fill no)
			(layer "F.CrtYd")
		)
		(fp_rect
			(start -0.508 0.9398)
			(end 0.508 -0.9398)
			(stroke
				(width 0)
				(type default)
			)
			(fill no)
			(layer "F.Fab")
		)
		(pad "1" smd custom
			(at 0 -0.4445 180)
			(size 0.1397 0.1397)
			(layers "F.Cu" "F.Mask" "F.Paste")
			(net "I2C_M2_1_SDA")
			(options
				(clearance outline)
				(anchor circle)
			)
			(primitives
				(gr_poly
					(pts
						(arc
							(start -0.1778 -0.2794)
							(mid -0.249642 -0.249642)
							(end -0.2794 -0.1778)
						)
						(arc
							(start -0.2794 0.1778)
							(mid -0.249642 0.249642)
							(end -0.1778 0.2794)
						)
						(arc
							(start 0.1778 0.2794)
							(mid 0.249642 0.249642)
							(end 0.2794 0.1778)
						)
						(arc
							(start 0.2794 -0.1778)
							(mid 0.249642 -0.249642)
							(end 0.1778 -0.2794)
						)
					)
					(width 0)
					(fill yes)
				)
			)
		)
		(pad "2" smd custom
			(at 0 0.4445 180)
			(size 0.1397 0.1397)
			(layers "F.Cu" "F.Mask" "F.Paste")
			(net "P3V3_STBY")
			(options
				(clearance outline)
				(anchor circle)
			)
			(primitives
				(gr_poly
					(pts
						(arc
							(start -0.1778 -0.2794)
							(mid -0.249642 -0.249642)
							(end -0.2794 -0.1778)
						)
						(arc
							(start -0.2794 0.1778)
							(mid -0.249642 0.249642)
							(end -0.1778 0.2794)
						)
						(arc
							(start 0.1778 0.2794)
							(mid 0.249642 0.249642)
							(end 0.2794 0.1778)
						)
						(arc
							(start 0.2794 -0.1778)
							(mid 0.249642 -0.249642)
							(end 0.1778 -0.2794)
						)
					)
					(width 0)
					(fill yes)
				)
			)
		)
	)
	(footprint ""
		(layer "F.Cu")
		(at 26.90368 -122.859292 180)
		(property "Reference" "R84"
			(at 0 0 180)
			(layer "F.SilkS")
			(hide yes)
			(effects
				(font
					(size 1.27 1.27)
				)
			)
		)
		(property "Value" "4K7R2F-GP"
			(at 0.064008 -3.993896 180)
			(unlocked yes)
			(layer "F.Fab")
			(hide yes)
			(effects
				(font
					(size 1.016 1.016)
					(thickness 0.1524)
				)
			)
		)
		(property "Device Type" "R402H16"
			(at 0.064008 -5.517896 180)
			(unlocked yes)
			(layer "F.Fab")
			(hide yes)
			(effects
				(font
					(size 1.016 1.016)
					(thickness 0.1524)
				)
			)
		)
		(duplicate_pad_numbers_are_jumpers no)
		(fp_line
			(start 0.508 -0.9398)
			(end -0.508 -0.9398)
			(stroke
				(width 0.1524)
				(type default)
			)
			(layer "F.SilkS")
		)
		(fp_line
			(start -0.508 -0.9398)
			(end -0.508 0.9398)
			(stroke
				(width 0.1524)
				(type default)
			)
			(layer "F.SilkS")
		)
		(fp_rect
			(start -0.508 0.9398)
			(end 0.508 -0.9398)
			(stroke
				(width 0)
				(type default)
			)
			(fill no)
			(layer "F.CrtYd")
		)
		(fp_rect
			(start -0.508 0.9398)
			(end 0.508 -0.9398)
			(stroke
				(width 0)
				(type default)
			)
			(fill no)
			(layer "F.Fab")
		)
		(pad "1" smd custom
			(at 0 -0.4445 180)
			(size 0.1397 0.1397)
			(layers "F.Cu" "F.Mask" "F.Paste")
			(net "P3V3_STBY")
			(options
				(clearance outline)
				(anchor circle)
			)
			(primitives
				(gr_poly
					(pts
						(arc
							(start -0.1778 -0.2794)
							(mid -0.249642 -0.249642)
							(end -0.2794 -0.1778)
						)
						(arc
							(start -0.2794 0.1778)
							(mid -0.249642 0.249642)
							(end -0.1778 0.2794)
						)
						(arc
							(start 0.1778 0.2794)
							(mid 0.249642 0.249642)
							(end 0.2794 0.1778)
						)
						(arc
							(start 0.2794 -0.1778)
							(mid 0.249642 -0.249642)
							(end 0.1778 -0.2794)
						)
					)
					(width 0)
					(fill yes)
				)
			)
		)
		(pad "2" smd custom
			(at 0 0.4445 180)
			(size 0.1397 0.1397)
			(layers "F.Cu" "F.Mask" "F.Paste")
			(net "WP_DISABLE")
			(options
				(clearance outline)
				(anchor circle)
			)
			(primitives
				(gr_poly
					(pts
						(arc
							(start -0.1778 -0.2794)
							(mid -0.249642 -0.249642)
							(end -0.2794 -0.1778)
						)
						(arc
							(start -0.2794 0.1778)
							(mid -0.249642 0.249642)
							(end -0.1778 0.2794)
						)
						(arc
							(start 0.1778 0.2794)
							(mid 0.249642 0.249642)
							(end 0.2794 0.1778)
						)
						(arc
							(start 0.2794 -0.1778)
							(mid 0.249642 -0.249642)
							(end 0.1778 -0.2794)
						)
					)
					(width 0)
					(fill yes)
				)
			)
		)
	)
	(footprint ""
		(layer "F.Cu")
		(at 185.42 -49.9872)
		(property "Reference" "TP162"
			(at 0 0 0)
			(layer "F.SilkS")
			(hide yes)
			(effects
				(font
					(size 1.27 1.27)
				)
			)
		)
		(property "Value" "TPAD28-2-GP"
			(at -0.0127 -1.6637 0)
			(unlocked yes)
			(layer "F.Fab")
			(hide yes)
			(effects
				(font
					(size 1.016 1.016)
					(thickness 0.1524)
				)
			)
		)
		(property "Device Type" "TPAD28"
			(at -0.0127 -3.1877 0)
			(unlocked yes)
			(layer "F.Fab")
			(hide yes)
			(effects
				(font
					(size 1.016 1.016)
					(thickness 0.1524)
				)
			)
		)
		(duplicate_pad_numbers_are_jumpers no)
		(fp_poly
			(pts
				(arc
					(start 0.3556 0)
					(mid -0.3556 0)
					(end 0.3556 0)
				)
			)
			(stroke
				(width 0)
				(type default)
			)
			(fill no)
			(layer "F.CrtYd")
		)
		(fp_poly
			(pts
				(arc
					(start 0.6096 0)
					(mid -0.6096 0)
					(end 0.6096 0)
				)
			)
			(stroke
				(width 0)
				(type default)
			)
			(fill no)
			(layer "F.Fab")
		)
		(pad "1" smd circle
			(at 0 0)
			(size 0.7112 0.7112)
			(layers "F.Cu" "F.Mask" "F.Paste")
			(net "XM_ADDR_0")
		)
	)
	(footprint ""
		(layer "F.Cu")
		(at 36.76904 -121.360946 -90)
		(property "Reference" "SKT1"
			(at 0 0 270)
			(layer "F.SilkS")
			(hide yes)
			(effects
				(font
					(size 1.27 1.27)
				)
			)
		)
		(property "Value" "SKT-SPI16P-GP-U"
			(at -8.9916 4.641596 270)
			(unlocked yes)
			(layer "F.Fab")
			(hide yes)
			(effects
				(font
					(size 1.016 1.016)
					(thickness 0.1524)
				)
			)
		)
		(property "Device Type" "SKT-SOIC16-153139H258"
			(at -8.9916 3.117596 270)
			(unlocked yes)
			(layer "F.Fab")
			(hide yes)
			(effects
				(font
					(size 1.016 1.016)
					(thickness 0.1524)
				)
			)
		)
		(duplicate_pad_numbers_are_jumpers no)
		(fp_line
			(start -7.8994 6.4008)
			(end 7.8994 6.4008)
			(stroke
				(width 0.1524)
				(type default)
			)
			(layer "F.SilkS")
		)
		(fp_line
			(start 7.8994 6.4008)
			(end 7.8994 -6.4008)
			(stroke
				(width 0.1524)
				(type default)
			)
			(layer "F.SilkS")
		)
		(fp_line
			(start 6.7183 0.0762)
			(end 7.8994 1.2573)
			(stroke
				(width 0.1524)
				(type default)
			)
			(layer "F.SilkS")
		)
		(fp_line
			(start 7.8867 -1.0922)
			(end 6.7183 0.0762)
			(stroke
				(width 0.1524)
				(type default)
			)
			(layer "F.SilkS")
		)
		(fp_line
			(start 7.7216 -6.223)
			(end 7.7216 -3.6576)
			(stroke
				(width 0.508)
				(type default)
			)
			(layer "F.SilkS")
		)
		(fp_line
			(start -7.8994 -6.4008)
			(end -7.8994 6.4008)
			(stroke
				(width 0.1524)
				(type default)
			)
			(layer "F.SilkS")
		)
		(fp_line
			(start 7.8994 -6.4008)
			(end -7.8994 -6.4008)
			(stroke
				(width 0.1524)
				(type default)
			)
			(layer "F.SilkS")
		)
		(fp_poly
			(pts
				(xy -4.699 -3.855466) (xy -4.699 3.855466) (xy 4.699 3.855466) (xy 4.699 -3.855466)
			)
			(stroke
				(width 0)
				(type default)
			)
			(fill yes)
			(layer "F.SilkS")
		)
		(fp_rect
			(start -8.1534 11.6078)
			(end 8.1534 6.4008)
			(stroke
				(width 0)
				(type default)
			)
			(fill no)
			(layer "F.CrtYd")
		)
		(fp_rect
			(start -8.1534 -6.4008)
			(end 8.1534 -12.5222)
			(stroke
				(width 0)
				(type default)
			)
			(fill no)
			(layer "F.CrtYd")
		)
		(fp_poly
			(pts
				(xy -8.1534 6.4008) (xy -8.1534 -6.4008) (xy -6.2484 -6.4008) (xy -6.2484 -2.6416) (xy -7.6454 -2.6416)
				(xy -7.6454 2.6416) (xy -6.2484 2.6416) (xy -6.2484 6.4008)
			)
			(stroke
				(width 0)
				(type default)
			)
			(fill no)
			(layer "F.CrtYd")
		)
		(fp_poly
			(pts
				(xy 6.2484 -6.4008) (xy 8.1534 -6.4008) (xy 8.1534 6.4008) (xy 6.2484 6.4008) (xy 6.2484 2.6416)
				(xy 7.6454 2.6416) (xy 7.6454 -2.6416) (xy 6.2484 -2.6416)
			)
			(stroke
				(width 0)
				(type default)
			)
			(fill no)
			(layer "F.CrtYd")
		)
		(fp_poly
			(pts
				(xy 6.2484 -6.4008) (xy -6.2484 -6.4008) (xy -6.2484 -2.6416) (xy -7.6454 -2.6416) (xy -7.6454 2.6416)
				(xy -6.2484 2.6416) (xy -6.2484 6.4008) (xy 6.2484 6.4008) (xy 6.2484 2.6416) (xy 7.6454 2.6416)
				(xy 7.6454 -2.6416) (xy 6.2484 -2.6416)
			)
			(stroke
				(width 0)
				(type default)
			)
			(fill no)
			(layer "F.CrtYd")
		)
		(fp_rect
			(start -8.1534 11.6078)
			(end 8.1534 -12.5222)
			(stroke
				(width 0)
				(type default)
			)
			(fill no)
			(layer "F.Fab")
		)
		(pad "1" smd rect
			(at 4.445 -4.896866 270)
			(size 0.508 1.6764)
			(layers "F.Cu" "F.Mask" "F.Paste")
			(net "FLA0_SPI_HOLD_N")
		)
		(pad "2" smd rect
			(at 3.175 -4.896866 270)
			(size 0.508 1.6764)
			(layers "F.Cu" "F.Mask" "F.Paste")
			(net "P3V3_STBY")
		)
		(pad "3" smd rect
			(at 1.905 -4.896866 270)
			(size 0.508 1.6764)
			(layers "F.Cu" "F.Mask" "F.Paste")
			(net "FLA0_SPI_RST")
		)
		(pad "4" smd rect
			(at 0.635 -4.896866 270)
			(size 0.508 1.6764)
			(layers "F.Cu" "F.Mask" "F.Paste")
			(net "Net_1257")
		)
		(pad "5" smd rect
			(at -0.635 -4.896866 270)
			(size 0.508 1.6764)
			(layers "F.Cu" "F.Mask" "F.Paste")
			(net "Net_1256")
		)
		(pad "6" smd rect
			(at -1.905 -4.896866 270)
			(size 0.508 1.6764)
			(layers "F.Cu" "F.Mask" "F.Paste")
			(net "Net_1255")
		)
		(pad "7" smd rect
			(at -3.175 -4.896866 270)
			(size 0.508 1.6764)
			(layers "F.Cu" "F.Mask" "F.Paste")
			(net "FLA_CS_0_R")
		)
		(pad "8" smd rect
			(at -4.445 -4.896866 270)
			(size 0.508 1.6764)
			(layers "F.Cu" "F.Mask" "F.Paste")
			(net "BMC_SPI_MISO_TPM")
		)
		(pad "9" smd rect
			(at -4.445 4.896866 270)
			(size 0.508 1.6764)
			(layers "F.Cu" "F.Mask" "F.Paste")
			(net "FLA0_WP_N")
		)
		(pad "10" smd rect
			(at -3.175 4.896866 270)
			(size 0.508 1.6764)
			(layers "F.Cu" "F.Mask" "F.Paste")
			(net "GND")
		)
		(pad "11" smd rect
			(at -1.905 4.896866 270)
			(size 0.508 1.6764)
			(layers "F.Cu" "F.Mask" "F.Paste")
			(net "Net_1261")
		)
		(pad "12" smd rect
			(at -0.635 4.896866 270)
			(size 0.508 1.6764)
			(layers "F.Cu" "F.Mask" "F.Paste")
			(net "Net_1260")
		)
		(pad "13" smd rect
			(at 0.635 4.896866 270)
			(size 0.508 1.6764)
			(layers "F.Cu" "F.Mask" "F.Paste")
			(net "Net_1259")
		)
		(pad "14" smd rect
			(at 1.905 4.896866 270)
			(size 0.508 1.6764)
			(layers "F.Cu" "F.Mask" "F.Paste")
			(net "Net_1258")
		)
		(pad "15" smd rect
			(at 3.175 4.896866 270)
			(size 0.508 1.6764)
			(layers "F.Cu" "F.Mask" "F.Paste")
			(net "BMC_SPI_MOSI_R")
		)
		(pad "16" smd rect
			(at 4.445 4.896866 270)
			(size 0.508 1.6764)
			(layers "F.Cu" "F.Mask" "F.Paste")
			(net "BMC_SPI_CLK_R")
		)
	)
	(footprint ""
		(layer "F.Cu")
		(at 220.2815 -102.4636 90)
		(property "Reference" "R604"
			(at 0 0 90)
			(layer "F.SilkS")
			(hide yes)
			(effects
				(font
					(size 1.27 1.27)
				)
			)
		)
		(property "Value" "4K7R2F-GP"
			(at 0.064008 -3.993896 90)
			(unlocked yes)
			(layer "F.Fab")
			(hide yes)
			(effects
				(font
					(size 1.016 1.016)
					(thickness 0.1524)
				)
			)
		)
		(property "Device Type" "R402H16"
			(at 0.064008 -5.517896 90)
			(unlocked yes)
			(layer "F.Fab")
			(hide yes)
			(effects
				(font
					(size 1.016 1.016)
					(thickness 0.1524)
				)
			)
		)
		(duplicate_pad_numbers_are_jumpers no)
		(fp_line
			(start 0.508 -0.9398)
			(end -0.508 -0.9398)
			(stroke
				(width 0.1524)
				(type default)
			)
			(layer "F.SilkS")
		)
		(fp_line
			(start -0.508 -0.9398)
			(end -0.508 0.9398)
			(stroke
				(width 0.1524)
				(type default)
			)
			(layer "F.SilkS")
		)
		(fp_rect
			(start -0.508 0.9398)
			(end 0.508 -0.9398)
			(stroke
				(width 0)
				(type default)
			)
			(fill no)
			(layer "F.CrtYd")
		)
		(fp_rect
			(start -0.508 0.9398)
			(end 0.508 -0.9398)
			(stroke
				(width 0)
				(type default)
			)
			(fill no)
			(layer "F.Fab")
		)
		(pad "1" smd custom
			(at 0 -0.4445 90)
			(size 0.1397 0.1397)
			(layers "F.Cu" "F.Mask" "F.Paste")
			(net "IOC_EEPROM_A1")
			(options
				(clearance outline)
				(anchor circle)
			)
			(primitives
				(gr_poly
					(pts
						(arc
							(start -0.1778 -0.2794)
							(mid -0.249642 -0.249642)
							(end -0.2794 -0.1778)
						)
						(arc
							(start -0.2794 0.1778)
							(mid -0.249642 0.249642)
							(end -0.1778 0.2794)
						)
						(arc
							(start 0.1778 0.2794)
							(mid 0.249642 0.249642)
							(end 0.2794 0.1778)
						)
						(arc
							(start 0.2794 -0.1778)
							(mid 0.249642 -0.249642)
							(end 0.1778 -0.2794)
						)
					)
					(width 0)
					(fill yes)
				)
			)
		)
		(pad "2" smd custom
			(at 0 0.4445 90)
			(size 0.1397 0.1397)
			(layers "F.Cu" "F.Mask" "F.Paste")
			(net "GND")
			(options
				(clearance outline)
				(anchor circle)
			)
			(primitives
				(gr_poly
					(pts
						(arc
							(start -0.1778 -0.2794)
							(mid -0.249642 -0.249642)
							(end -0.2794 -0.1778)
						)
						(arc
							(start -0.2794 0.1778)
							(mid -0.249642 0.249642)
							(end -0.1778 0.2794)
						)
						(arc
							(start 0.1778 0.2794)
							(mid 0.249642 0.249642)
							(end 0.2794 0.1778)
						)
						(arc
							(start 0.2794 -0.1778)
							(mid 0.249642 -0.249642)
							(end 0.1778 -0.2794)
						)
					)
					(width 0)
					(fill yes)
				)
			)
		)
	)
	(footprint ""
		(layer "F.Cu")
		(at 68.7324 -162.306 90)
		(property "Reference" "C52"
			(at 0 0 90)
			(layer "F.SilkS")
			(hide yes)
			(effects
				(font
					(size 1.27 1.27)
				)
			)
		)
		(property "Value" "SCD1U16V2KX-3GP"
			(at 1.1811 -2.7051 90)
			(unlocked yes)
			(layer "F.Fab")
			(hide yes)
			(effects
				(font
					(size 1.016 1.016)
					(thickness 0.1524)
				)
			)
		)
		(property "Device Type" "C402H22"
			(at 1.1811 -4.2291 90)
			(unlocked yes)
			(layer "F.Fab")
			(hide yes)
			(effects
				(font
					(size 1.016 1.016)
					(thickness 0.1524)
				)
			)
		)
		(duplicate_pad_numbers_are_jumpers no)
		(fp_rect
			(start -0.4318 0.9525)
			(end 0.4318 -0.9525)
			(stroke
				(width 0)
				(type default)
			)
			(fill no)
			(layer "F.CrtYd")
		)
		(fp_rect
			(start -0.4318 0.9525)
			(end 0.4318 -0.9525)
			(stroke
				(width 0)
				(type default)
			)
			(fill no)
			(layer "F.Fab")
		)
		(pad "1" smd custom
			(at 0 -0.4445 90)
			(size 0.1524 0.1524)
			(layers "F.Cu" "F.Mask" "F.Paste")
			(net "BMC_TPM_RST_N")
			(options
				(clearance outline)
				(anchor circle)
			)
			(primitives
				(gr_poly
					(pts
						(arc
							(start 0.3048 -0.2032)
							(mid 0.275042 -0.275042)
							(end 0.2032 -0.3048)
						)
						(arc
							(start -0.2032 -0.3048)
							(mid -0.275042 -0.275042)
							(end -0.3048 -0.2032)
						)
						(arc
							(start -0.3048 0.2032)
							(mid -0.275042 0.275042)
							(end -0.2032 0.3048)
						)
						(arc
							(start 0.2032 0.3048)
							(mid 0.275042 0.275042)
							(end 0.3048 0.2032)
						)
					)
					(width 0)
					(fill yes)
				)
			)
		)
		(pad "2" smd custom
			(at 0 0.4445 90)
			(size 0.1524 0.1524)
			(layers "F.Cu" "F.Mask" "F.Paste")
			(net "GND")
			(options
				(clearance outline)
				(anchor circle)
			)
			(primitives
				(gr_poly
					(pts
						(arc
							(start 0.3048 -0.2032)
							(mid 0.275042 -0.275042)
							(end 0.2032 -0.3048)
						)
						(arc
							(start -0.2032 -0.3048)
							(mid -0.275042 -0.275042)
							(end -0.3048 -0.2032)
						)
						(arc
							(start -0.3048 0.2032)
							(mid -0.275042 0.275042)
							(end -0.2032 0.3048)
						)
						(arc
							(start 0.2032 0.3048)
							(mid 0.275042 0.275042)
							(end 0.3048 0.2032)
						)
					)
					(width 0)
					(fill yes)
				)
			)
		)
	)
	(footprint ""
		(layer "F.Cu")
		(at 69.215762 -179.460398 180)
		(property "Reference" "C196"
			(at 0 0 180)
			(layer "F.SilkS")
			(hide yes)
			(effects
				(font
					(size 1.27 1.27)
				)
			)
		)
		(property "Value" "SC470P50V2KX-3GP"
			(at 1.1811 -2.7051 180)
			(unlocked yes)
			(layer "F.Fab")
			(hide yes)
			(effects
				(font
					(size 1.016 1.016)
					(thickness 0.1524)
				)
			)
		)
		(property "Device Type" "C402H22"
			(at 1.1811 -4.2291 180)
			(unlocked yes)
			(layer "F.Fab")
			(hide yes)
			(effects
				(font
					(size 1.016 1.016)
					(thickness 0.1524)
				)
			)
		)
		(duplicate_pad_numbers_are_jumpers no)
		(fp_rect
			(start -0.4318 0.9525)
			(end 0.4318 -0.9525)
			(stroke
				(width 0)
				(type default)
			)
			(fill no)
			(layer "F.CrtYd")
		)
		(fp_rect
			(start -0.4318 0.9525)
			(end 0.4318 -0.9525)
			(stroke
				(width 0)
				(type default)
			)
			(fill no)
			(layer "F.Fab")
		)
		(pad "1" smd custom
			(at 0 -0.4445 180)
			(size 0.1524 0.1524)
			(layers "F.Cu" "F.Mask" "F.Paste")
			(net "GND")
			(options
				(clearance outline)
				(anchor circle)
			)
			(primitives
				(gr_poly
					(pts
						(arc
							(start 0.3048 -0.2032)
							(mid 0.275042 -0.275042)
							(end 0.2032 -0.3048)
						)
						(arc
							(start -0.2032 -0.3048)
							(mid -0.275042 -0.275042)
							(end -0.3048 -0.2032)
						)
						(arc
							(start -0.3048 0.2032)
							(mid -0.275042 0.275042)
							(end -0.2032 0.3048)
						)
						(arc
							(start 0.2032 0.3048)
							(mid 0.275042 0.275042)
							(end 0.3048 0.2032)
						)
					)
					(width 0)
					(fill yes)
				)
			)
		)
		(pad "2" smd custom
			(at 0 0.4445 180)
			(size 0.1524 0.1524)
			(layers "F.Cu" "F.Mask" "F.Paste")
			(net "TPS74801_P2V5_STBY_SS")
			(options
				(clearance outline)
				(anchor circle)
			)
			(primitives
				(gr_poly
					(pts
						(arc
							(start 0.3048 -0.2032)
							(mid 0.275042 -0.275042)
							(end 0.2032 -0.3048)
						)
						(arc
							(start -0.2032 -0.3048)
							(mid -0.275042 -0.275042)
							(end -0.3048 -0.2032)
						)
						(arc
							(start -0.3048 0.2032)
							(mid -0.275042 0.275042)
							(end -0.2032 0.3048)
						)
						(arc
							(start 0.2032 0.3048)
							(mid 0.275042 0.275042)
							(end 0.3048 0.2032)
						)
					)
					(width 0)
					(fill yes)
				)
			)
		)
	)
	(footprint ""
		(layer "F.Cu")
		(at 63.443358 -143.019272 90)
		(property "Reference" "R199"
			(at 0 0 90)
			(layer "F.SilkS")
			(hide yes)
			(effects
				(font
					(size 1.27 1.27)
				)
			)
		)
		(property "Value" "1KR2F-3-GP"
			(at 0.064008 -3.993896 90)
			(unlocked yes)
			(layer "F.Fab")
			(hide yes)
			(effects
				(font
					(size 1.016 1.016)
					(thickness 0.1524)
				)
			)
		)
		(property "Device Type" "R402H16"
			(at 0.064008 -5.517896 90)
			(unlocked yes)
			(layer "F.Fab")
			(hide yes)
			(effects
				(font
					(size 1.016 1.016)
					(thickness 0.1524)
				)
			)
		)
		(duplicate_pad_numbers_are_jumpers no)
		(fp_line
			(start 0.508 -0.9398)
			(end -0.508 -0.9398)
			(stroke
				(width 0.1524)
				(type default)
			)
			(layer "F.SilkS")
		)
		(fp_line
			(start -0.508 -0.9398)
			(end -0.508 0.9398)
			(stroke
				(width 0.1524)
				(type default)
			)
			(layer "F.SilkS")
		)
		(fp_rect
			(start -0.508 0.9398)
			(end 0.508 -0.9398)
			(stroke
				(width 0)
				(type default)
			)
			(fill no)
			(layer "F.CrtYd")
		)
		(fp_rect
			(start -0.508 0.9398)
			(end 0.508 -0.9398)
			(stroke
				(width 0)
				(type default)
			)
			(fill no)
			(layer "F.Fab")
		)
		(pad "1" smd custom
			(at 0 -0.4445 90)
			(size 0.1397 0.1397)
			(layers "F.Cu" "F.Mask" "F.Paste")
			(net "I2C_EXP_RMT_SDA_OUT")
			(options
				(clearance outline)
				(anchor circle)
			)
			(primitives
				(gr_poly
					(pts
						(arc
							(start -0.1778 -0.2794)
							(mid -0.249642 -0.249642)
							(end -0.2794 -0.1778)
						)
						(arc
							(start -0.2794 0.1778)
							(mid -0.249642 0.249642)
							(end -0.1778 0.2794)
						)
						(arc
							(start 0.1778 0.2794)
							(mid 0.249642 0.249642)
							(end 0.2794 0.1778)
						)
						(arc
							(start 0.2794 -0.1778)
							(mid 0.249642 -0.249642)
							(end 0.1778 -0.2794)
						)
					)
					(width 0)
					(fill yes)
				)
			)
		)
		(pad "2" smd custom
			(at 0 0.4445 90)
			(size 0.1397 0.1397)
			(layers "F.Cu" "F.Mask" "F.Paste")
			(net "P3V3_STBY")
			(options
				(clearance outline)
				(anchor circle)
			)
			(primitives
				(gr_poly
					(pts
						(arc
							(start -0.1778 -0.2794)
							(mid -0.249642 -0.249642)
							(end -0.2794 -0.1778)
						)
						(arc
							(start -0.2794 0.1778)
							(mid -0.249642 0.249642)
							(end -0.1778 0.2794)
						)
						(arc
							(start 0.1778 0.2794)
							(mid 0.249642 0.249642)
							(end 0.2794 0.1778)
						)
						(arc
							(start 0.2794 -0.1778)
							(mid 0.249642 -0.249642)
							(end 0.1778 -0.2794)
						)
					)
					(width 0)
					(fill yes)
				)
			)
		)
	)
	(footprint ""
		(layer "F.Cu")
		(at 195.407026 -124.154946 90)
		(property "Reference" "R557"
			(at 0 0 90)
			(layer "F.SilkS")
			(hide yes)
			(effects
				(font
					(size 1.27 1.27)
				)
			)
		)
		(property "Value" "1K21R2F-2-GP"
			(at 0.064008 -3.993896 90)
			(unlocked yes)
			(layer "F.Fab")
			(hide yes)
			(effects
				(font
					(size 1.016 1.016)
					(thickness 0.1524)
				)
			)
		)
		(property "Device Type" "R402H16"
			(at 0.064008 -5.517896 90)
			(unlocked yes)
			(layer "F.Fab")
			(hide yes)
			(effects
				(font
					(size 1.016 1.016)
					(thickness 0.1524)
				)
			)
		)
		(duplicate_pad_numbers_are_jumpers no)
		(fp_line
			(start 0.508 -0.9398)
			(end -0.508 -0.9398)
			(stroke
				(width 0.1524)
				(type default)
			)
			(layer "F.SilkS")
		)
		(fp_line
			(start -0.508 -0.9398)
			(end -0.508 0.9398)
			(stroke
				(width 0.1524)
				(type default)
			)
			(layer "F.SilkS")
		)
		(fp_rect
			(start -0.508 0.9398)
			(end 0.508 -0.9398)
			(stroke
				(width 0)
				(type default)
			)
			(fill no)
			(layer "F.CrtYd")
		)
		(fp_rect
			(start -0.508 0.9398)
			(end 0.508 -0.9398)
			(stroke
				(width 0)
				(type default)
			)
			(fill no)
			(layer "F.Fab")
		)
		(pad "1" smd custom
			(at 0 -0.4445 90)
			(size 0.1397 0.1397)
			(layers "F.Cu" "F.Mask" "F.Paste")
			(net "VT235_VFB")
			(options
				(clearance outline)
				(anchor circle)
			)
			(primitives
				(gr_poly
					(pts
						(arc
							(start -0.1778 -0.2794)
							(mid -0.249642 -0.249642)
							(end -0.2794 -0.1778)
						)
						(arc
							(start -0.2794 0.1778)
							(mid -0.249642 0.249642)
							(end -0.1778 0.2794)
						)
						(arc
							(start 0.1778 0.2794)
							(mid 0.249642 0.249642)
							(end 0.2794 0.1778)
						)
						(arc
							(start 0.2794 -0.1778)
							(mid 0.249642 -0.249642)
							(end 0.1778 -0.2794)
						)
					)
					(width 0)
					(fill yes)
				)
			)
		)
		(pad "2" smd custom
			(at 0 0.4445 90)
			(size 0.1397 0.1397)
			(layers "F.Cu" "F.Mask" "F.Paste")
			(net "VT235_VDES_RC")
			(options
				(clearance outline)
				(anchor circle)
			)
			(primitives
				(gr_poly
					(pts
						(arc
							(start -0.1778 -0.2794)
							(mid -0.249642 -0.249642)
							(end -0.2794 -0.1778)
						)
						(arc
							(start -0.2794 0.1778)
							(mid -0.249642 0.249642)
							(end -0.1778 0.2794)
						)
						(arc
							(start 0.1778 0.2794)
							(mid 0.249642 0.249642)
							(end 0.2794 0.1778)
						)
						(arc
							(start 0.2794 -0.1778)
							(mid 0.249642 -0.249642)
							(end 0.1778 -0.2794)
						)
					)
					(width 0)
					(fill yes)
				)
			)
		)
	)
	(footprint ""
		(layer "F.Cu")
		(at 194.9958 -28.702 90)
		(property "Reference" "C515"
			(at 0 0 90)
			(layer "F.SilkS")
			(hide yes)
			(effects
				(font
					(size 1.27 1.27)
				)
			)
		)
		(property "Value" "SCD1U16V2KX-3GP"
			(at 1.1811 -2.7051 90)
			(unlocked yes)
			(layer "F.Fab")
			(hide yes)
			(effects
				(font
					(size 1.016 1.016)
					(thickness 0.1524)
				)
			)
		)
		(property "Device Type" "C402H22"
			(at 1.1811 -4.2291 90)
			(unlocked yes)
			(layer "F.Fab")
			(hide yes)
			(effects
				(font
					(size 1.016 1.016)
					(thickness 0.1524)
				)
			)
		)
		(duplicate_pad_numbers_are_jumpers no)
		(fp_rect
			(start -0.4318 0.9525)
			(end 0.4318 -0.9525)
			(stroke
				(width 0)
				(type default)
			)
			(fill no)
			(layer "F.CrtYd")
		)
		(fp_rect
			(start -0.4318 0.9525)
			(end 0.4318 -0.9525)
			(stroke
				(width 0)
				(type default)
			)
			(fill no)
			(layer "F.Fab")
		)
		(pad "1" smd custom
			(at 0 -0.4445 90)
			(size 0.1524 0.1524)
			(layers "F.Cu" "F.Mask" "F.Paste")
			(net "P1V8")
			(options
				(clearance outline)
				(anchor circle)
			)
			(primitives
				(gr_poly
					(pts
						(arc
							(start 0.3048 -0.2032)
							(mid 0.275042 -0.275042)
							(end 0.2032 -0.3048)
						)
						(arc
							(start -0.2032 -0.3048)
							(mid -0.275042 -0.275042)
							(end -0.3048 -0.2032)
						)
						(arc
							(start -0.3048 0.2032)
							(mid -0.275042 0.275042)
							(end -0.2032 0.3048)
						)
						(arc
							(start 0.2032 0.3048)
							(mid 0.275042 0.275042)
							(end 0.3048 0.2032)
						)
					)
					(width 0)
					(fill yes)
				)
			)
		)
		(pad "2" smd custom
			(at 0 0.4445 90)
			(size 0.1524 0.1524)
			(layers "F.Cu" "F.Mask" "F.Paste")
			(net "GND")
			(options
				(clearance outline)
				(anchor circle)
			)
			(primitives
				(gr_poly
					(pts
						(arc
							(start 0.3048 -0.2032)
							(mid 0.275042 -0.275042)
							(end 0.2032 -0.3048)
						)
						(arc
							(start -0.2032 -0.3048)
							(mid -0.275042 -0.275042)
							(end -0.3048 -0.2032)
						)
						(arc
							(start -0.3048 0.2032)
							(mid -0.275042 0.275042)
							(end -0.2032 0.3048)
						)
						(arc
							(start 0.2032 0.3048)
							(mid 0.275042 0.275042)
							(end 0.3048 0.2032)
						)
					)
					(width 0)
					(fill yes)
				)
			)
		)
	)
	(footprint ""
		(layer "F.Cu")
		(at 96.1009 -148.108924 180)
		(property "Reference" "R34"
			(at 0 0 180)
			(layer "F.SilkS")
			(hide yes)
			(effects
				(font
					(size 1.27 1.27)
				)
			)
		)
		(property "Value" "4K7R2F-GP"
			(at 0.064008 -3.993896 180)
			(unlocked yes)
			(layer "F.Fab")
			(hide yes)
			(effects
				(font
					(size 1.016 1.016)
					(thickness 0.1524)
				)
			)
		)
		(property "Device Type" "R402H16"
			(at 0.064008 -5.517896 180)
			(unlocked yes)
			(layer "F.Fab")
			(hide yes)
			(effects
				(font
					(size 1.016 1.016)
					(thickness 0.1524)
				)
			)
		)
		(duplicate_pad_numbers_are_jumpers no)
		(fp_line
			(start 0.508 -0.9398)
			(end -0.508 -0.9398)
			(stroke
				(width 0.1524)
				(type default)
			)
			(layer "F.SilkS")
		)
		(fp_line
			(start -0.508 -0.9398)
			(end -0.508 0.9398)
			(stroke
				(width 0.1524)
				(type default)
			)
			(layer "F.SilkS")
		)
		(fp_rect
			(start -0.508 0.9398)
			(end 0.508 -0.9398)
			(stroke
				(width 0)
				(type default)
			)
			(fill no)
			(layer "F.CrtYd")
		)
		(fp_rect
			(start -0.508 0.9398)
			(end 0.508 -0.9398)
			(stroke
				(width 0)
				(type default)
			)
			(fill no)
			(layer "F.Fab")
		)
		(pad "1" smd custom
			(at 0 -0.4445 180)
			(size 0.1397 0.1397)
			(layers "F.Cu" "F.Mask" "F.Paste")
			(net "P3V3_STBY")
			(options
				(clearance outline)
				(anchor circle)
			)
			(primitives
				(gr_poly
					(pts
						(arc
							(start -0.1778 -0.2794)
							(mid -0.249642 -0.249642)
							(end -0.2794 -0.1778)
						)
						(arc
							(start -0.2794 0.1778)
							(mid -0.249642 0.249642)
							(end -0.1778 0.2794)
						)
						(arc
							(start 0.1778 0.2794)
							(mid 0.249642 0.249642)
							(end 0.2794 0.1778)
						)
						(arc
							(start 0.2794 -0.1778)
							(mid 0.249642 -0.249642)
							(end 0.1778 -0.2794)
						)
					)
					(width 0)
					(fill yes)
				)
			)
		)
		(pad "2" smd custom
			(at 0 0.4445 180)
			(size 0.1397 0.1397)
			(layers "F.Cu" "F.Mask" "F.Paste")
			(net "USB_EN_2")
			(options
				(clearance outline)
				(anchor circle)
			)
			(primitives
				(gr_poly
					(pts
						(arc
							(start -0.1778 -0.2794)
							(mid -0.249642 -0.249642)
							(end -0.2794 -0.1778)
						)
						(arc
							(start -0.2794 0.1778)
							(mid -0.249642 0.249642)
							(end -0.1778 0.2794)
						)
						(arc
							(start 0.1778 0.2794)
							(mid 0.249642 0.249642)
							(end 0.2794 0.1778)
						)
						(arc
							(start 0.2794 -0.1778)
							(mid 0.249642 -0.249642)
							(end 0.1778 -0.2794)
						)
					)
					(width 0)
					(fill yes)
				)
			)
		)
	)
	(footprint ""
		(layer "F.Cu")
		(at 99.15017 -173.899576 -90)
		(property "Reference" "R124"
			(at 0 0 270)
			(layer "F.SilkS")
			(hide yes)
			(effects
				(font
					(size 1.27 1.27)
				)
			)
		)
		(property "Value" "0R2J-2-GP"
			(at 0.064008 -3.993896 270)
			(unlocked yes)
			(layer "F.Fab")
			(hide yes)
			(effects
				(font
					(size 1.016 1.016)
					(thickness 0.1524)
				)
			)
		)
		(property "Device Type" "R402H16"
			(at 0.064008 -5.517896 270)
			(unlocked yes)
			(layer "F.Fab")
			(hide yes)
			(effects
				(font
					(size 1.016 1.016)
					(thickness 0.1524)
				)
			)
		)
		(duplicate_pad_numbers_are_jumpers no)
		(fp_line
			(start -0.508 -0.9398)
			(end -0.508 0.9398)
			(stroke
				(width 0.1524)
				(type default)
			)
			(layer "F.SilkS")
		)
		(fp_line
			(start 0.508 -0.9398)
			(end -0.508 -0.9398)
			(stroke
				(width 0.1524)
				(type default)
			)
			(layer "F.SilkS")
		)
		(fp_rect
			(start -0.508 0.9398)
			(end 0.508 -0.9398)
			(stroke
				(width 0)
				(type default)
			)
			(fill no)
			(layer "F.CrtYd")
		)
		(fp_rect
			(start -0.508 0.9398)
			(end 0.508 -0.9398)
			(stroke
				(width 0)
				(type default)
			)
			(fill no)
			(layer "F.Fab")
		)
		(pad "1" smd custom
			(at 0 -0.4445 270)
			(size 0.1397 0.1397)
			(layers "F.Cu" "F.Mask" "F.Paste")
			(net "I2C_DPB_MISC_SCL")
			(options
				(clearance outline)
				(anchor circle)
			)
			(primitives
				(gr_poly
					(pts
						(arc
							(start -0.1778 -0.2794)
							(mid -0.249642 -0.249642)
							(end -0.2794 -0.1778)
						)
						(arc
							(start -0.2794 0.1778)
							(mid -0.249642 0.249642)
							(end -0.1778 0.2794)
						)
						(arc
							(start 0.1778 0.2794)
							(mid 0.249642 0.249642)
							(end 0.2794 0.1778)
						)
						(arc
							(start 0.2794 -0.1778)
							(mid 0.249642 -0.249642)
							(end 0.1778 -0.2794)
						)
					)
					(width 0)
					(fill yes)
				)
			)
		)
		(pad "2" smd custom
			(at 0 0.4445 270)
			(size 0.1397 0.1397)
			(layers "F.Cu" "F.Mask" "F.Paste")
			(net "I2C_DPB_MISC_SCL_R")
			(options
				(clearance outline)
				(anchor circle)
			)
			(primitives
				(gr_poly
					(pts
						(arc
							(start -0.1778 -0.2794)
							(mid -0.249642 -0.249642)
							(end -0.2794 -0.1778)
						)
						(arc
							(start -0.2794 0.1778)
							(mid -0.249642 0.249642)
							(end -0.1778 0.2794)
						)
						(arc
							(start 0.1778 0.2794)
							(mid 0.249642 0.249642)
							(end 0.2794 0.1778)
						)
						(arc
							(start 0.2794 -0.1778)
							(mid 0.249642 -0.249642)
							(end 0.1778 -0.2794)
						)
					)
					(width 0)
					(fill yes)
				)
			)
		)
	)
	(footprint ""
		(layer "F.Cu")
		(at 28.194 -152.654 -90)
		(property "Reference" "R769"
			(at 0 0 270)
			(layer "F.SilkS")
			(hide yes)
			(effects
				(font
					(size 1.27 1.27)
				)
			)
		)
		(property "Value" "0R2J-2-GP"
			(at 0.064008 -3.993896 270)
			(unlocked yes)
			(layer "F.Fab")
			(hide yes)
			(effects
				(font
					(size 1.016 1.016)
					(thickness 0.1524)
				)
			)
		)
		(property "Device Type" "R402H16"
			(at 0.064008 -5.517896 270)
			(unlocked yes)
			(layer "F.Fab")
			(hide yes)
			(effects
				(font
					(size 1.016 1.016)
					(thickness 0.1524)
				)
			)
		)
		(duplicate_pad_numbers_are_jumpers no)
		(fp_line
			(start -0.508 -0.9398)
			(end -0.508 0.9398)
			(stroke
				(width 0.1524)
				(type default)
			)
			(layer "F.SilkS")
		)
		(fp_line
			(start 0.508 -0.9398)
			(end -0.508 -0.9398)
			(stroke
				(width 0.1524)
				(type default)
			)
			(layer "F.SilkS")
		)
		(fp_rect
			(start -0.508 0.9398)
			(end 0.508 -0.9398)
			(stroke
				(width 0)
				(type default)
			)
			(fill no)
			(layer "F.CrtYd")
		)
		(fp_rect
			(start -0.508 0.9398)
			(end 0.508 -0.9398)
			(stroke
				(width 0)
				(type default)
			)
			(fill no)
			(layer "F.Fab")
		)
		(pad "1" smd custom
			(at 0 -0.4445 270)
			(size 0.1397 0.1397)
			(layers "F.Cu" "F.Mask" "F.Paste")
			(net "DEBUG_GPIO_BMC_R_2")
			(options
				(clearance outline)
				(anchor circle)
			)
			(primitives
				(gr_poly
					(pts
						(arc
							(start -0.1778 -0.2794)
							(mid -0.249642 -0.249642)
							(end -0.2794 -0.1778)
						)
						(arc
							(start -0.2794 0.1778)
							(mid -0.249642 0.249642)
							(end -0.1778 0.2794)
						)
						(arc
							(start 0.1778 0.2794)
							(mid 0.249642 0.249642)
							(end 0.2794 0.1778)
						)
						(arc
							(start 0.2794 -0.1778)
							(mid 0.249642 -0.249642)
							(end 0.1778 -0.2794)
						)
					)
					(width 0)
					(fill yes)
				)
			)
		)
		(pad "2" smd custom
			(at 0 0.4445 270)
			(size 0.1397 0.1397)
			(layers "F.Cu" "F.Mask" "F.Paste")
			(net "DEBUG_GPIO_BMC_2")
			(options
				(clearance outline)
				(anchor circle)
			)
			(primitives
				(gr_poly
					(pts
						(arc
							(start -0.1778 -0.2794)
							(mid -0.249642 -0.249642)
							(end -0.2794 -0.1778)
						)
						(arc
							(start -0.2794 0.1778)
							(mid -0.249642 0.249642)
							(end -0.1778 0.2794)
						)
						(arc
							(start 0.1778 0.2794)
							(mid 0.249642 0.249642)
							(end 0.2794 0.1778)
						)
						(arc
							(start 0.2794 -0.1778)
							(mid 0.249642 -0.249642)
							(end 0.1778 -0.2794)
						)
					)
					(width 0)
					(fill yes)
				)
			)
		)
	)
	(footprint ""
		(layer "F.Cu")
		(at 28.321 -157.734 -90)
		(property "Reference" "R773"
			(at 0 0 270)
			(layer "F.SilkS")
			(hide yes)
			(effects
				(font
					(size 1.27 1.27)
				)
			)
		)
		(property "Value" "0R2J-2-GP"
			(at 0.064008 -3.993896 270)
			(unlocked yes)
			(layer "F.Fab")
			(hide yes)
			(effects
				(font
					(size 1.016 1.016)
					(thickness 0.1524)
				)
			)
		)
		(property "Device Type" "R402H16"
			(at 0.064008 -5.517896 270)
			(unlocked yes)
			(layer "F.Fab")
			(hide yes)
			(effects
				(font
					(size 1.016 1.016)
					(thickness 0.1524)
				)
			)
		)
		(duplicate_pad_numbers_are_jumpers no)
		(fp_line
			(start -0.508 -0.9398)
			(end -0.508 0.9398)
			(stroke
				(width 0.1524)
				(type default)
			)
			(layer "F.SilkS")
		)
		(fp_line
			(start 0.508 -0.9398)
			(end -0.508 -0.9398)
			(stroke
				(width 0.1524)
				(type default)
			)
			(layer "F.SilkS")
		)
		(fp_rect
			(start -0.508 0.9398)
			(end 0.508 -0.9398)
			(stroke
				(width 0)
				(type default)
			)
			(fill no)
			(layer "F.CrtYd")
		)
		(fp_rect
			(start -0.508 0.9398)
			(end 0.508 -0.9398)
			(stroke
				(width 0)
				(type default)
			)
			(fill no)
			(layer "F.Fab")
		)
		(pad "1" smd custom
			(at 0 -0.4445 270)
			(size 0.1397 0.1397)
			(layers "F.Cu" "F.Mask" "F.Paste")
			(net "DEBUG_GPIO_BMC_R_6")
			(options
				(clearance outline)
				(anchor circle)
			)
			(primitives
				(gr_poly
					(pts
						(arc
							(start -0.1778 -0.2794)
							(mid -0.249642 -0.249642)
							(end -0.2794 -0.1778)
						)
						(arc
							(start -0.2794 0.1778)
							(mid -0.249642 0.249642)
							(end -0.1778 0.2794)
						)
						(arc
							(start 0.1778 0.2794)
							(mid 0.249642 0.249642)
							(end 0.2794 0.1778)
						)
						(arc
							(start 0.2794 -0.1778)
							(mid 0.249642 -0.249642)
							(end 0.1778 -0.2794)
						)
					)
					(width 0)
					(fill yes)
				)
			)
		)
		(pad "2" smd custom
			(at 0 0.4445 270)
			(size 0.1397 0.1397)
			(layers "F.Cu" "F.Mask" "F.Paste")
			(net "DEBUG_GPIO_BMC_6")
			(options
				(clearance outline)
				(anchor circle)
			)
			(primitives
				(gr_poly
					(pts
						(arc
							(start -0.1778 -0.2794)
							(mid -0.249642 -0.249642)
							(end -0.2794 -0.1778)
						)
						(arc
							(start -0.2794 0.1778)
							(mid -0.249642 0.249642)
							(end -0.1778 0.2794)
						)
						(arc
							(start 0.1778 0.2794)
							(mid 0.249642 0.249642)
							(end 0.2794 0.1778)
						)
						(arc
							(start 0.2794 -0.1778)
							(mid 0.249642 -0.249642)
							(end 0.1778 -0.2794)
						)
					)
					(width 0)
					(fill yes)
				)
			)
		)
	)
	(footprint ""
		(layer "F.Cu")
		(at 78.122018 -77.353668 90)
		(property "Reference" "VIA3"
			(at 0 0 90)
			(layer "F.SilkS")
			(hide yes)
			(effects
				(font
					(size 1.27 1.27)
				)
			)
		)
		(property "Value" "85OHM-8L-1D6MM-L16L18-GP"
			(at 4.064 0.6096 90)
			(unlocked yes)
			(layer "F.Fab")
			(hide yes)
			(effects
				(font
					(size 1.016 1.016)
					(thickness 0.1524)
				)
			)
		)
		(property "Device Type" "VIA-PCIE-4P-368076"
			(at 4.064 -0.9144 90)
			(unlocked yes)
			(layer "F.Fab")
			(hide yes)
			(effects
				(font
					(size 1.016 1.016)
					(thickness 0.1524)
				)
			)
		)
		(duplicate_pad_numbers_are_jumpers no)
		(fp_rect
			(start -1.8415 0.381)
			(end 1.8415 -0.381)
			(stroke
				(width 0)
				(type default)
			)
			(fill no)
			(layer "F.CrtYd")
		)
		(fp_rect
			(start -1.8415 0.381)
			(end 1.8415 -0.381)
			(stroke
				(width 0)
				(type default)
			)
			(fill no)
			(layer "F.Fab")
		)
		(pad "1" thru_hole circle
			(at -1.4605 0 90)
			(size 0.508 0.508)
			(drill 0.254)
			(layers "*.Cu" "*.Mask")
			(remove_unused_layers no)
			(net "GND")
			(clearance 0.127)
			(thermal_gap 0.127)
		)
		(pad "2" thru_hole circle
			(at -0.4445 0 90)
			(size 0.508 0.508)
			(drill 0.254)
			(layers "*.Cu" "*.Mask")
			(remove_unused_layers no)
			(net "PCIE_COMP_TO_IOM_18_DP")
			(clearance 0.127)
			(thermal_gap 0.127)
		)
		(pad "3" thru_hole circle
			(at 0.4445 0 90)
			(size 0.508 0.508)
			(drill 0.254)
			(layers "*.Cu" "*.Mask")
			(remove_unused_layers no)
			(net "PCIE_COMP_TO_IOM_18_DN")
			(clearance 0.127)
			(thermal_gap 0.127)
		)
		(pad "4" thru_hole circle
			(at 1.4605 0 90)
			(size 0.508 0.508)
			(drill 0.254)
			(layers "*.Cu" "*.Mask")
			(remove_unused_layers no)
			(net "GND")
			(clearance 0.127)
			(thermal_gap 0.127)
		)
	)
	(footprint ""
		(layer "F.Cu")
		(at 88.222074 -61.534294 -90)
		(property "Reference" "R5"
			(at 0 0 270)
			(layer "F.SilkS")
			(hide yes)
			(effects
				(font
					(size 1.27 1.27)
				)
			)
		)
		(property "Value" "0R2J-2-GP"
			(at 0.064008 -3.993896 270)
			(unlocked yes)
			(layer "F.Fab")
			(hide yes)
			(effects
				(font
					(size 1.016 1.016)
					(thickness 0.1524)
				)
			)
		)
		(property "Device Type" "R402H16"
			(at 0.064008 -5.517896 270)
			(unlocked yes)
			(layer "F.Fab")
			(hide yes)
			(effects
				(font
					(size 1.016 1.016)
					(thickness 0.1524)
				)
			)
		)
		(duplicate_pad_numbers_are_jumpers no)
		(fp_line
			(start -0.508 -0.9398)
			(end -0.508 0.9398)
			(stroke
				(width 0.1524)
				(type default)
			)
			(layer "F.SilkS")
		)
		(fp_line
			(start 0.508 -0.9398)
			(end -0.508 -0.9398)
			(stroke
				(width 0.1524)
				(type default)
			)
			(layer "F.SilkS")
		)
		(fp_rect
			(start -0.508 0.9398)
			(end 0.508 -0.9398)
			(stroke
				(width 0)
				(type default)
			)
			(fill no)
			(layer "F.CrtYd")
		)
		(fp_rect
			(start -0.508 0.9398)
			(end 0.508 -0.9398)
			(stroke
				(width 0)
				(type default)
			)
			(fill no)
			(layer "F.Fab")
		)
		(pad "1" smd custom
			(at 0 -0.4445 270)
			(size 0.1397 0.1397)
			(layers "F.Cu" "F.Mask" "F.Paste")
			(net "NCSI_RCSDV")
			(options
				(clearance outline)
				(anchor circle)
			)
			(primitives
				(gr_poly
					(pts
						(arc
							(start -0.1778 -0.2794)
							(mid -0.249642 -0.249642)
							(end -0.2794 -0.1778)
						)
						(arc
							(start -0.2794 0.1778)
							(mid -0.249642 0.249642)
							(end -0.1778 0.2794)
						)
						(arc
							(start 0.1778 0.2794)
							(mid 0.249642 0.249642)
							(end 0.2794 0.1778)
						)
						(arc
							(start 0.2794 -0.1778)
							(mid 0.249642 -0.249642)
							(end 0.1778 -0.2794)
						)
					)
					(width 0)
					(fill yes)
				)
			)
		)
		(pad "2" smd custom
			(at 0 0.4445 270)
			(size 0.1397 0.1397)
			(layers "F.Cu" "F.Mask" "F.Paste")
			(net "NCSI_RCSDV_R")
			(options
				(clearance outline)
				(anchor circle)
			)
			(primitives
				(gr_poly
					(pts
						(arc
							(start -0.1778 -0.2794)
							(mid -0.249642 -0.249642)
							(end -0.2794 -0.1778)
						)
						(arc
							(start -0.2794 0.1778)
							(mid -0.249642 0.249642)
							(end -0.1778 0.2794)
						)
						(arc
							(start 0.1778 0.2794)
							(mid 0.249642 0.249642)
							(end 0.2794 0.1778)
						)
						(arc
							(start 0.2794 -0.1778)
							(mid 0.249642 -0.249642)
							(end 0.1778 -0.2794)
						)
					)
					(width 0)
					(fill yes)
				)
			)
		)
	)
	(footprint ""
		(layer "F.Cu")
		(at 92.386404 -46.654974 90)
		(property "Reference" "PQ2"
			(at 0 0 90)
			(layer "F.SilkS")
			(hide yes)
			(effects
				(font
					(size 1.27 1.27)
				)
			)
		)
		(property "Value" "2N7002K-1-GP"
			(at 0.127 -8.9662 90)
			(unlocked yes)
			(layer "F.Fab")
			(hide yes)
			(effects
				(font
					(size 1.016 1.016)
					(thickness 0.1524)
				)
			)
		)
		(property "Device Type" "SOT23DGS2D4H44"
			(at 0.127 -10.4902 90)
			(unlocked yes)
			(layer "F.Fab")
			(hide yes)
			(effects
				(font
					(size 1.016 1.016)
					(thickness 0.1524)
				)
			)
		)
		(duplicate_pad_numbers_are_jumpers no)
		(fp_line
			(start 1.651 -1.778)
			(end -1.651 -1.778)
			(stroke
				(width 0.1524)
				(type default)
			)
			(layer "F.SilkS")
		)
		(fp_line
			(start -1.651 -1.778)
			(end -1.651 1.778)
			(stroke
				(width 0.1524)
				(type default)
			)
			(layer "F.SilkS")
		)
		(fp_line
			(start 1.651 1.778)
			(end 1.651 -1.778)
			(stroke
				(width 0.1524)
				(type default)
			)
			(layer "F.SilkS")
		)
		(fp_line
			(start -1.651 1.778)
			(end 1.651 1.778)
			(stroke
				(width 0.1524)
				(type default)
			)
			(layer "F.SilkS")
		)
		(fp_poly
			(pts
				(xy -1.778 1.8796) (xy -1.778 -1.8796) (xy 1.778 -1.8796) (xy 1.778 1.8796)
			)
			(stroke
				(width 0)
				(type default)
			)
			(fill no)
			(layer "F.CrtYd")
		)
		(fp_poly
			(pts
				(xy -1.778 1.8796) (xy -1.778 -1.8796) (xy 1.778 -1.8796) (xy 1.778 1.8796)
			)
			(stroke
				(width 0)
				(type default)
			)
			(fill no)
			(layer "F.Fab")
		)
		(pad "D" smd custom
			(at 0 -0.9525 90)
			(size 0.1905 0.1905)
			(layers "F.Cu" "F.Mask" "F.Paste")
			(net "PQ2_D")
			(options
				(clearance outline)
				(anchor circle)
			)
			(primitives
				(gr_poly
					(pts
						(arc
							(start -0.1778 0.5715)
							(mid -0.321484 0.511984)
							(end -0.381 0.3683)
						)
						(arc
							(start -0.381 -0.3683)
							(mid -0.321484 -0.511984)
							(end -0.1778 -0.5715)
						)
						(arc
							(start 0.1778 -0.5715)
							(mid 0.321484 -0.511984)
							(end 0.381 -0.3683)
						)
						(arc
							(start 0.381 0.3683)
							(mid 0.321484 0.511984)
							(end 0.1778 0.5715)
						)
					)
					(width 0)
					(fill yes)
				)
			)
		)
		(pad "G" smd custom
			(at -0.98425 0.9525 90)
			(size 0.1905 0.1905)
			(layers "F.Cu" "F.Mask" "F.Paste")
			(net "PQ2_G")
			(options
				(clearance outline)
				(anchor circle)
			)
			(primitives
				(gr_poly
					(pts
						(arc
							(start -0.1778 0.5715)
							(mid -0.321484 0.511984)
							(end -0.381 0.3683)
						)
						(arc
							(start -0.381 -0.3683)
							(mid -0.321484 -0.511984)
							(end -0.1778 -0.5715)
						)
						(arc
							(start 0.1778 -0.5715)
							(mid 0.321484 -0.511984)
							(end 0.381 -0.3683)
						)
						(arc
							(start 0.381 0.3683)
							(mid 0.321484 0.511984)
							(end 0.1778 0.5715)
						)
					)
					(width 0)
					(fill yes)
				)
			)
		)
		(pad "S" smd custom
			(at 0.98425 0.9525 90)
			(size 0.1905 0.1905)
			(layers "F.Cu" "F.Mask" "F.Paste")
			(net "P3V3_EN_R")
			(options
				(clearance outline)
				(anchor circle)
			)
			(primitives
				(gr_poly
					(pts
						(arc
							(start -0.1778 0.5715)
							(mid -0.321484 0.511984)
							(end -0.381 0.3683)
						)
						(arc
							(start -0.381 -0.3683)
							(mid -0.321484 -0.511984)
							(end -0.1778 -0.5715)
						)
						(arc
							(start 0.1778 -0.5715)
							(mid 0.321484 -0.511984)
							(end 0.381 -0.3683)
						)
						(arc
							(start 0.381 0.3683)
							(mid 0.321484 0.511984)
							(end 0.1778 0.5715)
						)
					)
					(width 0)
					(fill yes)
				)
			)
		)
	)
	(footprint ""
		(layer "F.Cu")
		(at 66.394584 -160.038034 -90)
		(property "Reference" "R774"
			(at 0 0 270)
			(layer "F.SilkS")
			(hide yes)
			(effects
				(font
					(size 1.27 1.27)
				)
			)
		)
		(property "Value" "1KR2F-3-GP"
			(at 0.064008 -3.993896 270)
			(unlocked yes)
			(layer "F.Fab")
			(hide yes)
			(effects
				(font
					(size 1.016 1.016)
					(thickness 0.1524)
				)
			)
		)
		(property "Device Type" "R402H16"
			(at 0.064008 -5.517896 270)
			(unlocked yes)
			(layer "F.Fab")
			(hide yes)
			(effects
				(font
					(size 1.016 1.016)
					(thickness 0.1524)
				)
			)
		)
		(duplicate_pad_numbers_are_jumpers no)
		(fp_line
			(start -0.508 -0.9398)
			(end -0.508 0.9398)
			(stroke
				(width 0.1524)
				(type default)
			)
			(layer "F.SilkS")
		)
		(fp_line
			(start 0.508 -0.9398)
			(end -0.508 -0.9398)
			(stroke
				(width 0.1524)
				(type default)
			)
			(layer "F.SilkS")
		)
		(fp_rect
			(start -0.508 0.9398)
			(end 0.508 -0.9398)
			(stroke
				(width 0)
				(type default)
			)
			(fill no)
			(layer "F.CrtYd")
		)
		(fp_rect
			(start -0.508 0.9398)
			(end 0.508 -0.9398)
			(stroke
				(width 0)
				(type default)
			)
			(fill no)
			(layer "F.Fab")
		)
		(pad "1" smd custom
			(at 0 -0.4445 270)
			(size 0.1397 0.1397)
			(layers "F.Cu" "F.Mask" "F.Paste")
			(net "P1V15_STBY")
			(options
				(clearance outline)
				(anchor circle)
			)
			(primitives
				(gr_poly
					(pts
						(arc
							(start -0.1778 -0.2794)
							(mid -0.249642 -0.249642)
							(end -0.2794 -0.1778)
						)
						(arc
							(start -0.2794 0.1778)
							(mid -0.249642 0.249642)
							(end -0.1778 0.2794)
						)
						(arc
							(start 0.1778 0.2794)
							(mid 0.249642 0.249642)
							(end 0.2794 0.1778)
						)
						(arc
							(start 0.2794 -0.1778)
							(mid 0.249642 -0.249642)
							(end 0.1778 -0.2794)
						)
					)
					(width 0)
					(fill yes)
				)
			)
		)
		(pad "2" smd custom
			(at 0 0.4445 270)
			(size 0.1397 0.1397)
			(layers "F.Cu" "F.Mask" "F.Paste")
			(net "ADC_P1V15_STBY")
			(options
				(clearance outline)
				(anchor circle)
			)
			(primitives
				(gr_poly
					(pts
						(arc
							(start -0.1778 -0.2794)
							(mid -0.249642 -0.249642)
							(end -0.2794 -0.1778)
						)
						(arc
							(start -0.2794 0.1778)
							(mid -0.249642 0.249642)
							(end -0.1778 0.2794)
						)
						(arc
							(start 0.1778 0.2794)
							(mid 0.249642 0.249642)
							(end 0.2794 0.1778)
						)
						(arc
							(start 0.2794 -0.1778)
							(mid 0.249642 -0.249642)
							(end 0.1778 -0.2794)
						)
					)
					(width 0)
					(fill yes)
				)
			)
		)
	)
	(footprint ""
		(layer "F.Cu")
		(at 66.276474 -175.088296)
		(property "Reference" "U10"
			(at 0 0 0)
			(layer "F.SilkS")
			(hide yes)
			(effects
				(font
					(size 1.27 1.27)
				)
			)
		)
		(property "Value" "LMV331IDCKRG4-GP"
			(at -2.3368 -8.6868 0)
			(unlocked yes)
			(layer "F.Fab")
			(hide yes)
			(effects
				(font
					(size 1.016 1.016)
					(thickness 0.1524)
				)
			)
		)
		(property "Device Type" "SC70-5H44"
			(at -2.3114 -10.414 0)
			(unlocked yes)
			(layer "F.Fab")
			(hide yes)
			(effects
				(font
					(size 1.016 1.016)
					(thickness 0.1524)
				)
			)
		)
		(duplicate_pad_numbers_are_jumpers no)
		(fp_line
			(start -1.27 -1.7018)
			(end 1.27 -1.7018)
			(stroke
				(width 0.1524)
				(type default)
			)
			(layer "F.SilkS")
		)
		(fp_line
			(start -1.27 1.7018)
			(end -1.27 -1.7018)
			(stroke
				(width 0.1524)
				(type default)
			)
			(layer "F.SilkS")
		)
		(fp_line
			(start 0.6604 -1.8034)
			(end 1.3843 -1.8034)
			(stroke
				(width 0.3302)
				(type default)
			)
			(layer "F.SilkS")
		)
		(fp_line
			(start 1.27 -1.7018)
			(end 1.27 1.7018)
			(stroke
				(width 0.1524)
				(type default)
			)
			(layer "F.SilkS")
		)
		(fp_line
			(start 1.27 1.7018)
			(end -1.27 1.7018)
			(stroke
				(width 0.1524)
				(type default)
			)
			(layer "F.SilkS")
		)
		(fp_line
			(start 1.3843 -1.8034)
			(end 1.3843 -1.1176)
			(stroke
				(width 0.3302)
				(type default)
			)
			(layer "F.SilkS")
		)
		(fp_rect
			(start -1.524 1.9558)
			(end 1.524 -1.9558)
			(stroke
				(width 0)
				(type default)
			)
			(fill no)
			(layer "F.CrtYd")
		)
		(fp_poly
			(pts
				(xy -1.524 -1.9558) (xy 1.524 -1.9558) (xy 1.524 1.9558) (xy -1.524 1.9558)
			)
			(stroke
				(width 0)
				(type default)
			)
			(fill no)
			(layer "F.Fab")
		)
		(pad "1" smd rect
			(at 0.65024 -0.8255)
			(size 0.4064 1.2192)
			(layers "F.Cu" "F.Mask" "F.Paste")
			(net "FM_TPM_PRSNT_RST_N")
		)
		(pad "2" smd rect
			(at 0 -0.8255)
			(size 0.4064 1.2192)
			(layers "F.Cu" "F.Mask" "F.Paste")
			(net "GND")
		)
		(pad "3" smd rect
			(at -0.65024 -0.8255)
			(size 0.4064 1.2192)
			(layers "F.Cu" "F.Mask" "F.Paste")
			(net "VREF_2V2")
		)
		(pad "4" smd rect
			(at -0.65024 0.8255)
			(size 0.4064 1.2192)
			(layers "F.Cu" "F.Mask" "F.Paste")
			(net "FM_TPM_PRSNT_N")
		)
		(pad "5" smd rect
			(at 0.65024 0.8255)
			(size 0.4064 1.2192)
			(layers "F.Cu" "F.Mask" "F.Paste")
			(net "P5V_STBY")
		)
	)
	(footprint ""
		(layer "F.Cu")
		(at 92.342462 -121.402348 180)
		(property "Reference" "R797"
			(at 0 0 180)
			(layer "F.SilkS")
			(hide yes)
			(effects
				(font
					(size 1.27 1.27)
				)
			)
		)
		(property "Value" "0R2J-2-GP"
			(at 0.064008 -3.993896 180)
			(unlocked yes)
			(layer "F.Fab")
			(hide yes)
			(effects
				(font
					(size 1.016 1.016)
					(thickness 0.1524)
				)
			)
		)
		(property "Device Type" "R402H16"
			(at 0.064008 -5.517896 180)
			(unlocked yes)
			(layer "F.Fab")
			(hide yes)
			(effects
				(font
					(size 1.016 1.016)
					(thickness 0.1524)
				)
			)
		)
		(duplicate_pad_numbers_are_jumpers no)
		(fp_line
			(start 0.508 -0.9398)
			(end -0.508 -0.9398)
			(stroke
				(width 0.1524)
				(type default)
			)
			(layer "F.SilkS")
		)
		(fp_line
			(start -0.508 -0.9398)
			(end -0.508 0.9398)
			(stroke
				(width 0.1524)
				(type default)
			)
			(layer "F.SilkS")
		)
		(fp_rect
			(start -0.508 0.9398)
			(end 0.508 -0.9398)
			(stroke
				(width 0)
				(type default)
			)
			(fill no)
			(layer "F.CrtYd")
		)
		(fp_rect
			(start -0.508 0.9398)
			(end 0.508 -0.9398)
			(stroke
				(width 0)
				(type default)
			)
			(fill no)
			(layer "F.Fab")
		)
		(pad "1" smd custom
			(at 0 -0.4445 180)
			(size 0.1397 0.1397)
			(layers "F.Cu" "F.Mask" "F.Paste")
			(net "UART_BMC_COMP_IN_RX")
			(options
				(clearance outline)
				(anchor circle)
			)
			(primitives
				(gr_poly
					(pts
						(arc
							(start -0.1778 -0.2794)
							(mid -0.249642 -0.249642)
							(end -0.2794 -0.1778)
						)
						(arc
							(start -0.2794 0.1778)
							(mid -0.249642 0.249642)
							(end -0.1778 0.2794)
						)
						(arc
							(start 0.1778 0.2794)
							(mid 0.249642 0.249642)
							(end 0.2794 0.1778)
						)
						(arc
							(start 0.2794 -0.1778)
							(mid 0.249642 -0.249642)
							(end 0.1778 -0.2794)
						)
					)
					(width 0)
					(fill yes)
				)
			)
		)
		(pad "2" smd custom
			(at 0 0.4445 180)
			(size 0.1397 0.1397)
			(layers "F.Cu" "F.Mask" "F.Paste")
			(net "UART_BMC_COMP_IN_RX_R")
			(options
				(clearance outline)
				(anchor circle)
			)
			(primitives
				(gr_poly
					(pts
						(arc
							(start -0.1778 -0.2794)
							(mid -0.249642 -0.249642)
							(end -0.2794 -0.1778)
						)
						(arc
							(start -0.2794 0.1778)
							(mid -0.249642 0.249642)
							(end -0.1778 0.2794)
						)
						(arc
							(start 0.1778 0.2794)
							(mid 0.249642 0.249642)
							(end 0.2794 0.1778)
						)
						(arc
							(start 0.2794 -0.1778)
							(mid 0.249642 -0.249642)
							(end 0.1778 -0.2794)
						)
					)
					(width 0)
					(fill yes)
				)
			)
		)
	)
	(footprint ""
		(layer "F.Cu")
		(at 25.682702 -132.353558 180)
		(property "Reference" "R232"
			(at 0 0 180)
			(layer "F.SilkS")
			(hide yes)
			(effects
				(font
					(size 1.27 1.27)
				)
			)
		)
		(property "Value" "120R2F-GP"
			(at 0.064008 -3.993896 180)
			(unlocked yes)
			(layer "F.Fab")
			(hide yes)
			(effects
				(font
					(size 1.016 1.016)
					(thickness 0.1524)
				)
			)
		)
		(property "Device Type" "R402H16"
			(at 0.064008 -5.517896 180)
			(unlocked yes)
			(layer "F.Fab")
			(hide yes)
			(effects
				(font
					(size 1.016 1.016)
					(thickness 0.1524)
				)
			)
		)
		(duplicate_pad_numbers_are_jumpers no)
		(fp_line
			(start 0.508 -0.9398)
			(end -0.508 -0.9398)
			(stroke
				(width 0.1524)
				(type default)
			)
			(layer "F.SilkS")
		)
		(fp_line
			(start -0.508 -0.9398)
			(end -0.508 0.9398)
			(stroke
				(width 0.1524)
				(type default)
			)
			(layer "F.SilkS")
		)
		(fp_rect
			(start -0.508 0.9398)
			(end 0.508 -0.9398)
			(stroke
				(width 0)
				(type default)
			)
			(fill no)
			(layer "F.CrtYd")
		)
		(fp_rect
			(start -0.508 0.9398)
			(end 0.508 -0.9398)
			(stroke
				(width 0)
				(type default)
			)
			(fill no)
			(layer "F.Fab")
		)
		(pad "1" smd custom
			(at 0 -0.4445 180)
			(size 0.1397 0.1397)
			(layers "F.Cu" "F.Mask" "F.Paste")
			(net "MEMBA_1")
			(options
				(clearance outline)
				(anchor circle)
			)
			(primitives
				(gr_poly
					(pts
						(arc
							(start -0.1778 -0.2794)
							(mid -0.249642 -0.249642)
							(end -0.2794 -0.1778)
						)
						(arc
							(start -0.2794 0.1778)
							(mid -0.249642 0.249642)
							(end -0.1778 0.2794)
						)
						(arc
							(start 0.1778 0.2794)
							(mid 0.249642 0.249642)
							(end 0.2794 0.1778)
						)
						(arc
							(start 0.2794 -0.1778)
							(mid 0.249642 -0.249642)
							(end 0.1778 -0.2794)
						)
					)
					(width 0)
					(fill yes)
				)
			)
		)
		(pad "2" smd custom
			(at 0 0.4445 180)
			(size 0.1397 0.1397)
			(layers "F.Cu" "F.Mask" "F.Paste")
			(net "P1V2_STBY")
			(options
				(clearance outline)
				(anchor circle)
			)
			(primitives
				(gr_poly
					(pts
						(arc
							(start -0.1778 -0.2794)
							(mid -0.249642 -0.249642)
							(end -0.2794 -0.1778)
						)
						(arc
							(start -0.2794 0.1778)
							(mid -0.249642 0.249642)
							(end -0.1778 0.2794)
						)
						(arc
							(start 0.1778 0.2794)
							(mid 0.249642 0.249642)
							(end 0.2794 0.1778)
						)
						(arc
							(start 0.2794 -0.1778)
							(mid 0.249642 -0.249642)
							(end 0.1778 -0.2794)
						)
					)
					(width 0)
					(fill yes)
				)
			)
		)
	)
	(footprint ""
		(layer "F.Cu")
		(at 90.424 -26.8478 90)
		(property "Reference" "L23"
			(at 0 0 90)
			(layer "F.SilkS")
			(hide yes)
			(effects
				(font
					(size 1.27 1.27)
				)
			)
		)
		(property "Value" "BLM21PG300SN-2GP"
			(at 0.0254 -5.6896 90)
			(unlocked yes)
			(layer "F.Fab")
			(hide yes)
			(effects
				(font
					(size 1.016 1.016)
					(thickness 0.1524)
				)
			)
		)
		(property "Device Type" "L20125H42"
			(at 0.0254 -7.5946 90)
			(unlocked yes)
			(layer "F.Fab")
			(hide yes)
			(effects
				(font
					(size 1.016 1.016)
					(thickness 0.1524)
				)
			)
		)
		(duplicate_pad_numbers_are_jumpers no)
		(fp_line
			(start 0.9144 -1.7018)
			(end -0.9144 -1.7018)
			(stroke
				(width 0.1524)
				(type default)
			)
			(layer "F.SilkS")
		)
		(fp_line
			(start -0.9144 -1.7018)
			(end -0.9144 1.7018)
			(stroke
				(width 0.1524)
				(type default)
			)
			(layer "F.SilkS")
		)
		(fp_line
			(start 0.9144 1.7018)
			(end 0.9144 -1.7018)
			(stroke
				(width 0.1524)
				(type default)
			)
			(layer "F.SilkS")
		)
		(fp_line
			(start -0.9144 1.7018)
			(end 0.9144 1.7018)
			(stroke
				(width 0.1524)
				(type default)
			)
			(layer "F.SilkS")
		)
		(fp_rect
			(start -1.0033 1.778)
			(end 1.0033 -1.778)
			(stroke
				(width 0)
				(type default)
			)
			(fill no)
			(layer "F.CrtYd")
		)
		(fp_poly
			(pts
				(xy -1.0033 -1.778) (xy 1.0033 -1.778) (xy 1.0033 1.778) (xy -1.0033 1.778)
			)
			(stroke
				(width 0)
				(type default)
			)
			(fill no)
			(layer "F.Fab")
		)
		(pad "1" smd rect
			(at 0 -0.9652 90)
			(size 1.397 1.143)
			(layers "F.Cu" "F.Mask" "F.Paste")
			(net "P5V_VBUS_CONN")
		)
		(pad "2" smd rect
			(at 0 0.9652 90)
			(size 1.397 1.143)
			(layers "F.Cu" "F.Mask" "F.Paste")
			(net "P5V_USB")
		)
	)
	(footprint ""
		(layer "F.Cu")
		(at 31.70428 -186.992514 180)
		(property "Reference" "C173"
			(at 0 0 180)
			(layer "F.SilkS")
			(hide yes)
			(effects
				(font
					(size 1.27 1.27)
				)
			)
		)
		(property "Value" "SC10U16V5KX-7-GP-U"
			(at -0.0762 -6.1214 180)
			(unlocked yes)
			(layer "F.Fab")
			(hide yes)
			(effects
				(font
					(size 1.016 1.016)
					(thickness 0.1524)
				)
			)
		)
		(property "Device Type" "C805H58"
			(at -0.0762 -8.1534 180)
			(unlocked yes)
			(layer "F.Fab")
			(hide yes)
			(effects
				(font
					(size 1.016 1.016)
					(thickness 0.1524)
				)
			)
		)
		(duplicate_pad_numbers_are_jumpers no)
		(fp_line
			(start 0.635 0)
			(end -0.635 0)
			(stroke
				(width 0.508)
				(type default)
			)
			(layer "F.SilkS")
		)
		(fp_rect
			(start -0.9652 1.778)
			(end 0.9652 -1.778)
			(stroke
				(width 0)
				(type default)
			)
			(fill no)
			(layer "F.CrtYd")
		)
		(fp_poly
			(pts
				(xy -0.9652 -1.778) (xy 0.9652 -1.778) (xy 0.9652 1.778) (xy -0.9652 1.778)
			)
			(stroke
				(width 0)
				(type default)
			)
			(fill no)
			(layer "F.Fab")
		)
		(pad "1" smd rect
			(at 0 -0.9652 180)
			(size 1.397 1.143)
			(layers "F.Cu" "F.Mask" "F.Paste")
			(net "P12V_STBY_VIN_PU2")
		)
		(pad "2" smd rect
			(at 0 0.9652 180)
			(size 1.397 1.143)
			(layers "F.Cu" "F.Mask" "F.Paste")
			(net "GND")
		)
	)
	(footprint ""
		(layer "F.Cu")
		(at 45.432726 -131.748022 180)
		(property "Reference" "R264"
			(at 0 0 180)
			(layer "F.SilkS")
			(hide yes)
			(effects
				(font
					(size 1.27 1.27)
				)
			)
		)
		(property "Value" "4K7R2F-GP"
			(at 0.064008 -3.993896 180)
			(unlocked yes)
			(layer "F.Fab")
			(hide yes)
			(effects
				(font
					(size 1.016 1.016)
					(thickness 0.1524)
				)
			)
		)
		(property "Device Type" "R402H16"
			(at 0.064008 -5.517896 180)
			(unlocked yes)
			(layer "F.Fab")
			(hide yes)
			(effects
				(font
					(size 1.016 1.016)
					(thickness 0.1524)
				)
			)
		)
		(duplicate_pad_numbers_are_jumpers no)
		(fp_line
			(start 0.508 -0.9398)
			(end -0.508 -0.9398)
			(stroke
				(width 0.1524)
				(type default)
			)
			(layer "F.SilkS")
		)
		(fp_line
			(start -0.508 -0.9398)
			(end -0.508 0.9398)
			(stroke
				(width 0.1524)
				(type default)
			)
			(layer "F.SilkS")
		)
		(fp_rect
			(start -0.508 0.9398)
			(end 0.508 -0.9398)
			(stroke
				(width 0)
				(type default)
			)
			(fill no)
			(layer "F.CrtYd")
		)
		(fp_rect
			(start -0.508 0.9398)
			(end 0.508 -0.9398)
			(stroke
				(width 0)
				(type default)
			)
			(fill no)
			(layer "F.Fab")
		)
		(pad "1" smd custom
			(at 0 -0.4445 180)
			(size 0.1397 0.1397)
			(layers "F.Cu" "F.Mask" "F.Paste")
			(net "P3V3_STBY")
			(options
				(clearance outline)
				(anchor circle)
			)
			(primitives
				(gr_poly
					(pts
						(arc
							(start -0.1778 -0.2794)
							(mid -0.249642 -0.249642)
							(end -0.2794 -0.1778)
						)
						(arc
							(start -0.2794 0.1778)
							(mid -0.249642 0.249642)
							(end -0.1778 0.2794)
						)
						(arc
							(start 0.1778 0.2794)
							(mid 0.249642 0.249642)
							(end 0.2794 0.1778)
						)
						(arc
							(start 0.2794 -0.1778)
							(mid 0.249642 -0.249642)
							(end 0.1778 -0.2794)
						)
					)
					(width 0)
					(fill yes)
				)
			)
		)
		(pad "2" smd custom
			(at 0 0.4445 180)
			(size 0.1397 0.1397)
			(layers "F.Cu" "F.Mask" "F.Paste")
			(net "BMC_GPIOY2")
			(options
				(clearance outline)
				(anchor circle)
			)
			(primitives
				(gr_poly
					(pts
						(arc
							(start -0.1778 -0.2794)
							(mid -0.249642 -0.249642)
							(end -0.2794 -0.1778)
						)
						(arc
							(start -0.2794 0.1778)
							(mid -0.249642 0.249642)
							(end -0.1778 0.2794)
						)
						(arc
							(start 0.1778 0.2794)
							(mid 0.249642 0.249642)
							(end 0.2794 0.1778)
						)
						(arc
							(start 0.2794 -0.1778)
							(mid 0.249642 -0.249642)
							(end 0.1778 -0.2794)
						)
					)
					(width 0)
					(fill yes)
				)
			)
		)
	)
	(footprint ""
		(layer "F.Cu")
		(at 160.69564 -132.471922 -90)
		(property "Reference" "C207"
			(at 0 0 270)
			(layer "F.SilkS")
			(hide yes)
			(effects
				(font
					(size 1.27 1.27)
				)
			)
		)
		(property "Value" "SCD1U50V3KX-GP"
			(at 0 -2.8194 270)
			(unlocked yes)
			(layer "F.Fab")
			(hide yes)
			(effects
				(font
					(size 1.016 1.016)
					(thickness 0.1524)
				)
			)
		)
		(property "Device Type" "C603H36"
			(at 0 -4.3434 270)
			(unlocked yes)
			(layer "F.Fab")
			(hide yes)
			(effects
				(font
					(size 1.016 1.016)
					(thickness 0.1524)
				)
			)
		)
		(duplicate_pad_numbers_are_jumpers no)
		(fp_line
			(start 0.508 0)
			(end -0.508 0)
			(stroke
				(width 0.2032)
				(type default)
			)
			(layer "F.SilkS")
		)
		(fp_rect
			(start -0.5842 1.3335)
			(end 0.5842 -1.3335)
			(stroke
				(width 0)
				(type default)
			)
			(fill no)
			(layer "F.CrtYd")
		)
		(fp_rect
			(start -0.5842 1.3335)
			(end 0.5842 -1.3335)
			(stroke
				(width 0)
				(type default)
			)
			(fill no)
			(layer "F.Fab")
		)
		(pad "1" smd custom
			(at 0 -0.762 270)
			(size 0.2159 0.2159)
			(layers "F.Cu" "F.Mask" "F.Paste")
			(net "P1V8_STBY_VBST_RR")
			(options
				(clearance outline)
				(anchor circle)
			)
			(primitives
				(gr_poly
					(pts
						(arc
							(start -0.3302 -0.4318)
							(mid -0.402042 -0.402042)
							(end -0.4318 -0.3302)
						)
						(arc
							(start -0.4318 0.3302)
							(mid -0.402042 0.402042)
							(end -0.3302 0.4318)
						)
						(arc
							(start 0.3302 0.4318)
							(mid 0.402042 0.402042)
							(end 0.4318 0.3302)
						)
						(arc
							(start 0.4318 -0.3302)
							(mid 0.402042 -0.402042)
							(end 0.3302 -0.4318)
						)
					)
					(width 0)
					(fill yes)
				)
			)
		)
		(pad "2" smd custom
			(at 0 0.762 270)
			(size 0.2159 0.2159)
			(layers "F.Cu" "F.Mask" "F.Paste")
			(net "P1V8_STBY_SW")
			(options
				(clearance outline)
				(anchor circle)
			)
			(primitives
				(gr_poly
					(pts
						(arc
							(start -0.3302 -0.4318)
							(mid -0.402042 -0.402042)
							(end -0.4318 -0.3302)
						)
						(arc
							(start -0.4318 0.3302)
							(mid -0.402042 0.402042)
							(end -0.3302 0.4318)
						)
						(arc
							(start 0.3302 0.4318)
							(mid 0.402042 0.402042)
							(end 0.4318 0.3302)
						)
						(arc
							(start 0.4318 -0.3302)
							(mid 0.402042 -0.402042)
							(end 0.3302 -0.4318)
						)
					)
					(width 0)
					(fill yes)
				)
			)
		)
	)
	(footprint ""
		(layer "F.Cu")
		(at 41.8592 -161.3662)
		(property "Reference" "R309"
			(at 0 0 0)
			(layer "F.SilkS")
			(hide yes)
			(effects
				(font
					(size 1.27 1.27)
				)
			)
		)
		(property "Value" "4K7R2F-GP"
			(at 0.064008 -3.993896 0)
			(unlocked yes)
			(layer "F.Fab")
			(hide yes)
			(effects
				(font
					(size 1.016 1.016)
					(thickness 0.1524)
				)
			)
		)
		(property "Device Type" "R402H16"
			(at 0.064008 -5.517896 0)
			(unlocked yes)
			(layer "F.Fab")
			(hide yes)
			(effects
				(font
					(size 1.016 1.016)
					(thickness 0.1524)
				)
			)
		)
		(duplicate_pad_numbers_are_jumpers no)
		(fp_line
			(start -0.508 -0.9398)
			(end -0.508 0.9398)
			(stroke
				(width 0.1524)
				(type default)
			)
			(layer "F.SilkS")
		)
		(fp_line
			(start 0.508 -0.9398)
			(end -0.508 -0.9398)
			(stroke
				(width 0.1524)
				(type default)
			)
			(layer "F.SilkS")
		)
		(fp_rect
			(start -0.508 0.9398)
			(end 0.508 -0.9398)
			(stroke
				(width 0)
				(type default)
			)
			(fill no)
			(layer "F.CrtYd")
		)
		(fp_rect
			(start -0.508 0.9398)
			(end 0.508 -0.9398)
			(stroke
				(width 0)
				(type default)
			)
			(fill no)
			(layer "F.Fab")
		)
		(pad "1" smd custom
			(at 0 -0.4445)
			(size 0.1397 0.1397)
			(layers "F.Cu" "F.Mask" "F.Paste")
			(net "P3V3_STBY")
			(options
				(clearance outline)
				(anchor circle)
			)
			(primitives
				(gr_poly
					(pts
						(arc
							(start -0.1778 -0.2794)
							(mid -0.249642 -0.249642)
							(end -0.2794 -0.1778)
						)
						(arc
							(start -0.2794 0.1778)
							(mid -0.249642 0.249642)
							(end -0.1778 0.2794)
						)
						(arc
							(start 0.1778 0.2794)
							(mid 0.249642 0.249642)
							(end 0.2794 0.1778)
						)
						(arc
							(start 0.2794 -0.1778)
							(mid 0.249642 -0.249642)
							(end 0.1778 -0.2794)
						)
					)
					(width 0)
					(fill yes)
				)
			)
		)
		(pad "2" smd custom
			(at 0 0.4445)
			(size 0.1397 0.1397)
			(layers "F.Cu" "F.Mask" "F.Paste")
			(net "BOARD_REV_0")
			(options
				(clearance outline)
				(anchor circle)
			)
			(primitives
				(gr_poly
					(pts
						(arc
							(start -0.1778 -0.2794)
							(mid -0.249642 -0.249642)
							(end -0.2794 -0.1778)
						)
						(arc
							(start -0.2794 0.1778)
							(mid -0.249642 0.249642)
							(end -0.1778 0.2794)
						)
						(arc
							(start 0.1778 0.2794)
							(mid 0.249642 0.249642)
							(end 0.2794 0.1778)
						)
						(arc
							(start 0.2794 -0.1778)
							(mid 0.249642 -0.249642)
							(end 0.1778 -0.2794)
						)
					)
					(width 0)
					(fill yes)
				)
			)
		)
	)
	(footprint ""
		(layer "F.Cu")
		(at 41.450006 -169.999914)
		(property "Reference" "NUT1"
			(at 0 0 0)
			(layer "F.SilkS")
			(hide yes)
			(effects
				(font
					(size 1.27 1.27)
				)
			)
		)
		(property "Value" "STF256R168H278-GP"
			(at -4.826 0.0508 0)
			(unlocked yes)
			(layer "F.Fab")
			(hide yes)
			(effects
				(font
					(size 1.016 1.016)
					(thickness 0.1524)
				)
			)
		)
		(property "Device Type" "STF256R168H278"
			(at -4.826 -1.4732 0)
			(unlocked yes)
			(layer "F.Fab")
			(hide yes)
			(effects
				(font
					(size 1.016 1.016)
					(thickness 0.1524)
				)
			)
		)
		(duplicate_pad_numbers_are_jumpers no)
		(fp_circle
			(center 0 0)
			(end 3.6068 0)
			(stroke
				(width 0.3048)
				(type default)
			)
			(fill no)
			(layer "F.SilkS")
		)
		(fp_poly
			(pts
				(arc
					(start 3.7592 0)
					(mid -3.7592 0)
					(end 3.7592 0)
				)
			)
			(stroke
				(width 0)
				(type default)
			)
			(fill no)
			(layer "B.CrtYd")
		)
		(fp_poly
			(pts
				(arc
					(start 2.5019 0)
					(mid -2.5019 0)
					(end 2.5019 0)
				)
			)
			(stroke
				(width 0)
				(type default)
			)
			(fill no)
			(layer "F.CrtYd")
		)
		(fp_poly
			(pts
				(arc
					(start 3.7592 0.00635)
					(mid -3.759205 0)
					(end 3.7592 -0.00635)
				)
				(arc
					(start 2.5019 -0.00635)
					(mid -2.501908 0)
					(end 2.5019 0.00635)
				)
			)
			(stroke
				(width 0)
				(type default)
			)
			(fill no)
			(layer "F.CrtYd")
		)
		(fp_poly
			(pts
				(arc
					(start 3.7592 0)
					(mid -3.7592 0)
					(end 3.7592 0)
				)
			)
			(stroke
				(width 0)
				(type default)
			)
			(fill no)
			(layer "B.Fab")
		)
		(fp_poly
			(pts
				(arc
					(start 3.7592 0)
					(mid -3.7592 0)
					(end 3.7592 0)
				)
			)
			(stroke
				(width 0)
				(type default)
			)
			(fill no)
			(layer "F.Fab")
		)
		(pad "1" thru_hole circle
			(at 0 0)
			(size 6.5024 6.5024)
			(drill 4.2672)
			(layers "*.Cu" "*.Mask")
			(remove_unused_layers no)
			(net "Net_97")
			(clearance -0.6096)
			(thermal_gap 0.3048)
			(padstack
				(mode front_inner_back)
				(layer "Inner"
					(shape circle)
					(size 4.6736 4.6736)
					(clearance 0.3048)
				)
				(layer "B.Cu"
					(shape circle)
					(size 6.5024 6.5024)
					(clearance -0.6096)
				)
			)
		)
	)
	(footprint ""
		(layer "F.Cu")
		(at 24.042116 -162.3441 90)
		(property "Reference" "C225"
			(at 0 0 90)
			(layer "F.SilkS")
			(hide yes)
			(effects
				(font
					(size 1.27 1.27)
				)
			)
		)
		(property "Value" "SC10U6D3V5KX-4GP"
			(at -0.0762 -6.1214 90)
			(unlocked yes)
			(layer "F.Fab")
			(hide yes)
			(effects
				(font
					(size 1.016 1.016)
					(thickness 0.1524)
				)
			)
		)
		(property "Device Type" "C805H58"
			(at -0.0762 -8.1534 90)
			(unlocked yes)
			(layer "F.Fab")
			(hide yes)
			(effects
				(font
					(size 1.016 1.016)
					(thickness 0.1524)
				)
			)
		)
		(duplicate_pad_numbers_are_jumpers no)
		(fp_line
			(start 0.635 0)
			(end -0.635 0)
			(stroke
				(width 0.508)
				(type default)
			)
			(layer "F.SilkS")
		)
		(fp_rect
			(start -0.9652 1.778)
			(end 0.9652 -1.778)
			(stroke
				(width 0)
				(type default)
			)
			(fill no)
			(layer "F.CrtYd")
		)
		(fp_poly
			(pts
				(xy -0.9652 -1.778) (xy 0.9652 -1.778) (xy 0.9652 1.778) (xy -0.9652 1.778)
			)
			(stroke
				(width 0)
				(type default)
			)
			(fill no)
			(layer "F.Fab")
		)
		(pad "1" smd rect
			(at 0 -0.9652 90)
			(size 1.397 1.143)
			(layers "F.Cu" "F.Mask" "F.Paste")
			(net "TPS74801_P1V2_STBY_OUT")
		)
		(pad "2" smd rect
			(at 0 0.9652 90)
			(size 1.397 1.143)
			(layers "F.Cu" "F.Mask" "F.Paste")
			(net "GND")
		)
	)
	(footprint ""
		(layer "F.Cu")
		(at 23.2537 -167.221916 180)
		(property "Reference" "C224"
			(at 0 0 180)
			(layer "F.SilkS")
			(hide yes)
			(effects
				(font
					(size 1.27 1.27)
				)
			)
		)
		(property "Value" "SC10U6D3V5KX-4GP"
			(at -0.0762 -6.1214 180)
			(unlocked yes)
			(layer "F.Fab")
			(hide yes)
			(effects
				(font
					(size 1.016 1.016)
					(thickness 0.1524)
				)
			)
		)
		(property "Device Type" "C805H58"
			(at -0.0762 -8.1534 180)
			(unlocked yes)
			(layer "F.Fab")
			(hide yes)
			(effects
				(font
					(size 1.016 1.016)
					(thickness 0.1524)
				)
			)
		)
		(duplicate_pad_numbers_are_jumpers no)
		(fp_line
			(start 0.635 0)
			(end -0.635 0)
			(stroke
				(width 0.508)
				(type default)
			)
			(layer "F.SilkS")
		)
		(fp_rect
			(start -0.9652 1.778)
			(end 0.9652 -1.778)
			(stroke
				(width 0)
				(type default)
			)
			(fill no)
			(layer "F.CrtYd")
		)
		(fp_poly
			(pts
				(xy -0.9652 -1.778) (xy 0.9652 -1.778) (xy 0.9652 1.778) (xy -0.9652 1.778)
			)
			(stroke
				(width 0)
				(type default)
			)
			(fill no)
			(layer "F.Fab")
		)
		(pad "1" smd rect
			(at 0 -0.9652 180)
			(size 1.397 1.143)
			(layers "F.Cu" "F.Mask" "F.Paste")
			(net "TPS74801_P1V2_STBY_OUT")
		)
		(pad "2" smd rect
			(at 0 0.9652 180)
			(size 1.397 1.143)
			(layers "F.Cu" "F.Mask" "F.Paste")
			(net "GND")
		)
	)
	(footprint ""
		(layer "F.Cu")
		(at 44.9834 -161.3662 180)
		(property "Reference" "R187"
			(at 0 0 180)
			(layer "F.SilkS")
			(hide yes)
			(effects
				(font
					(size 1.27 1.27)
				)
			)
		)
		(property "Value" "2K2R2F-GP"
			(at 0.064008 -3.993896 180)
			(unlocked yes)
			(layer "F.Fab")
			(hide yes)
			(effects
				(font
					(size 1.016 1.016)
					(thickness 0.1524)
				)
			)
		)
		(property "Device Type" "R402H16"
			(at 0.064008 -5.517896 180)
			(unlocked yes)
			(layer "F.Fab")
			(hide yes)
			(effects
				(font
					(size 1.016 1.016)
					(thickness 0.1524)
				)
			)
		)
		(duplicate_pad_numbers_are_jumpers no)
		(fp_line
			(start 0.508 -0.9398)
			(end -0.508 -0.9398)
			(stroke
				(width 0.1524)
				(type default)
			)
			(layer "F.SilkS")
		)
		(fp_line
			(start -0.508 -0.9398)
			(end -0.508 0.9398)
			(stroke
				(width 0.1524)
				(type default)
			)
			(layer "F.SilkS")
		)
		(fp_rect
			(start -0.508 0.9398)
			(end 0.508 -0.9398)
			(stroke
				(width 0)
				(type default)
			)
			(fill no)
			(layer "F.CrtYd")
		)
		(fp_rect
			(start -0.508 0.9398)
			(end 0.508 -0.9398)
			(stroke
				(width 0)
				(type default)
			)
			(fill no)
			(layer "F.Fab")
		)
		(pad "1" smd custom
			(at 0 -0.4445 180)
			(size 0.1397 0.1397)
			(layers "F.Cu" "F.Mask" "F.Paste")
			(net "I2C_M2_1_SCL")
			(options
				(clearance outline)
				(anchor circle)
			)
			(primitives
				(gr_poly
					(pts
						(arc
							(start -0.1778 -0.2794)
							(mid -0.249642 -0.249642)
							(end -0.2794 -0.1778)
						)
						(arc
							(start -0.2794 0.1778)
							(mid -0.249642 0.249642)
							(end -0.1778 0.2794)
						)
						(arc
							(start 0.1778 0.2794)
							(mid 0.249642 0.249642)
							(end 0.2794 0.1778)
						)
						(arc
							(start 0.2794 -0.1778)
							(mid 0.249642 -0.249642)
							(end 0.1778 -0.2794)
						)
					)
					(width 0)
					(fill yes)
				)
			)
		)
		(pad "2" smd custom
			(at 0 0.4445 180)
			(size 0.1397 0.1397)
			(layers "F.Cu" "F.Mask" "F.Paste")
			(net "P3V3_STBY")
			(options
				(clearance outline)
				(anchor circle)
			)
			(primitives
				(gr_poly
					(pts
						(arc
							(start -0.1778 -0.2794)
							(mid -0.249642 -0.249642)
							(end -0.2794 -0.1778)
						)
						(arc
							(start -0.2794 0.1778)
							(mid -0.249642 0.249642)
							(end -0.1778 0.2794)
						)
						(arc
							(start 0.1778 0.2794)
							(mid 0.249642 0.249642)
							(end 0.2794 0.1778)
						)
						(arc
							(start 0.2794 -0.1778)
							(mid 0.249642 -0.249642)
							(end 0.1778 -0.2794)
						)
					)
					(width 0)
					(fill yes)
				)
			)
		)
	)
	(footprint ""
		(layer "F.Cu")
		(at 40.824658 -131.704588 180)
		(property "Reference" "R376"
			(at 0 0 180)
			(layer "F.SilkS")
			(hide yes)
			(effects
				(font
					(size 1.27 1.27)
				)
			)
		)
		(property "Value" "4K7R2F-GP"
			(at 0.064008 -3.993896 180)
			(unlocked yes)
			(layer "F.Fab")
			(hide yes)
			(effects
				(font
					(size 1.016 1.016)
					(thickness 0.1524)
				)
			)
		)
		(property "Device Type" "R402H16"
			(at 0.064008 -5.517896 180)
			(unlocked yes)
			(layer "F.Fab")
			(hide yes)
			(effects
				(font
					(size 1.016 1.016)
					(thickness 0.1524)
				)
			)
		)
		(duplicate_pad_numbers_are_jumpers no)
		(fp_line
			(start 0.508 -0.9398)
			(end -0.508 -0.9398)
			(stroke
				(width 0.1524)
				(type default)
			)
			(layer "F.SilkS")
		)
		(fp_line
			(start -0.508 -0.9398)
			(end -0.508 0.9398)
			(stroke
				(width 0.1524)
				(type default)
			)
			(layer "F.SilkS")
		)
		(fp_rect
			(start -0.508 0.9398)
			(end 0.508 -0.9398)
			(stroke
				(width 0)
				(type default)
			)
			(fill no)
			(layer "F.CrtYd")
		)
		(fp_rect
			(start -0.508 0.9398)
			(end 0.508 -0.9398)
			(stroke
				(width 0)
				(type default)
			)
			(fill no)
			(layer "F.Fab")
		)
		(pad "1" smd custom
			(at 0 -0.4445 180)
			(size 0.1397 0.1397)
			(layers "F.Cu" "F.Mask" "F.Paste")
			(net "P3V3_STBY")
			(options
				(clearance outline)
				(anchor circle)
			)
			(primitives
				(gr_poly
					(pts
						(arc
							(start -0.1778 -0.2794)
							(mid -0.249642 -0.249642)
							(end -0.2794 -0.1778)
						)
						(arc
							(start -0.2794 0.1778)
							(mid -0.249642 0.249642)
							(end -0.1778 0.2794)
						)
						(arc
							(start 0.1778 0.2794)
							(mid 0.249642 0.249642)
							(end 0.2794 0.1778)
						)
						(arc
							(start 0.2794 -0.1778)
							(mid 0.249642 -0.249642)
							(end 0.1778 -0.2794)
						)
					)
					(width 0)
					(fill yes)
				)
			)
		)
		(pad "2" smd custom
			(at 0 0.4445 180)
			(size 0.1397 0.1397)
			(layers "F.Cu" "F.Mask" "F.Paste")
			(net "BMC_GPIOZ4")
			(options
				(clearance outline)
				(anchor circle)
			)
			(primitives
				(gr_poly
					(pts
						(arc
							(start -0.1778 -0.2794)
							(mid -0.249642 -0.249642)
							(end -0.2794 -0.1778)
						)
						(arc
							(start -0.2794 0.1778)
							(mid -0.249642 0.249642)
							(end -0.1778 0.2794)
						)
						(arc
							(start 0.1778 0.2794)
							(mid 0.249642 0.249642)
							(end 0.2794 0.1778)
						)
						(arc
							(start 0.2794 -0.1778)
							(mid 0.249642 -0.249642)
							(end 0.1778 -0.2794)
						)
					)
					(width 0)
					(fill yes)
				)
			)
		)
	)
	(footprint ""
		(layer "F.Cu")
		(at 169.037 -174.9552 -90)
		(property "Reference" "C166"
			(at 0 0 270)
			(layer "F.SilkS")
			(hide yes)
			(effects
				(font
					(size 1.27 1.27)
				)
			)
		)
		(property "Value" "SC10U16V5KX-7-GP-U"
			(at -0.0762 -6.1214 270)
			(unlocked yes)
			(layer "F.Fab")
			(hide yes)
			(effects
				(font
					(size 1.016 1.016)
					(thickness 0.1524)
				)
			)
		)
		(property "Device Type" "C805H58"
			(at -0.0762 -8.1534 270)
			(unlocked yes)
			(layer "F.Fab")
			(hide yes)
			(effects
				(font
					(size 1.016 1.016)
					(thickness 0.1524)
				)
			)
		)
		(duplicate_pad_numbers_are_jumpers no)
		(fp_line
			(start 0.635 0)
			(end -0.635 0)
			(stroke
				(width 0.508)
				(type default)
			)
			(layer "F.SilkS")
		)
		(fp_rect
			(start -0.9652 1.778)
			(end 0.9652 -1.778)
			(stroke
				(width 0)
				(type default)
			)
			(fill no)
			(layer "F.CrtYd")
		)
		(fp_poly
			(pts
				(xy -0.9652 -1.778) (xy 0.9652 -1.778) (xy 0.9652 1.778) (xy -0.9652 1.778)
			)
			(stroke
				(width 0)
				(type default)
			)
			(fill no)
			(layer "F.Fab")
		)
		(pad "1" smd rect
			(at 0 -0.9652 270)
			(size 1.397 1.143)
			(layers "F.Cu" "F.Mask" "F.Paste")
			(net "P5V_STBY")
		)
		(pad "2" smd rect
			(at 0 0.9652 270)
			(size 1.397 1.143)
			(layers "F.Cu" "F.Mask" "F.Paste")
			(net "GND")
		)
	)
	(footprint ""
		(layer "F.Cu")
		(at 42.8752 -159.6136)
		(property "Reference" "TP14"
			(at 0 0 0)
			(layer "F.SilkS")
			(hide yes)
			(effects
				(font
					(size 1.27 1.27)
				)
			)
		)
		(property "Value" "TPAD28-2-GP"
			(at -0.0127 -1.6637 0)
			(unlocked yes)
			(layer "F.Fab")
			(hide yes)
			(effects
				(font
					(size 1.016 1.016)
					(thickness 0.1524)
				)
			)
		)
		(property "Device Type" "TPAD28"
			(at -0.0127 -3.1877 0)
			(unlocked yes)
			(layer "F.Fab")
			(hide yes)
			(effects
				(font
					(size 1.016 1.016)
					(thickness 0.1524)
				)
			)
		)
		(duplicate_pad_numbers_are_jumpers no)
		(fp_poly
			(pts
				(arc
					(start 0.3556 0)
					(mid -0.3556 0)
					(end 0.3556 0)
				)
			)
			(stroke
				(width 0)
				(type default)
			)
			(fill no)
			(layer "F.CrtYd")
		)
		(fp_poly
			(pts
				(arc
					(start 0.6096 0)
					(mid -0.6096 0)
					(end 0.6096 0)
				)
			)
			(stroke
				(width 0)
				(type default)
			)
			(fill no)
			(layer "F.Fab")
		)
		(pad "1" smd circle
			(at 0 0)
			(size 0.7112 0.7112)
			(layers "F.Cu" "F.Mask" "F.Paste")
			(net "I2C_M2_1_SDA")
		)
	)
	(footprint ""
		(layer "F.Cu")
		(at 204.3684 -49.9618)
		(property "Reference" "TP144"
			(at 0 0 0)
			(layer "F.SilkS")
			(hide yes)
			(effects
				(font
					(size 1.27 1.27)
				)
			)
		)
		(property "Value" "TPAD28-2-GP"
			(at -0.0127 -1.6637 0)
			(unlocked yes)
			(layer "F.Fab")
			(hide yes)
			(effects
				(font
					(size 1.016 1.016)
					(thickness 0.1524)
				)
			)
		)
		(property "Device Type" "TPAD28"
			(at -0.0127 -3.1877 0)
			(unlocked yes)
			(layer "F.Fab")
			(hide yes)
			(effects
				(font
					(size 1.016 1.016)
					(thickness 0.1524)
				)
			)
		)
		(duplicate_pad_numbers_are_jumpers no)
		(fp_poly
			(pts
				(arc
					(start 0.3556 0)
					(mid -0.3556 0)
					(end 0.3556 0)
				)
			)
			(stroke
				(width 0)
				(type default)
			)
			(fill no)
			(layer "F.CrtYd")
		)
		(fp_poly
			(pts
				(arc
					(start 0.6096 0)
					(mid -0.6096 0)
					(end 0.6096 0)
				)
			)
			(stroke
				(width 0)
				(type default)
			)
			(fill no)
			(layer "F.Fab")
		)
		(pad "1" smd circle
			(at 0 0)
			(size 0.7112 0.7112)
			(layers "F.Cu" "F.Mask" "F.Paste")
			(net "ICE1_TRST#")
		)
	)
	(footprint ""
		(layer "F.Cu")
		(at 182.0291 -48.1457)
		(property "Reference" "R670"
			(at 0 0 0)
			(layer "F.SilkS")
			(hide yes)
			(effects
				(font
					(size 1.27 1.27)
				)
			)
		)
		(property "Value" "10KR2F-2-GP"
			(at 0.064008 -3.993896 0)
			(unlocked yes)
			(layer "F.Fab")
			(hide yes)
			(effects
				(font
					(size 1.016 1.016)
					(thickness 0.1524)
				)
			)
		)
		(property "Device Type" "R402H16"
			(at 0.064008 -5.517896 0)
			(unlocked yes)
			(layer "F.Fab")
			(hide yes)
			(effects
				(font
					(size 1.016 1.016)
					(thickness 0.1524)
				)
			)
		)
		(duplicate_pad_numbers_are_jumpers no)
		(fp_line
			(start -0.508 -0.9398)
			(end -0.508 0.9398)
			(stroke
				(width 0.1524)
				(type default)
			)
			(layer "F.SilkS")
		)
		(fp_line
			(start 0.508 -0.9398)
			(end -0.508 -0.9398)
			(stroke
				(width 0.1524)
				(type default)
			)
			(layer "F.SilkS")
		)
		(fp_rect
			(start -0.508 0.9398)
			(end 0.508 -0.9398)
			(stroke
				(width 0)
				(type default)
			)
			(fill no)
			(layer "F.CrtYd")
		)
		(fp_rect
			(start -0.508 0.9398)
			(end 0.508 -0.9398)
			(stroke
				(width 0)
				(type default)
			)
			(fill no)
			(layer "F.Fab")
		)
		(pad "1" smd custom
			(at 0 -0.4445)
			(size 0.1397 0.1397)
			(layers "F.Cu" "F.Mask" "F.Paste")
			(net "XM_ADDR_4")
			(options
				(clearance outline)
				(anchor circle)
			)
			(primitives
				(gr_poly
					(pts
						(arc
							(start -0.1778 -0.2794)
							(mid -0.249642 -0.249642)
							(end -0.2794 -0.1778)
						)
						(arc
							(start -0.2794 0.1778)
							(mid -0.249642 0.249642)
							(end -0.1778 0.2794)
						)
						(arc
							(start 0.1778 0.2794)
							(mid 0.249642 0.249642)
							(end 0.2794 0.1778)
						)
						(arc
							(start 0.2794 -0.1778)
							(mid 0.249642 -0.249642)
							(end 0.1778 -0.2794)
						)
					)
					(width 0)
					(fill yes)
				)
			)
		)
		(pad "2" smd custom
			(at 0 0.4445)
			(size 0.1397 0.1397)
			(layers "F.Cu" "F.Mask" "F.Paste")
			(net "GND")
			(options
				(clearance outline)
				(anchor circle)
			)
			(primitives
				(gr_poly
					(pts
						(arc
							(start -0.1778 -0.2794)
							(mid -0.249642 -0.249642)
							(end -0.2794 -0.1778)
						)
						(arc
							(start -0.2794 0.1778)
							(mid -0.249642 0.249642)
							(end -0.1778 0.2794)
						)
						(arc
							(start 0.1778 0.2794)
							(mid 0.249642 0.249642)
							(end 0.2794 0.1778)
						)
						(arc
							(start 0.2794 -0.1778)
							(mid 0.249642 -0.249642)
							(end 0.1778 -0.2794)
						)
					)
					(width 0)
					(fill yes)
				)
			)
		)
	)
	(footprint ""
		(layer "F.Cu")
		(at 71.7804 -173.7106 180)
		(property "Reference" "C78"
			(at 0 0 180)
			(layer "F.SilkS")
			(hide yes)
			(effects
				(font
					(size 1.27 1.27)
				)
			)
		)
		(property "Value" "SCD1U16V2KX-3GP"
			(at 1.1811 -2.7051 180)
			(unlocked yes)
			(layer "F.Fab")
			(hide yes)
			(effects
				(font
					(size 1.016 1.016)
					(thickness 0.1524)
				)
			)
		)
		(property "Device Type" "C402H22"
			(at 1.1811 -4.2291 180)
			(unlocked yes)
			(layer "F.Fab")
			(hide yes)
			(effects
				(font
					(size 1.016 1.016)
					(thickness 0.1524)
				)
			)
		)
		(duplicate_pad_numbers_are_jumpers no)
		(fp_rect
			(start -0.4318 0.9525)
			(end 0.4318 -0.9525)
			(stroke
				(width 0)
				(type default)
			)
			(fill no)
			(layer "F.CrtYd")
		)
		(fp_rect
			(start -0.4318 0.9525)
			(end 0.4318 -0.9525)
			(stroke
				(width 0)
				(type default)
			)
			(fill no)
			(layer "F.Fab")
		)
		(pad "1" smd custom
			(at 0 -0.4445 180)
			(size 0.1524 0.1524)
			(layers "F.Cu" "F.Mask" "F.Paste")
			(net "P3V3_STBY")
			(options
				(clearance outline)
				(anchor circle)
			)
			(primitives
				(gr_poly
					(pts
						(arc
							(start 0.3048 -0.2032)
							(mid 0.275042 -0.275042)
							(end 0.2032 -0.3048)
						)
						(arc
							(start -0.2032 -0.3048)
							(mid -0.275042 -0.275042)
							(end -0.3048 -0.2032)
						)
						(arc
							(start -0.3048 0.2032)
							(mid -0.275042 0.275042)
							(end -0.2032 0.3048)
						)
						(arc
							(start 0.2032 0.3048)
							(mid 0.275042 0.275042)
							(end 0.3048 0.2032)
						)
					)
					(width 0)
					(fill yes)
				)
			)
		)
		(pad "2" smd custom
			(at 0 0.4445 180)
			(size 0.1524 0.1524)
			(layers "F.Cu" "F.Mask" "F.Paste")
			(net "GND")
			(options
				(clearance outline)
				(anchor circle)
			)
			(primitives
				(gr_poly
					(pts
						(arc
							(start 0.3048 -0.2032)
							(mid 0.275042 -0.275042)
							(end 0.2032 -0.3048)
						)
						(arc
							(start -0.2032 -0.3048)
							(mid -0.275042 -0.275042)
							(end -0.3048 -0.2032)
						)
						(arc
							(start -0.3048 0.2032)
							(mid -0.275042 0.275042)
							(end -0.2032 0.3048)
						)
						(arc
							(start 0.2032 0.3048)
							(mid 0.275042 0.275042)
							(end 0.3048 0.2032)
						)
					)
					(width 0)
					(fill yes)
				)
			)
		)
	)
	(footprint ""
		(layer "F.Cu")
		(at 149.827742 -97.335594 180)
		(property "Reference" "Q17"
			(at 0 0 180)
			(layer "F.SilkS")
			(hide yes)
			(effects
				(font
					(size 1.27 1.27)
				)
			)
		)
		(property "Value" "2N7002K-1-GP"
			(at 0.127 -8.9662 180)
			(unlocked yes)
			(layer "F.Fab")
			(hide yes)
			(effects
				(font
					(size 1.016 1.016)
					(thickness 0.1524)
				)
			)
		)
		(property "Device Type" "SOT23DGS2D4H44"
			(at 0.127 -10.4902 180)
			(unlocked yes)
			(layer "F.Fab")
			(hide yes)
			(effects
				(font
					(size 1.016 1.016)
					(thickness 0.1524)
				)
			)
		)
		(duplicate_pad_numbers_are_jumpers no)
		(fp_line
			(start 1.651 1.778)
			(end 1.651 -1.778)
			(stroke
				(width 0.1524)
				(type default)
			)
			(layer "F.SilkS")
		)
		(fp_line
			(start 1.651 -1.778)
			(end -1.651 -1.778)
			(stroke
				(width 0.1524)
				(type default)
			)
			(layer "F.SilkS")
		)
		(fp_line
			(start -1.651 1.778)
			(end 1.651 1.778)
			(stroke
				(width 0.1524)
				(type default)
			)
			(layer "F.SilkS")
		)
		(fp_line
			(start -1.651 -1.778)
			(end -1.651 1.778)
			(stroke
				(width 0.1524)
				(type default)
			)
			(layer "F.SilkS")
		)
		(fp_poly
			(pts
				(xy -1.778 1.8796) (xy -1.778 -1.8796) (xy 1.778 -1.8796) (xy 1.778 1.8796)
			)
			(stroke
				(width 0)
				(type default)
			)
			(fill no)
			(layer "F.CrtYd")
		)
		(fp_poly
			(pts
				(xy -1.778 1.8796) (xy -1.778 -1.8796) (xy 1.778 -1.8796) (xy 1.778 1.8796)
			)
			(stroke
				(width 0)
				(type default)
			)
			(fill no)
			(layer "F.Fab")
		)
		(pad "D" smd custom
			(at 0 -0.9525 180)
			(size 0.1905 0.1905)
			(layers "F.Cu" "F.Mask" "F.Paste")
			(net "P3V3_STBY_G")
			(options
				(clearance outline)
				(anchor circle)
			)
			(primitives
				(gr_poly
					(pts
						(arc
							(start -0.1778 0.5715)
							(mid -0.321484 0.511984)
							(end -0.381 0.3683)
						)
						(arc
							(start -0.381 -0.3683)
							(mid -0.321484 -0.511984)
							(end -0.1778 -0.5715)
						)
						(arc
							(start 0.1778 -0.5715)
							(mid 0.321484 -0.511984)
							(end 0.381 -0.3683)
						)
						(arc
							(start 0.381 0.3683)
							(mid 0.321484 0.511984)
							(end 0.1778 0.5715)
						)
					)
					(width 0)
					(fill yes)
				)
			)
		)
		(pad "G" smd custom
			(at -0.98425 0.9525 180)
			(size 0.1905 0.1905)
			(layers "F.Cu" "F.Mask" "F.Paste")
			(net "PCIE_COMP_TO_IOM_RST_2")
			(options
				(clearance outline)
				(anchor circle)
			)
			(primitives
				(gr_poly
					(pts
						(arc
							(start -0.1778 0.5715)
							(mid -0.321484 0.511984)
							(end -0.381 0.3683)
						)
						(arc
							(start -0.381 -0.3683)
							(mid -0.321484 -0.511984)
							(end -0.1778 -0.5715)
						)
						(arc
							(start 0.1778 -0.5715)
							(mid 0.321484 -0.511984)
							(end 0.381 -0.3683)
						)
						(arc
							(start 0.381 0.3683)
							(mid 0.321484 0.511984)
							(end 0.1778 0.5715)
						)
					)
					(width 0)
					(fill yes)
				)
			)
		)
		(pad "S" smd custom
			(at 0.98425 0.9525 180)
			(size 0.1905 0.1905)
			(layers "F.Cu" "F.Mask" "F.Paste")
			(net "GND")
			(options
				(clearance outline)
				(anchor circle)
			)
			(primitives
				(gr_poly
					(pts
						(arc
							(start -0.1778 0.5715)
							(mid -0.321484 0.511984)
							(end -0.381 0.3683)
						)
						(arc
							(start -0.381 -0.3683)
							(mid -0.321484 -0.511984)
							(end -0.1778 -0.5715)
						)
						(arc
							(start 0.1778 -0.5715)
							(mid 0.321484 -0.511984)
							(end 0.381 -0.3683)
						)
						(arc
							(start 0.381 0.3683)
							(mid 0.321484 0.511984)
							(end 0.1778 0.5715)
						)
					)
					(width 0)
					(fill yes)
				)
			)
		)
	)
	(footprint ""
		(layer "F.Cu")
		(at 190.220346 -133.265164)
		(property "Reference" "R558"
			(at 0 0 0)
			(layer "F.SilkS")
			(hide yes)
			(effects
				(font
					(size 1.27 1.27)
				)
			)
		)
		(property "Value" "0R2J-2-GP"
			(at 0.064008 -3.993896 0)
			(unlocked yes)
			(layer "F.Fab")
			(hide yes)
			(effects
				(font
					(size 1.016 1.016)
					(thickness 0.1524)
				)
			)
		)
		(property "Device Type" "R402H16"
			(at 0.064008 -5.517896 0)
			(unlocked yes)
			(layer "F.Fab")
			(hide yes)
			(effects
				(font
					(size 1.016 1.016)
					(thickness 0.1524)
				)
			)
		)
		(duplicate_pad_numbers_are_jumpers no)
		(fp_line
			(start -0.508 -0.9398)
			(end -0.508 0.9398)
			(stroke
				(width 0.1524)
				(type default)
			)
			(layer "F.SilkS")
		)
		(fp_line
			(start 0.508 -0.9398)
			(end -0.508 -0.9398)
			(stroke
				(width 0.1524)
				(type default)
			)
			(layer "F.SilkS")
		)
		(fp_rect
			(start -0.508 0.9398)
			(end 0.508 -0.9398)
			(stroke
				(width 0)
				(type default)
			)
			(fill no)
			(layer "F.CrtYd")
		)
		(fp_rect
			(start -0.508 0.9398)
			(end 0.508 -0.9398)
			(stroke
				(width 0)
				(type default)
			)
			(fill no)
			(layer "F.Fab")
		)
		(pad "1" smd custom
			(at 0 -0.4445)
			(size 0.1397 0.1397)
			(layers "F.Cu" "F.Mask" "F.Paste")
			(net "PWRGD_P1V5")
			(options
				(clearance outline)
				(anchor circle)
			)
			(primitives
				(gr_poly
					(pts
						(arc
							(start -0.1778 -0.2794)
							(mid -0.249642 -0.249642)
							(end -0.2794 -0.1778)
						)
						(arc
							(start -0.2794 0.1778)
							(mid -0.249642 0.249642)
							(end -0.1778 0.2794)
						)
						(arc
							(start 0.1778 0.2794)
							(mid 0.249642 0.249642)
							(end 0.2794 0.1778)
						)
						(arc
							(start 0.2794 -0.1778)
							(mid 0.249642 -0.249642)
							(end 0.1778 -0.2794)
						)
					)
					(width 0)
					(fill yes)
				)
			)
		)
		(pad "2" smd custom
			(at 0 0.4445)
			(size 0.1397 0.1397)
			(layers "F.Cu" "F.Mask" "F.Paste")
			(net "VT235_EN")
			(options
				(clearance outline)
				(anchor circle)
			)
			(primitives
				(gr_poly
					(pts
						(arc
							(start -0.1778 -0.2794)
							(mid -0.249642 -0.249642)
							(end -0.2794 -0.1778)
						)
						(arc
							(start -0.2794 0.1778)
							(mid -0.249642 0.249642)
							(end -0.1778 0.2794)
						)
						(arc
							(start 0.1778 0.2794)
							(mid 0.249642 0.249642)
							(end 0.2794 0.1778)
						)
						(arc
							(start 0.2794 -0.1778)
							(mid 0.249642 -0.249642)
							(end 0.1778 -0.2794)
						)
					)
					(width 0)
					(fill yes)
				)
			)
		)
	)
	(footprint ""
		(layer "F.Cu")
		(at 66.422778 -159.068262 90)
		(property "Reference" "C518"
			(at 0 0 90)
			(layer "F.SilkS")
			(hide yes)
			(effects
				(font
					(size 1.27 1.27)
				)
			)
		)
		(property "Value" "SCD1U25V2KX-2-GP"
			(at 1.1811 -2.7051 90)
			(unlocked yes)
			(layer "F.Fab")
			(hide yes)
			(effects
				(font
					(size 1.016 1.016)
					(thickness 0.1524)
				)
			)
		)
		(property "Device Type" "C402H22"
			(at 1.1811 -4.2291 90)
			(unlocked yes)
			(layer "F.Fab")
			(hide yes)
			(effects
				(font
					(size 1.016 1.016)
					(thickness 0.1524)
				)
			)
		)
		(duplicate_pad_numbers_are_jumpers no)
		(fp_rect
			(start -0.4318 0.9525)
			(end 0.4318 -0.9525)
			(stroke
				(width 0)
				(type default)
			)
			(fill no)
			(layer "F.CrtYd")
		)
		(fp_rect
			(start -0.4318 0.9525)
			(end 0.4318 -0.9525)
			(stroke
				(width 0)
				(type default)
			)
			(fill no)
			(layer "F.Fab")
		)
		(pad "1" smd custom
			(at 0 -0.4445 90)
			(size 0.1524 0.1524)
			(layers "F.Cu" "F.Mask" "F.Paste")
			(net "ADC_P1V15_STBY")
			(options
				(clearance outline)
				(anchor circle)
			)
			(primitives
				(gr_poly
					(pts
						(arc
							(start 0.3048 -0.2032)
							(mid 0.275042 -0.275042)
							(end 0.2032 -0.3048)
						)
						(arc
							(start -0.2032 -0.3048)
							(mid -0.275042 -0.275042)
							(end -0.3048 -0.2032)
						)
						(arc
							(start -0.3048 0.2032)
							(mid -0.275042 0.275042)
							(end -0.2032 0.3048)
						)
						(arc
							(start 0.2032 0.3048)
							(mid 0.275042 0.275042)
							(end 0.3048 0.2032)
						)
					)
					(width 0)
					(fill yes)
				)
			)
		)
		(pad "2" smd custom
			(at 0 0.4445 90)
			(size 0.1524 0.1524)
			(layers "F.Cu" "F.Mask" "F.Paste")
			(net "GND")
			(options
				(clearance outline)
				(anchor circle)
			)
			(primitives
				(gr_poly
					(pts
						(arc
							(start 0.3048 -0.2032)
							(mid 0.275042 -0.275042)
							(end 0.2032 -0.3048)
						)
						(arc
							(start -0.2032 -0.3048)
							(mid -0.275042 -0.275042)
							(end -0.3048 -0.2032)
						)
						(arc
							(start -0.3048 0.2032)
							(mid -0.275042 0.275042)
							(end -0.2032 0.3048)
						)
						(arc
							(start 0.2032 0.3048)
							(mid 0.275042 0.275042)
							(end 0.3048 0.2032)
						)
					)
					(width 0)
					(fill yes)
				)
			)
		)
	)
	(footprint ""
		(layer "F.Cu")
		(at 176.1236 -38.5318)
		(property "Reference" "TP172"
			(at 0 0 0)
			(layer "F.SilkS")
			(hide yes)
			(effects
				(font
					(size 1.27 1.27)
				)
			)
		)
		(property "Value" "TPAD28-2-GP"
			(at -0.0127 -1.6637 0)
			(unlocked yes)
			(layer "F.Fab")
			(hide yes)
			(effects
				(font
					(size 1.016 1.016)
					(thickness 0.1524)
				)
			)
		)
		(property "Device Type" "TPAD28"
			(at -0.0127 -3.1877 0)
			(unlocked yes)
			(layer "F.Fab")
			(hide yes)
			(effects
				(font
					(size 1.016 1.016)
					(thickness 0.1524)
				)
			)
		)
		(duplicate_pad_numbers_are_jumpers no)
		(fp_poly
			(pts
				(arc
					(start 0.3556 0)
					(mid -0.3556 0)
					(end 0.3556 0)
				)
			)
			(stroke
				(width 0)
				(type default)
			)
			(fill no)
			(layer "F.CrtYd")
		)
		(fp_poly
			(pts
				(arc
					(start 0.6096 0)
					(mid -0.6096 0)
					(end 0.6096 0)
				)
			)
			(stroke
				(width 0)
				(type default)
			)
			(fill no)
			(layer "F.Fab")
		)
		(pad "1" smd circle
			(at 0 0)
			(size 0.7112 0.7112)
			(layers "F.Cu" "F.Mask" "F.Paste")
			(net "ZDEF_EXTA_TP_C2")
		)
	)
	(footprint ""
		(layer "F.Cu")
		(at 208.055972 -67.7672 90)
		(property "Reference" "C318"
			(at 0 0 90)
			(layer "F.SilkS")
			(hide yes)
			(effects
				(font
					(size 1.27 1.27)
				)
			)
		)
		(property "Value" "SCD01U16V1KX-GP"
			(at -2.8321 -1.7399 90)
			(unlocked yes)
			(layer "F.Fab")
			(hide yes)
			(effects
				(font
					(size 1.016 1.016)
					(thickness 0.1524)
				)
			)
		)
		(property "Device Type" "C0201H13"
			(at -2.8321 -3.2639 90)
			(unlocked yes)
			(layer "F.Fab")
			(hide yes)
			(effects
				(font
					(size 1.016 1.016)
					(thickness 0.1524)
				)
			)
		)
		(duplicate_pad_numbers_are_jumpers no)
		(fp_rect
			(start -0.2794 0.6477)
			(end 0.2794 -0.6477)
			(stroke
				(width 0)
				(type default)
			)
			(fill no)
			(layer "F.CrtYd")
		)
		(fp_rect
			(start -0.2794 0.6477)
			(end 0.2794 -0.6477)
			(stroke
				(width 0)
				(type default)
			)
			(fill no)
			(layer "F.Fab")
		)
		(pad "1" smd custom
			(at 0 -0.2794 90)
			(size 0.0762 0.0762)
			(layers "F.Cu" "F.Mask" "F.Paste")
			(net "PHY_IOC_TO_CON_B_1_DN_C")
			(options
				(clearance outline)
				(anchor circle)
			)
			(primitives
				(gr_poly
					(pts
						(arc
							(start 0.1524 -0.127)
							(mid 0.137521 -0.162921)
							(end 0.1016 -0.1778)
						)
						(arc
							(start -0.1016 -0.1778)
							(mid -0.137521 -0.162921)
							(end -0.1524 -0.127)
						)
						(arc
							(start -0.1524 0.127)
							(mid -0.137521 0.162921)
							(end -0.1016 0.1778)
						)
						(arc
							(start 0.1016 0.1778)
							(mid 0.137521 0.162921)
							(end 0.1524 0.127)
						)
					)
					(width 0)
					(fill yes)
				)
			)
		)
		(pad "2" smd custom
			(at 0 0.2794 90)
			(size 0.0762 0.0762)
			(layers "F.Cu" "F.Mask" "F.Paste")
			(net "PHY_IOC_TO_CON_B_1_DN")
			(options
				(clearance outline)
				(anchor circle)
			)
			(primitives
				(gr_poly
					(pts
						(arc
							(start 0.1524 -0.127)
							(mid 0.137521 -0.162921)
							(end 0.1016 -0.1778)
						)
						(arc
							(start -0.1016 -0.1778)
							(mid -0.137521 -0.162921)
							(end -0.1524 -0.127)
						)
						(arc
							(start -0.1524 0.127)
							(mid -0.137521 0.162921)
							(end -0.1016 0.1778)
						)
						(arc
							(start 0.1016 0.1778)
							(mid 0.137521 0.162921)
							(end 0.1524 0.127)
						)
					)
					(width 0)
					(fill yes)
				)
			)
		)
	)
	(footprint ""
		(layer "F.Cu")
		(at 177.216562 -53.782722 90)
		(property "Reference" "R766"
			(at 0 0 90)
			(layer "F.SilkS")
			(hide yes)
			(effects
				(font
					(size 1.27 1.27)
				)
			)
		)
		(property "Value" "10KR2F-2-GP"
			(at 0.064008 -3.993896 90)
			(unlocked yes)
			(layer "F.Fab")
			(hide yes)
			(effects
				(font
					(size 1.016 1.016)
					(thickness 0.1524)
				)
			)
		)
		(property "Device Type" "R402H16"
			(at 0.064008 -5.517896 90)
			(unlocked yes)
			(layer "F.Fab")
			(hide yes)
			(effects
				(font
					(size 1.016 1.016)
					(thickness 0.1524)
				)
			)
		)
		(duplicate_pad_numbers_are_jumpers no)
		(fp_line
			(start 0.508 -0.9398)
			(end -0.508 -0.9398)
			(stroke
				(width 0.1524)
				(type default)
			)
			(layer "F.SilkS")
		)
		(fp_line
			(start -0.508 -0.9398)
			(end -0.508 0.9398)
			(stroke
				(width 0.1524)
				(type default)
			)
			(layer "F.SilkS")
		)
		(fp_rect
			(start -0.508 0.9398)
			(end 0.508 -0.9398)
			(stroke
				(width 0)
				(type default)
			)
			(fill no)
			(layer "F.CrtYd")
		)
		(fp_rect
			(start -0.508 0.9398)
			(end 0.508 -0.9398)
			(stroke
				(width 0)
				(type default)
			)
			(fill no)
			(layer "F.Fab")
		)
		(pad "1" smd custom
			(at 0 -0.4445 90)
			(size 0.1397 0.1397)
			(layers "F.Cu" "F.Mask" "F.Paste")
			(net "P1V8")
			(options
				(clearance outline)
				(anchor circle)
			)
			(primitives
				(gr_poly
					(pts
						(arc
							(start -0.1778 -0.2794)
							(mid -0.249642 -0.249642)
							(end -0.2794 -0.1778)
						)
						(arc
							(start -0.2794 0.1778)
							(mid -0.249642 0.249642)
							(end -0.1778 0.2794)
						)
						(arc
							(start 0.1778 0.2794)
							(mid 0.249642 0.249642)
							(end 0.2794 0.1778)
						)
						(arc
							(start 0.2794 -0.1778)
							(mid 0.249642 -0.249642)
							(end 0.1778 -0.2794)
						)
					)
					(width 0)
					(fill yes)
				)
			)
		)
		(pad "2" smd custom
			(at 0 0.4445 90)
			(size 0.1397 0.1397)
			(layers "F.Cu" "F.Mask" "F.Paste")
			(net "XM_ADDR_11")
			(options
				(clearance outline)
				(anchor circle)
			)
			(primitives
				(gr_poly
					(pts
						(arc
							(start -0.1778 -0.2794)
							(mid -0.249642 -0.249642)
							(end -0.2794 -0.1778)
						)
						(arc
							(start -0.2794 0.1778)
							(mid -0.249642 0.249642)
							(end -0.1778 0.2794)
						)
						(arc
							(start 0.1778 0.2794)
							(mid 0.249642 0.249642)
							(end 0.2794 0.1778)
						)
						(arc
							(start 0.2794 -0.1778)
							(mid 0.249642 -0.249642)
							(end 0.1778 -0.2794)
						)
					)
					(width 0)
					(fill yes)
				)
			)
		)
	)
	(footprint ""
		(layer "F.Cu")
		(at 186.817 -49.9872)
		(property "Reference" "TP168"
			(at 0 0 0)
			(layer "F.SilkS")
			(hide yes)
			(effects
				(font
					(size 1.27 1.27)
				)
			)
		)
		(property "Value" "TPAD28-2-GP"
			(at -0.0127 -1.6637 0)
			(unlocked yes)
			(layer "F.Fab")
			(hide yes)
			(effects
				(font
					(size 1.016 1.016)
					(thickness 0.1524)
				)
			)
		)
		(property "Device Type" "TPAD28"
			(at -0.0127 -3.1877 0)
			(unlocked yes)
			(layer "F.Fab")
			(hide yes)
			(effects
				(font
					(size 1.016 1.016)
					(thickness 0.1524)
				)
			)
		)
		(duplicate_pad_numbers_are_jumpers no)
		(fp_poly
			(pts
				(arc
					(start 0.3556 0)
					(mid -0.3556 0)
					(end 0.3556 0)
				)
			)
			(stroke
				(width 0)
				(type default)
			)
			(fill no)
			(layer "F.CrtYd")
		)
		(fp_poly
			(pts
				(arc
					(start 0.6096 0)
					(mid -0.6096 0)
					(end 0.6096 0)
				)
			)
			(stroke
				(width 0)
				(type default)
			)
			(fill no)
			(layer "F.Fab")
		)
		(pad "1" smd circle
			(at 0 0)
			(size 0.7112 0.7112)
			(layers "F.Cu" "F.Mask" "F.Paste")
			(net "XM_RB")
		)
	)
	(footprint ""
		(layer "F.Cu")
		(at 127.665988 -6.399022)
		(property "Reference" "C146"
			(at 0 0 0)
			(layer "F.SilkS")
			(hide yes)
			(effects
				(font
					(size 1.27 1.27)
				)
			)
		)
		(property "Value" "SCD033U50V3KX-1GP"
			(at 0 -2.8194 0)
			(unlocked yes)
			(layer "F.Fab")
			(hide yes)
			(effects
				(font
					(size 1.016 1.016)
					(thickness 0.1524)
				)
			)
		)
		(property "Device Type" "C603H36"
			(at 0 -4.3434 0)
			(unlocked yes)
			(layer "F.Fab")
			(hide yes)
			(effects
				(font
					(size 1.016 1.016)
					(thickness 0.1524)
				)
			)
		)
		(duplicate_pad_numbers_are_jumpers no)
		(fp_line
			(start 0.508 0)
			(end -0.508 0)
			(stroke
				(width 0.2032)
				(type default)
			)
			(layer "F.SilkS")
		)
		(fp_rect
			(start -0.5842 1.3335)
			(end 0.5842 -1.3335)
			(stroke
				(width 0)
				(type default)
			)
			(fill no)
			(layer "F.CrtYd")
		)
		(fp_rect
			(start -0.5842 1.3335)
			(end 0.5842 -1.3335)
			(stroke
				(width 0)
				(type default)
			)
			(fill no)
			(layer "F.Fab")
		)
		(pad "1" smd custom
			(at 0 -0.762)
			(size 0.2159 0.2159)
			(layers "F.Cu" "F.Mask" "F.Paste")
			(net "MB0_CM_GATE_2")
			(options
				(clearance outline)
				(anchor circle)
			)
			(primitives
				(gr_poly
					(pts
						(arc
							(start -0.3302 -0.4318)
							(mid -0.402042 -0.402042)
							(end -0.4318 -0.3302)
						)
						(arc
							(start -0.4318 0.3302)
							(mid -0.402042 0.402042)
							(end -0.3302 0.4318)
						)
						(arc
							(start 0.3302 0.4318)
							(mid 0.402042 0.402042)
							(end 0.4318 0.3302)
						)
						(arc
							(start 0.4318 -0.3302)
							(mid 0.402042 -0.402042)
							(end 0.3302 -0.4318)
						)
					)
					(width 0)
					(fill yes)
				)
			)
		)
		(pad "2" smd custom
			(at 0 0.762)
			(size 0.2159 0.2159)
			(layers "F.Cu" "F.Mask" "F.Paste")
			(net "GND")
			(options
				(clearance outline)
				(anchor circle)
			)
			(primitives
				(gr_poly
					(pts
						(arc
							(start -0.3302 -0.4318)
							(mid -0.402042 -0.402042)
							(end -0.4318 -0.3302)
						)
						(arc
							(start -0.4318 0.3302)
							(mid -0.402042 0.402042)
							(end -0.3302 0.4318)
						)
						(arc
							(start 0.3302 0.4318)
							(mid 0.402042 0.402042)
							(end 0.4318 0.3302)
						)
						(arc
							(start 0.4318 -0.3302)
							(mid 0.402042 -0.402042)
							(end 0.3302 -0.4318)
						)
					)
					(width 0)
					(fill yes)
				)
			)
		)
	)
	(footprint ""
		(layer "F.Cu")
		(at 51.7271 -161.2519)
		(property "Reference" "C85"
			(at 0 0 0)
			(layer "F.SilkS")
			(hide yes)
			(effects
				(font
					(size 1.27 1.27)
				)
			)
		)
		(property "Value" "SCD1U16V2KX-3GP"
			(at 1.1811 -2.7051 0)
			(unlocked yes)
			(layer "F.Fab")
			(hide yes)
			(effects
				(font
					(size 1.016 1.016)
					(thickness 0.1524)
				)
			)
		)
		(property "Device Type" "C402H22"
			(at 1.1811 -4.2291 0)
			(unlocked yes)
			(layer "F.Fab")
			(hide yes)
			(effects
				(font
					(size 1.016 1.016)
					(thickness 0.1524)
				)
			)
		)
		(duplicate_pad_numbers_are_jumpers no)
		(fp_rect
			(start -0.4318 0.9525)
			(end 0.4318 -0.9525)
			(stroke
				(width 0)
				(type default)
			)
			(fill no)
			(layer "F.CrtYd")
		)
		(fp_rect
			(start -0.4318 0.9525)
			(end 0.4318 -0.9525)
			(stroke
				(width 0)
				(type default)
			)
			(fill no)
			(layer "F.Fab")
		)
		(pad "1" smd custom
			(at 0 -0.4445)
			(size 0.1524 0.1524)
			(layers "F.Cu" "F.Mask" "F.Paste")
			(net "GND")
			(options
				(clearance outline)
				(anchor circle)
			)
			(primitives
				(gr_poly
					(pts
						(arc
							(start 0.3048 -0.2032)
							(mid 0.275042 -0.275042)
							(end 0.2032 -0.3048)
						)
						(arc
							(start -0.2032 -0.3048)
							(mid -0.275042 -0.275042)
							(end -0.3048 -0.2032)
						)
						(arc
							(start -0.3048 0.2032)
							(mid -0.275042 0.275042)
							(end -0.2032 0.3048)
						)
						(arc
							(start 0.2032 0.3048)
							(mid 0.275042 0.275042)
							(end 0.3048 0.2032)
						)
					)
					(width 0)
					(fill yes)
				)
			)
		)
		(pad "2" smd custom
			(at 0 0.4445)
			(size 0.1524 0.1524)
			(layers "F.Cu" "F.Mask" "F.Paste")
			(net "ADCVREFFN")
			(options
				(clearance outline)
				(anchor circle)
			)
			(primitives
				(gr_poly
					(pts
						(arc
							(start 0.3048 -0.2032)
							(mid 0.275042 -0.275042)
							(end 0.2032 -0.3048)
						)
						(arc
							(start -0.2032 -0.3048)
							(mid -0.275042 -0.275042)
							(end -0.3048 -0.2032)
						)
						(arc
							(start -0.3048 0.2032)
							(mid -0.275042 0.275042)
							(end -0.2032 0.3048)
						)
						(arc
							(start 0.2032 0.3048)
							(mid 0.275042 0.275042)
							(end 0.3048 0.2032)
						)
					)
					(width 0)
					(fill yes)
				)
			)
		)
	)
	(footprint ""
		(layer "F.Cu")
		(at 35.394646 -174.67961 -90)
		(property "Reference" "R499"
			(at 0 0 270)
			(layer "F.SilkS")
			(hide yes)
			(effects
				(font
					(size 1.27 1.27)
				)
			)
		)
		(property "Value" "10KR2F-2-GP"
			(at 0.064008 -3.993896 270)
			(unlocked yes)
			(layer "F.Fab")
			(hide yes)
			(effects
				(font
					(size 1.016 1.016)
					(thickness 0.1524)
				)
			)
		)
		(property "Device Type" "R402H16"
			(at 0.064008 -5.517896 270)
			(unlocked yes)
			(layer "F.Fab")
			(hide yes)
			(effects
				(font
					(size 1.016 1.016)
					(thickness 0.1524)
				)
			)
		)
		(duplicate_pad_numbers_are_jumpers no)
		(fp_line
			(start -0.508 -0.9398)
			(end -0.508 0.9398)
			(stroke
				(width 0.1524)
				(type default)
			)
			(layer "F.SilkS")
		)
		(fp_line
			(start 0.508 -0.9398)
			(end -0.508 -0.9398)
			(stroke
				(width 0.1524)
				(type default)
			)
			(layer "F.SilkS")
		)
		(fp_rect
			(start -0.508 0.9398)
			(end 0.508 -0.9398)
			(stroke
				(width 0)
				(type default)
			)
			(fill no)
			(layer "F.CrtYd")
		)
		(fp_rect
			(start -0.508 0.9398)
			(end 0.508 -0.9398)
			(stroke
				(width 0)
				(type default)
			)
			(fill no)
			(layer "F.Fab")
		)
		(pad "1" smd custom
			(at 0 -0.4445 270)
			(size 0.1397 0.1397)
			(layers "F.Cu" "F.Mask" "F.Paste")
			(net "P3V3_STBY_VFB")
			(options
				(clearance outline)
				(anchor circle)
			)
			(primitives
				(gr_poly
					(pts
						(arc
							(start -0.1778 -0.2794)
							(mid -0.249642 -0.249642)
							(end -0.2794 -0.1778)
						)
						(arc
							(start -0.2794 0.1778)
							(mid -0.249642 0.249642)
							(end -0.1778 0.2794)
						)
						(arc
							(start 0.1778 0.2794)
							(mid 0.249642 0.249642)
							(end 0.2794 0.1778)
						)
						(arc
							(start 0.2794 -0.1778)
							(mid 0.249642 -0.249642)
							(end 0.1778 -0.2794)
						)
					)
					(width 0)
					(fill yes)
				)
			)
		)
		(pad "2" smd custom
			(at 0 0.4445 270)
			(size 0.1397 0.1397)
			(layers "F.Cu" "F.Mask" "F.Paste")
			(net "AGND_P3V3_STBY")
			(options
				(clearance outline)
				(anchor circle)
			)
			(primitives
				(gr_poly
					(pts
						(arc
							(start -0.1778 -0.2794)
							(mid -0.249642 -0.249642)
							(end -0.2794 -0.1778)
						)
						(arc
							(start -0.2794 0.1778)
							(mid -0.249642 0.249642)
							(end -0.1778 0.2794)
						)
						(arc
							(start 0.1778 0.2794)
							(mid 0.249642 0.249642)
							(end 0.2794 0.1778)
						)
						(arc
							(start 0.2794 -0.1778)
							(mid 0.249642 -0.249642)
							(end 0.1778 -0.2794)
						)
					)
					(width 0)
					(fill yes)
				)
			)
		)
	)
	(footprint ""
		(layer "F.Cu")
		(at 65.169796 -140.223494 90)
		(property "Reference" "R186"
			(at 0 0 90)
			(layer "F.SilkS")
			(hide yes)
			(effects
				(font
					(size 1.27 1.27)
				)
			)
		)
		(property "Value" "2K2R2F-GP"
			(at 0.064008 -3.993896 90)
			(unlocked yes)
			(layer "F.Fab")
			(hide yes)
			(effects
				(font
					(size 1.016 1.016)
					(thickness 0.1524)
				)
			)
		)
		(property "Device Type" "R402H16"
			(at 0.064008 -5.517896 90)
			(unlocked yes)
			(layer "F.Fab")
			(hide yes)
			(effects
				(font
					(size 1.016 1.016)
					(thickness 0.1524)
				)
			)
		)
		(duplicate_pad_numbers_are_jumpers no)
		(fp_line
			(start 0.508 -0.9398)
			(end -0.508 -0.9398)
			(stroke
				(width 0.1524)
				(type default)
			)
			(layer "F.SilkS")
		)
		(fp_line
			(start -0.508 -0.9398)
			(end -0.508 0.9398)
			(stroke
				(width 0.1524)
				(type default)
			)
			(layer "F.SilkS")
		)
		(fp_rect
			(start -0.508 0.9398)
			(end 0.508 -0.9398)
			(stroke
				(width 0)
				(type default)
			)
			(fill no)
			(layer "F.CrtYd")
		)
		(fp_rect
			(start -0.508 0.9398)
			(end 0.508 -0.9398)
			(stroke
				(width 0)
				(type default)
			)
			(fill no)
			(layer "F.Fab")
		)
		(pad "1" smd custom
			(at 0 -0.4445 90)
			(size 0.1397 0.1397)
			(layers "F.Cu" "F.Mask" "F.Paste")
			(net "I2C_M2_2_SDA")
			(options
				(clearance outline)
				(anchor circle)
			)
			(primitives
				(gr_poly
					(pts
						(arc
							(start -0.1778 -0.2794)
							(mid -0.249642 -0.249642)
							(end -0.2794 -0.1778)
						)
						(arc
							(start -0.2794 0.1778)
							(mid -0.249642 0.249642)
							(end -0.1778 0.2794)
						)
						(arc
							(start 0.1778 0.2794)
							(mid 0.249642 0.249642)
							(end 0.2794 0.1778)
						)
						(arc
							(start 0.2794 -0.1778)
							(mid 0.249642 -0.249642)
							(end 0.1778 -0.2794)
						)
					)
					(width 0)
					(fill yes)
				)
			)
		)
		(pad "2" smd custom
			(at 0 0.4445 90)
			(size 0.1397 0.1397)
			(layers "F.Cu" "F.Mask" "F.Paste")
			(net "P3V3_STBY")
			(options
				(clearance outline)
				(anchor circle)
			)
			(primitives
				(gr_poly
					(pts
						(arc
							(start -0.1778 -0.2794)
							(mid -0.249642 -0.249642)
							(end -0.2794 -0.1778)
						)
						(arc
							(start -0.2794 0.1778)
							(mid -0.249642 0.249642)
							(end -0.1778 0.2794)
						)
						(arc
							(start 0.1778 0.2794)
							(mid 0.249642 0.249642)
							(end 0.2794 0.1778)
						)
						(arc
							(start 0.2794 -0.1778)
							(mid 0.249642 -0.249642)
							(end 0.1778 -0.2794)
						)
					)
					(width 0)
					(fill yes)
				)
			)
		)
	)
	(footprint ""
		(layer "F.Cu")
		(at 176.6824 -58.0136 90)
		(property "Reference" "R663"
			(at 0 0 90)
			(layer "F.SilkS")
			(hide yes)
			(effects
				(font
					(size 1.27 1.27)
				)
			)
		)
		(property "Value" "10KR2F-2-GP"
			(at 0.064008 -3.993896 90)
			(unlocked yes)
			(layer "F.Fab")
			(hide yes)
			(effects
				(font
					(size 1.016 1.016)
					(thickness 0.1524)
				)
			)
		)
		(property "Device Type" "R402H16"
			(at 0.064008 -5.517896 90)
			(unlocked yes)
			(layer "F.Fab")
			(hide yes)
			(effects
				(font
					(size 1.016 1.016)
					(thickness 0.1524)
				)
			)
		)
		(duplicate_pad_numbers_are_jumpers no)
		(fp_line
			(start 0.508 -0.9398)
			(end -0.508 -0.9398)
			(stroke
				(width 0.1524)
				(type default)
			)
			(layer "F.SilkS")
		)
		(fp_line
			(start -0.508 -0.9398)
			(end -0.508 0.9398)
			(stroke
				(width 0.1524)
				(type default)
			)
			(layer "F.SilkS")
		)
		(fp_rect
			(start -0.508 0.9398)
			(end 0.508 -0.9398)
			(stroke
				(width 0)
				(type default)
			)
			(fill no)
			(layer "F.CrtYd")
		)
		(fp_rect
			(start -0.508 0.9398)
			(end 0.508 -0.9398)
			(stroke
				(width 0)
				(type default)
			)
			(fill no)
			(layer "F.Fab")
		)
		(pad "1" smd custom
			(at 0 -0.4445 90)
			(size 0.1397 0.1397)
			(layers "F.Cu" "F.Mask" "F.Paste")
			(net "P1V8")
			(options
				(clearance outline)
				(anchor circle)
			)
			(primitives
				(gr_poly
					(pts
						(arc
							(start -0.1778 -0.2794)
							(mid -0.249642 -0.249642)
							(end -0.2794 -0.1778)
						)
						(arc
							(start -0.2794 0.1778)
							(mid -0.249642 0.249642)
							(end -0.1778 0.2794)
						)
						(arc
							(start 0.1778 0.2794)
							(mid 0.249642 0.249642)
							(end 0.2794 0.1778)
						)
						(arc
							(start 0.2794 -0.1778)
							(mid 0.249642 -0.249642)
							(end 0.1778 -0.2794)
						)
					)
					(width 0)
					(fill yes)
				)
			)
		)
		(pad "2" smd custom
			(at 0 0.4445 90)
			(size 0.1397 0.1397)
			(layers "F.Cu" "F.Mask" "F.Paste")
			(net "XM_ADDR_22")
			(options
				(clearance outline)
				(anchor circle)
			)
			(primitives
				(gr_poly
					(pts
						(arc
							(start -0.1778 -0.2794)
							(mid -0.249642 -0.249642)
							(end -0.2794 -0.1778)
						)
						(arc
							(start -0.2794 0.1778)
							(mid -0.249642 0.249642)
							(end -0.1778 0.2794)
						)
						(arc
							(start 0.1778 0.2794)
							(mid 0.249642 0.249642)
							(end 0.2794 0.1778)
						)
						(arc
							(start 0.2794 -0.1778)
							(mid 0.249642 -0.249642)
							(end 0.1778 -0.2794)
						)
					)
					(width 0)
					(fill yes)
				)
			)
		)
	)
	(footprint ""
		(layer "F.Cu")
		(at 224.932748 -78.93177)
		(property "Reference" "LED4"
			(at 0 0 0)
			(layer "F.SilkS")
			(hide yes)
			(effects
				(font
					(size 1.27 1.27)
				)
			)
		)
		(property "Value" "LED-YG-51-GP"
			(at -2.6924 -1.4224 0)
			(unlocked yes)
			(layer "F.Fab")
			(hide yes)
			(effects
				(font
					(size 1.016 1.016)
					(thickness 0.1524)
				)
			)
		)
		(property "Device Type" "LED1608AKH40"
			(at -2.6924 -2.9464 0)
			(unlocked yes)
			(layer "F.Fab")
			(hide yes)
			(effects
				(font
					(size 1.016 1.016)
					(thickness 0.1524)
				)
			)
		)
		(duplicate_pad_numbers_are_jumpers no)
		(fp_line
			(start -0.7493 1.651)
			(end -0.7493 1.1811)
			(stroke
				(width 0.3302)
				(type default)
			)
			(layer "F.SilkS")
		)
		(fp_line
			(start -0.6604 -1.3716)
			(end 0.6604 -1.3716)
			(stroke
				(width 0.1524)
				(type default)
			)
			(layer "F.SilkS")
		)
		(fp_line
			(start -0.6604 1.3716)
			(end -0.6604 -1.3716)
			(stroke
				(width 0.1524)
				(type default)
			)
			(layer "F.SilkS")
		)
		(fp_line
			(start -0.5969 1.5494)
			(end 0.5842 1.5494)
			(stroke
				(width 0.508)
				(type default)
			)
			(layer "F.SilkS")
		)
		(fp_line
			(start 0.6604 -1.3716)
			(end 0.6604 1.3716)
			(stroke
				(width 0.1524)
				(type default)
			)
			(layer "F.SilkS")
		)
		(fp_line
			(start 0.6604 1.3716)
			(end -0.6604 1.3716)
			(stroke
				(width 0.1524)
				(type default)
			)
			(layer "F.SilkS")
		)
		(fp_line
			(start 0.7493 1.651)
			(end 0.7493 1.1811)
			(stroke
				(width 0.3302)
				(type default)
			)
			(layer "F.SilkS")
		)
		(fp_rect
			(start -0.6223 1.3335)
			(end 0.6223 -1.3335)
			(stroke
				(width 0)
				(type default)
			)
			(fill no)
			(layer "F.CrtYd")
		)
		(fp_rect
			(start -0.6223 1.3335)
			(end 0.6223 -1.3335)
			(stroke
				(width 0)
				(type default)
			)
			(fill no)
			(layer "F.Fab")
		)
		(pad "A" smd custom
			(at 0 -0.762)
			(size 0.2159 0.2159)
			(layers "F.Cu" "F.Mask" "F.Paste")
			(net "SYS_ERROR_LED_R")
			(options
				(clearance outline)
				(anchor circle)
			)
			(primitives
				(gr_poly
					(pts
						(arc
							(start -0.3302 -0.4318)
							(mid -0.402042 -0.402042)
							(end -0.4318 -0.3302)
						)
						(arc
							(start -0.4318 0.3302)
							(mid -0.402042 0.402042)
							(end -0.3302 0.4318)
						)
						(arc
							(start 0.3302 0.4318)
							(mid 0.402042 0.402042)
							(end 0.4318 0.3302)
						)
						(arc
							(start 0.4318 -0.3302)
							(mid 0.402042 -0.402042)
							(end 0.3302 -0.4318)
						)
					)
					(width 0)
					(fill yes)
				)
			)
		)
		(pad "K" smd custom
			(at 0 0.762)
			(size 0.2159 0.2159)
			(layers "F.Cu" "F.Mask" "F.Paste")
			(net "SYS_ERROR_LED_D")
			(options
				(clearance outline)
				(anchor circle)
			)
			(primitives
				(gr_poly
					(pts
						(arc
							(start -0.3302 -0.4318)
							(mid -0.402042 -0.402042)
							(end -0.4318 -0.3302)
						)
						(arc
							(start -0.4318 0.3302)
							(mid -0.402042 0.402042)
							(end -0.3302 0.4318)
						)
						(arc
							(start 0.3302 0.4318)
							(mid 0.402042 0.402042)
							(end 0.4318 0.3302)
						)
						(arc
							(start 0.4318 -0.3302)
							(mid 0.402042 -0.402042)
							(end 0.3302 -0.4318)
						)
					)
					(width 0)
					(fill yes)
				)
			)
		)
	)
	(footprint ""
		(layer "F.Cu")
		(at 93.609668 -57.133236 90)
		(property "Reference" "R719"
			(at 0 0 90)
			(layer "F.SilkS")
			(hide yes)
			(effects
				(font
					(size 1.27 1.27)
				)
			)
		)
		(property "Value" "0R2J-2-GP"
			(at 0.064008 -3.993896 90)
			(unlocked yes)
			(layer "F.Fab")
			(hide yes)
			(effects
				(font
					(size 1.016 1.016)
					(thickness 0.1524)
				)
			)
		)
		(property "Device Type" "R402H16"
			(at 0.064008 -5.517896 90)
			(unlocked yes)
			(layer "F.Fab")
			(hide yes)
			(effects
				(font
					(size 1.016 1.016)
					(thickness 0.1524)
				)
			)
		)
		(duplicate_pad_numbers_are_jumpers no)
		(fp_line
			(start 0.508 -0.9398)
			(end -0.508 -0.9398)
			(stroke
				(width 0.1524)
				(type default)
			)
			(layer "F.SilkS")
		)
		(fp_line
			(start -0.508 -0.9398)
			(end -0.508 0.9398)
			(stroke
				(width 0.1524)
				(type default)
			)
			(layer "F.SilkS")
		)
		(fp_rect
			(start -0.508 0.9398)
			(end 0.508 -0.9398)
			(stroke
				(width 0)
				(type default)
			)
			(fill no)
			(layer "F.CrtYd")
		)
		(fp_rect
			(start -0.508 0.9398)
			(end 0.508 -0.9398)
			(stroke
				(width 0)
				(type default)
			)
			(fill no)
			(layer "F.Fab")
		)
		(pad "1" smd custom
			(at 0 -0.4445 90)
			(size 0.1397 0.1397)
			(layers "F.Cu" "F.Mask" "F.Paste")
			(net "P3V3_EN_R")
			(options
				(clearance outline)
				(anchor circle)
			)
			(primitives
				(gr_poly
					(pts
						(arc
							(start -0.1778 -0.2794)
							(mid -0.249642 -0.249642)
							(end -0.2794 -0.1778)
						)
						(arc
							(start -0.2794 0.1778)
							(mid -0.249642 0.249642)
							(end -0.1778 0.2794)
						)
						(arc
							(start 0.1778 0.2794)
							(mid 0.249642 0.249642)
							(end 0.2794 0.1778)
						)
						(arc
							(start 0.2794 -0.1778)
							(mid 0.249642 -0.249642)
							(end 0.1778 -0.2794)
						)
					)
					(width 0)
					(fill yes)
				)
			)
		)
		(pad "2" smd custom
			(at 0 0.4445 90)
			(size 0.1397 0.1397)
			(layers "F.Cu" "F.Mask" "F.Paste")
			(net "P3V3_EN")
			(options
				(clearance outline)
				(anchor circle)
			)
			(primitives
				(gr_poly
					(pts
						(arc
							(start -0.1778 -0.2794)
							(mid -0.249642 -0.249642)
							(end -0.2794 -0.1778)
						)
						(arc
							(start -0.2794 0.1778)
							(mid -0.249642 0.249642)
							(end -0.1778 0.2794)
						)
						(arc
							(start 0.1778 0.2794)
							(mid 0.249642 0.249642)
							(end 0.2794 0.1778)
						)
						(arc
							(start 0.2794 -0.1778)
							(mid 0.249642 -0.249642)
							(end 0.1778 -0.2794)
						)
					)
					(width 0)
					(fill yes)
				)
			)
		)
	)
	(footprint ""
		(layer "F.Cu")
		(at 125.85446 -16.17218 90)
		(property "Reference" "PQ1"
			(at 0 0 90)
			(layer "F.SilkS")
			(hide yes)
			(effects
				(font
					(size 1.27 1.27)
				)
			)
		)
		(property "Value" "MMBT3904-3-GP"
			(at 0.10287 -10.29843 90)
			(unlocked yes)
			(layer "F.Fab")
			(hide yes)
			(effects
				(font
					(size 1.016 1.016)
					(thickness 0.1524)
				)
			)
		)
		(property "Device Type" "SOT23CBE2D4H44"
			(at 0.10287 -12.20343 90)
			(unlocked yes)
			(layer "F.Fab")
			(hide yes)
			(effects
				(font
					(size 1.016 1.016)
					(thickness 0.1524)
				)
			)
		)
		(duplicate_pad_numbers_are_jumpers no)
		(fp_line
			(start 1.651 -1.778)
			(end -1.651 -1.778)
			(stroke
				(width 0.1524)
				(type default)
			)
			(layer "F.SilkS")
		)
		(fp_line
			(start -1.651 -1.778)
			(end -1.651 1.778)
			(stroke
				(width 0.1524)
				(type default)
			)
			(layer "F.SilkS")
		)
		(fp_line
			(start 1.651 1.778)
			(end 1.651 -1.778)
			(stroke
				(width 0.1524)
				(type default)
			)
			(layer "F.SilkS")
		)
		(fp_line
			(start -1.651 1.778)
			(end 1.651 1.778)
			(stroke
				(width 0.1524)
				(type default)
			)
			(layer "F.SilkS")
		)
		(fp_poly
			(pts
				(xy -1.778 1.8796) (xy -1.778 -1.8796) (xy 1.778 -1.8796) (xy 1.778 1.8796)
			)
			(stroke
				(width 0)
				(type default)
			)
			(fill no)
			(layer "F.CrtYd")
		)
		(fp_poly
			(pts
				(xy -1.778 1.8796) (xy -1.778 -1.8796) (xy 1.778 -1.8796) (xy 1.778 1.8796)
			)
			(stroke
				(width 0)
				(type default)
			)
			(fill no)
			(layer "F.Fab")
		)
		(pad "B" smd custom
			(at -0.98425 0.9525 90)
			(size 0.1905 0.1905)
			(layers "F.Cu" "F.Mask" "F.Paste")
			(net "MB0_TEMP_C")
			(options
				(clearance outline)
				(anchor circle)
			)
			(primitives
				(gr_poly
					(pts
						(arc
							(start -0.1778 0.5715)
							(mid -0.321484 0.511984)
							(end -0.381 0.3683)
						)
						(arc
							(start -0.381 -0.3683)
							(mid -0.321484 -0.511984)
							(end -0.1778 -0.5715)
						)
						(arc
							(start 0.1778 -0.5715)
							(mid 0.321484 -0.511984)
							(end 0.381 -0.3683)
						)
						(arc
							(start 0.381 0.3683)
							(mid 0.321484 0.511984)
							(end 0.1778 0.5715)
						)
					)
					(width 0)
					(fill yes)
				)
			)
		)
		(pad "C" smd custom
			(at 0 -0.9525 90)
			(size 0.1905 0.1905)
			(layers "F.Cu" "F.Mask" "F.Paste")
			(net "MB0_TEMP_C")
			(options
				(clearance outline)
				(anchor circle)
			)
			(primitives
				(gr_poly
					(pts
						(arc
							(start -0.1778 0.5715)
							(mid -0.321484 0.511984)
							(end -0.381 0.3683)
						)
						(arc
							(start -0.381 -0.3683)
							(mid -0.321484 -0.511984)
							(end -0.1778 -0.5715)
						)
						(arc
							(start 0.1778 -0.5715)
							(mid 0.321484 -0.511984)
							(end 0.381 -0.3683)
						)
						(arc
							(start 0.381 0.3683)
							(mid 0.321484 0.511984)
							(end 0.1778 0.5715)
						)
					)
					(width 0)
					(fill yes)
				)
			)
		)
		(pad "E" smd custom
			(at 0.98425 0.9525 90)
			(size 0.1905 0.1905)
			(layers "F.Cu" "F.Mask" "F.Paste")
			(net "MB0_TEMP_E")
			(options
				(clearance outline)
				(anchor circle)
			)
			(primitives
				(gr_poly
					(pts
						(arc
							(start -0.1778 0.5715)
							(mid -0.321484 0.511984)
							(end -0.381 0.3683)
						)
						(arc
							(start -0.381 -0.3683)
							(mid -0.321484 -0.511984)
							(end -0.1778 -0.5715)
						)
						(arc
							(start 0.1778 -0.5715)
							(mid 0.321484 -0.511984)
							(end 0.381 -0.3683)
						)
						(arc
							(start 0.381 0.3683)
							(mid 0.321484 0.511984)
							(end 0.1778 0.5715)
						)
					)
					(width 0)
					(fill yes)
				)
			)
		)
	)
	(footprint ""
		(layer "F.Cu")
		(at 192.64249 -105.784142)
		(property "Reference" "C264"
			(at 0 0 0)
			(layer "F.SilkS")
			(hide yes)
			(effects
				(font
					(size 1.27 1.27)
				)
			)
		)
		(property "Value" "SC22U6D3V6KX-2-GP"
			(at -0.0762 -5.1308 0)
			(unlocked yes)
			(layer "F.Fab")
			(hide yes)
			(effects
				(font
					(size 1.016 1.016)
					(thickness 0.1524)
				)
			)
		)
		(property "Device Type" "C1206H71"
			(at -0.127 -6.6548 0)
			(unlocked yes)
			(layer "F.Fab")
			(hide yes)
			(effects
				(font
					(size 1.016 1.016)
					(thickness 0.1524)
				)
			)
		)
		(duplicate_pad_numbers_are_jumpers no)
		(fp_line
			(start -1.016 -2.2352)
			(end 1.016 -2.2352)
			(stroke
				(width 0.1524)
				(type default)
			)
			(layer "F.SilkS")
		)
		(fp_line
			(start -1.016 -0.8382)
			(end -1.016 -2.2352)
			(stroke
				(width 0.1524)
				(type default)
			)
			(layer "F.SilkS")
		)
		(fp_line
			(start -1.016 2.2352)
			(end -1.016 0.8382)
			(stroke
				(width 0.1524)
				(type default)
			)
			(layer "F.SilkS")
		)
		(fp_line
			(start 1.016 -2.2352)
			(end 1.016 -0.8382)
			(stroke
				(width 0.1524)
				(type default)
			)
			(layer "F.SilkS")
		)
		(fp_line
			(start 1.016 0.8382)
			(end 1.016 2.2352)
			(stroke
				(width 0.1524)
				(type default)
			)
			(layer "F.SilkS")
		)
		(fp_line
			(start 1.016 2.2352)
			(end -1.016 2.2352)
			(stroke
				(width 0.1524)
				(type default)
			)
			(layer "F.SilkS")
		)
		(fp_rect
			(start -1.0922 2.3114)
			(end 1.0922 -2.3114)
			(stroke
				(width 0)
				(type default)
			)
			(fill no)
			(layer "F.CrtYd")
		)
		(fp_poly
			(pts
				(xy 1.0922 -2.3114) (xy 1.0922 2.3114) (xy -1.0922 2.3114) (xy -1.0922 -2.3114)
			)
			(stroke
				(width 0)
				(type default)
			)
			(fill no)
			(layer "F.Fab")
		)
		(pad "1" smd rect
			(at 0 -1.397)
			(size 1.651 1.27)
			(layers "F.Cu" "F.Mask" "F.Paste")
			(net "P0V975")
		)
		(pad "2" smd rect
			(at 0 1.397)
			(size 1.651 1.27)
			(layers "F.Cu" "F.Mask" "F.Paste")
			(net "GND")
		)
	)
	(footprint ""
		(layer "F.Cu")
		(at 67.447414 -138.114786 -90)
		(property "Reference" "R59"
			(at 0 0 270)
			(layer "F.SilkS")
			(hide yes)
			(effects
				(font
					(size 1.27 1.27)
				)
			)
		)
		(property "Value" "33R2F-3-GP"
			(at 0.064008 -3.993896 270)
			(unlocked yes)
			(layer "F.Fab")
			(hide yes)
			(effects
				(font
					(size 1.016 1.016)
					(thickness 0.1524)
				)
			)
		)
		(property "Device Type" "R402H16"
			(at 0.064008 -5.517896 270)
			(unlocked yes)
			(layer "F.Fab")
			(hide yes)
			(effects
				(font
					(size 1.016 1.016)
					(thickness 0.1524)
				)
			)
		)
		(duplicate_pad_numbers_are_jumpers no)
		(fp_line
			(start -0.508 -0.9398)
			(end -0.508 0.9398)
			(stroke
				(width 0.1524)
				(type default)
			)
			(layer "F.SilkS")
		)
		(fp_line
			(start 0.508 -0.9398)
			(end -0.508 -0.9398)
			(stroke
				(width 0.1524)
				(type default)
			)
			(layer "F.SilkS")
		)
		(fp_rect
			(start -0.508 0.9398)
			(end 0.508 -0.9398)
			(stroke
				(width 0)
				(type default)
			)
			(fill no)
			(layer "F.CrtYd")
		)
		(fp_rect
			(start -0.508 0.9398)
			(end 0.508 -0.9398)
			(stroke
				(width 0)
				(type default)
			)
			(fill no)
			(layer "F.Fab")
		)
		(pad "1" smd custom
			(at 0 -0.4445 270)
			(size 0.1397 0.1397)
			(layers "F.Cu" "F.Mask" "F.Paste")
			(net "FP_RETBTN")
			(options
				(clearance outline)
				(anchor circle)
			)
			(primitives
				(gr_poly
					(pts
						(arc
							(start -0.1778 -0.2794)
							(mid -0.249642 -0.249642)
							(end -0.2794 -0.1778)
						)
						(arc
							(start -0.2794 0.1778)
							(mid -0.249642 0.249642)
							(end -0.1778 0.2794)
						)
						(arc
							(start 0.1778 0.2794)
							(mid 0.249642 0.249642)
							(end 0.2794 0.1778)
						)
						(arc
							(start 0.2794 -0.1778)
							(mid 0.249642 -0.249642)
							(end 0.1778 -0.2794)
						)
					)
					(width 0)
					(fill yes)
				)
			)
		)
		(pad "2" smd custom
			(at 0 0.4445 270)
			(size 0.1397 0.1397)
			(layers "F.Cu" "F.Mask" "F.Paste")
			(net "RSTBTN_OUT_N")
			(options
				(clearance outline)
				(anchor circle)
			)
			(primitives
				(gr_poly
					(pts
						(arc
							(start -0.1778 -0.2794)
							(mid -0.249642 -0.249642)
							(end -0.2794 -0.1778)
						)
						(arc
							(start -0.2794 0.1778)
							(mid -0.249642 0.249642)
							(end -0.1778 0.2794)
						)
						(arc
							(start 0.1778 0.2794)
							(mid 0.249642 0.249642)
							(end 0.2794 0.1778)
						)
						(arc
							(start 0.2794 -0.1778)
							(mid 0.249642 -0.249642)
							(end 0.1778 -0.2794)
						)
					)
					(width 0)
					(fill yes)
				)
			)
		)
	)
	(footprint ""
		(layer "F.Cu")
		(at 69.5452 -175.1584 180)
		(property "Reference" "U31"
			(at 0 0 180)
			(layer "F.SilkS")
			(hide yes)
			(effects
				(font
					(size 1.27 1.27)
				)
			)
		)
		(property "Value" "SN74LVC1G08DCKR-GP"
			(at -2.3368 -8.6868 180)
			(unlocked yes)
			(layer "F.Fab")
			(hide yes)
			(effects
				(font
					(size 1.016 1.016)
					(thickness 0.1524)
				)
			)
		)
		(property "Device Type" "SC70-5H44"
			(at -2.3114 -10.414 180)
			(unlocked yes)
			(layer "F.Fab")
			(hide yes)
			(effects
				(font
					(size 1.016 1.016)
					(thickness 0.1524)
				)
			)
		)
		(duplicate_pad_numbers_are_jumpers no)
		(fp_line
			(start 1.3843 -1.8034)
			(end 1.3843 -1.1176)
			(stroke
				(width 0.3302)
				(type default)
			)
			(layer "F.SilkS")
		)
		(fp_line
			(start 1.27 1.7018)
			(end -1.27 1.7018)
			(stroke
				(width 0.1524)
				(type default)
			)
			(layer "F.SilkS")
		)
		(fp_line
			(start 1.27 -1.7018)
			(end 1.27 1.7018)
			(stroke
				(width 0.1524)
				(type default)
			)
			(layer "F.SilkS")
		)
		(fp_line
			(start 0.6604 -1.8034)
			(end 1.3843 -1.8034)
			(stroke
				(width 0.3302)
				(type default)
			)
			(layer "F.SilkS")
		)
		(fp_line
			(start -1.27 1.7018)
			(end -1.27 -1.7018)
			(stroke
				(width 0.1524)
				(type default)
			)
			(layer "F.SilkS")
		)
		(fp_line
			(start -1.27 -1.7018)
			(end 1.27 -1.7018)
			(stroke
				(width 0.1524)
				(type default)
			)
			(layer "F.SilkS")
		)
		(fp_rect
			(start -1.524 1.9558)
			(end 1.524 -1.9558)
			(stroke
				(width 0)
				(type default)
			)
			(fill no)
			(layer "F.CrtYd")
		)
		(fp_poly
			(pts
				(xy -1.524 -1.9558) (xy 1.524 -1.9558) (xy 1.524 1.9558) (xy -1.524 1.9558)
			)
			(stroke
				(width 0)
				(type default)
			)
			(fill no)
			(layer "F.Fab")
		)
		(pad "1" smd rect
			(at 0.65024 -0.8255 180)
			(size 0.4064 1.2192)
			(layers "F.Cu" "F.Mask" "F.Paste")
			(net "COMP_TO_BMC_RESET_N_OUT")
		)
		(pad "2" smd rect
			(at 0 -0.8255 180)
			(size 0.4064 1.2192)
			(layers "F.Cu" "F.Mask" "F.Paste")
			(net "BMC_TPM_RST_N")
		)
		(pad "3" smd rect
			(at -0.65024 -0.8255 180)
			(size 0.4064 1.2192)
			(layers "F.Cu" "F.Mask" "F.Paste")
			(net "GND")
		)
		(pad "4" smd rect
			(at -0.65024 0.8255 180)
			(size 0.4064 1.2192)
			(layers "F.Cu" "F.Mask" "F.Paste")
			(net "RST_BMC_EXTRST_N_1")
		)
		(pad "5" smd rect
			(at 0.65024 0.8255 180)
			(size 0.4064 1.2192)
			(layers "F.Cu" "F.Mask" "F.Paste")
			(net "P3V3_STBY")
		)
	)
	(footprint ""
		(layer "F.Cu")
		(at 183.515 -86.614)
		(property "Reference" "TP146"
			(at 0 0 0)
			(layer "F.SilkS")
			(hide yes)
			(effects
				(font
					(size 1.27 1.27)
				)
			)
		)
		(property "Value" "TPAD28-2-GP"
			(at -0.0127 -1.6637 0)
			(unlocked yes)
			(layer "F.Fab")
			(hide yes)
			(effects
				(font
					(size 1.016 1.016)
					(thickness 0.1524)
				)
			)
		)
		(property "Device Type" "TPAD28"
			(at -0.0127 -3.1877 0)
			(unlocked yes)
			(layer "F.Fab")
			(hide yes)
			(effects
				(font
					(size 1.016 1.016)
					(thickness 0.1524)
				)
			)
		)
		(duplicate_pad_numbers_are_jumpers no)
		(fp_poly
			(pts
				(arc
					(start 0.3556 0)
					(mid -0.3556 0)
					(end 0.3556 0)
				)
			)
			(stroke
				(width 0)
				(type default)
			)
			(fill no)
			(layer "F.CrtYd")
		)
		(fp_poly
			(pts
				(arc
					(start 0.6096 0)
					(mid -0.6096 0)
					(end 0.6096 0)
				)
			)
			(stroke
				(width 0)
				(type default)
			)
			(fill no)
			(layer "F.Fab")
		)
		(pad "1" smd circle
			(at 0 0)
			(size 0.7112 0.7112)
			(layers "F.Cu" "F.Mask" "F.Paste")
			(net "SYS_HALT0#")
		)
	)
	(footprint ""
		(layer "F.Cu")
		(at 59.817 -139.2428)
		(property "Reference" "TP77"
			(at 0 0 0)
			(layer "F.SilkS")
			(hide yes)
			(effects
				(font
					(size 1.27 1.27)
				)
			)
		)
		(property "Value" "TPAD28-2-GP"
			(at -0.0127 -1.6637 0)
			(unlocked yes)
			(layer "F.Fab")
			(hide yes)
			(effects
				(font
					(size 1.016 1.016)
					(thickness 0.1524)
				)
			)
		)
		(property "Device Type" "TPAD28"
			(at -0.0127 -3.1877 0)
			(unlocked yes)
			(layer "F.Fab")
			(hide yes)
			(effects
				(font
					(size 1.016 1.016)
					(thickness 0.1524)
				)
			)
		)
		(duplicate_pad_numbers_are_jumpers no)
		(fp_poly
			(pts
				(arc
					(start 0.3556 0)
					(mid -0.3556 0)
					(end 0.3556 0)
				)
			)
			(stroke
				(width 0)
				(type default)
			)
			(fill no)
			(layer "F.CrtYd")
		)
		(fp_poly
			(pts
				(arc
					(start 0.6096 0)
					(mid -0.6096 0)
					(end 0.6096 0)
				)
			)
			(stroke
				(width 0)
				(type default)
			)
			(fill no)
			(layer "F.Fab")
		)
		(pad "1" smd circle
			(at 0 0)
			(size 0.7112 0.7112)
			(layers "F.Cu" "F.Mask" "F.Paste")
			(net "TP_BMC_GPIOI7")
		)
	)
	(footprint ""
		(layer "F.Cu")
		(at 61.294772 -144.480534 -90)
		(property "Reference" "R160"
			(at 0 0 270)
			(layer "F.SilkS")
			(hide yes)
			(effects
				(font
					(size 1.27 1.27)
				)
			)
		)
		(property "Value" "0R2J-2-GP"
			(at 0.064008 -3.993896 270)
			(unlocked yes)
			(layer "F.Fab")
			(hide yes)
			(effects
				(font
					(size 1.016 1.016)
					(thickness 0.1524)
				)
			)
		)
		(property "Device Type" "R402H16"
			(at 0.064008 -5.517896 270)
			(unlocked yes)
			(layer "F.Fab")
			(hide yes)
			(effects
				(font
					(size 1.016 1.016)
					(thickness 0.1524)
				)
			)
		)
		(duplicate_pad_numbers_are_jumpers no)
		(fp_line
			(start -0.508 -0.9398)
			(end -0.508 0.9398)
			(stroke
				(width 0.1524)
				(type default)
			)
			(layer "F.SilkS")
		)
		(fp_line
			(start 0.508 -0.9398)
			(end -0.508 -0.9398)
			(stroke
				(width 0.1524)
				(type default)
			)
			(layer "F.SilkS")
		)
		(fp_rect
			(start -0.508 0.9398)
			(end 0.508 -0.9398)
			(stroke
				(width 0)
				(type default)
			)
			(fill no)
			(layer "F.CrtYd")
		)
		(fp_rect
			(start -0.508 0.9398)
			(end 0.508 -0.9398)
			(stroke
				(width 0)
				(type default)
			)
			(fill no)
			(layer "F.Fab")
		)
		(pad "1" smd custom
			(at 0 -0.4445 270)
			(size 0.1397 0.1397)
			(layers "F.Cu" "F.Mask" "F.Paste")
			(net "I2C_SCC_SCL_OUT")
			(options
				(clearance outline)
				(anchor circle)
			)
			(primitives
				(gr_poly
					(pts
						(arc
							(start -0.1778 -0.2794)
							(mid -0.249642 -0.249642)
							(end -0.2794 -0.1778)
						)
						(arc
							(start -0.2794 0.1778)
							(mid -0.249642 0.249642)
							(end -0.1778 0.2794)
						)
						(arc
							(start 0.1778 0.2794)
							(mid 0.249642 0.249642)
							(end 0.2794 0.1778)
						)
						(arc
							(start 0.2794 -0.1778)
							(mid 0.249642 -0.249642)
							(end 0.1778 -0.2794)
						)
					)
					(width 0)
					(fill yes)
				)
			)
		)
		(pad "2" smd custom
			(at 0 0.4445 270)
			(size 0.1397 0.1397)
			(layers "F.Cu" "F.Mask" "F.Paste")
			(net "BMC_SMB3_CLK")
			(options
				(clearance outline)
				(anchor circle)
			)
			(primitives
				(gr_poly
					(pts
						(arc
							(start -0.1778 -0.2794)
							(mid -0.249642 -0.249642)
							(end -0.2794 -0.1778)
						)
						(arc
							(start -0.2794 0.1778)
							(mid -0.249642 0.249642)
							(end -0.1778 0.2794)
						)
						(arc
							(start 0.1778 0.2794)
							(mid 0.249642 0.249642)
							(end 0.2794 0.1778)
						)
						(arc
							(start 0.2794 -0.1778)
							(mid 0.249642 -0.249642)
							(end 0.1778 -0.2794)
						)
					)
					(width 0)
					(fill yes)
				)
			)
		)
	)
	(footprint ""
		(layer "F.Cu")
		(at 60.375546 -187.438538 -90)
		(property "Reference" "R479"
			(at 0 0 270)
			(layer "F.SilkS")
			(hide yes)
			(effects
				(font
					(size 1.27 1.27)
				)
			)
		)
		(property "Value" "0R6J-3-GP"
			(at -0.0508 -4.8514 270)
			(unlocked yes)
			(layer "F.Fab")
			(hide yes)
			(effects
				(font
					(size 1.016 1.016)
					(thickness 0.1524)
				)
			)
		)
		(property "Device Type" "R1206H28"
			(at 0 -6.3754 270)
			(unlocked yes)
			(layer "F.Fab")
			(hide yes)
			(effects
				(font
					(size 1.016 1.016)
					(thickness 0.1524)
				)
			)
		)
		(duplicate_pad_numbers_are_jumpers no)
		(fp_line
			(start -1.016 2.2352)
			(end -1.016 -2.2352)
			(stroke
				(width 0.1524)
				(type default)
			)
			(layer "F.SilkS")
		)
		(fp_line
			(start 1.016 2.2352)
			(end -1.016 2.2352)
			(stroke
				(width 0.1524)
				(type default)
			)
			(layer "F.SilkS")
		)
		(fp_line
			(start -1.016 -2.2352)
			(end 1.016 -2.2352)
			(stroke
				(width 0.1524)
				(type default)
			)
			(layer "F.SilkS")
		)
		(fp_line
			(start 1.016 -2.2352)
			(end 1.016 2.2352)
			(stroke
				(width 0.1524)
				(type default)
			)
			(layer "F.SilkS")
		)
		(fp_rect
			(start -1.0922 2.3114)
			(end 1.0922 -2.3114)
			(stroke
				(width 0)
				(type default)
			)
			(fill no)
			(layer "F.CrtYd")
		)
		(fp_poly
			(pts
				(xy -1.0922 -2.3114) (xy 1.0922 -2.3114) (xy 1.0922 2.3114) (xy -1.0922 2.3114)
			)
			(stroke
				(width 0)
				(type default)
			)
			(fill no)
			(layer "F.Fab")
		)
		(pad "1" smd rect
			(at 0 -1.397 270)
			(size 1.651 1.27)
			(layers "F.Cu" "F.Mask" "F.Paste")
			(net "P3V3_STBY")
		)
		(pad "2" smd rect
			(at 0 1.397 270)
			(size 1.651 1.27)
			(layers "F.Cu" "F.Mask" "F.Paste")
			(net "P3V3_STBY_OUT")
		)
	)
	(footprint ""
		(layer "F.Cu")
		(at 98.916744 -157.404054 -90)
		(property "Reference" "R18"
			(at 0 0 270)
			(layer "F.SilkS")
			(hide yes)
			(effects
				(font
					(size 1.27 1.27)
				)
			)
		)
		(property "Value" "4K7R2F-GP"
			(at 0.064008 -3.993896 270)
			(unlocked yes)
			(layer "F.Fab")
			(hide yes)
			(effects
				(font
					(size 1.016 1.016)
					(thickness 0.1524)
				)
			)
		)
		(property "Device Type" "R402H16"
			(at 0.064008 -5.517896 270)
			(unlocked yes)
			(layer "F.Fab")
			(hide yes)
			(effects
				(font
					(size 1.016 1.016)
					(thickness 0.1524)
				)
			)
		)
		(duplicate_pad_numbers_are_jumpers no)
		(fp_line
			(start -0.508 -0.9398)
			(end -0.508 0.9398)
			(stroke
				(width 0.1524)
				(type default)
			)
			(layer "F.SilkS")
		)
		(fp_line
			(start 0.508 -0.9398)
			(end -0.508 -0.9398)
			(stroke
				(width 0.1524)
				(type default)
			)
			(layer "F.SilkS")
		)
		(fp_rect
			(start -0.508 0.9398)
			(end 0.508 -0.9398)
			(stroke
				(width 0)
				(type default)
			)
			(fill no)
			(layer "F.CrtYd")
		)
		(fp_rect
			(start -0.508 0.9398)
			(end 0.508 -0.9398)
			(stroke
				(width 0)
				(type default)
			)
			(fill no)
			(layer "F.Fab")
		)
		(pad "1" smd custom
			(at 0 -0.4445 270)
			(size 0.1397 0.1397)
			(layers "F.Cu" "F.Mask" "F.Paste")
			(net "P3V3_STBY")
			(options
				(clearance outline)
				(anchor circle)
			)
			(primitives
				(gr_poly
					(pts
						(arc
							(start -0.1778 -0.2794)
							(mid -0.249642 -0.249642)
							(end -0.2794 -0.1778)
						)
						(arc
							(start -0.2794 0.1778)
							(mid -0.249642 0.249642)
							(end -0.1778 0.2794)
						)
						(arc
							(start 0.1778 0.2794)
							(mid 0.249642 0.249642)
							(end 0.2794 0.1778)
						)
						(arc
							(start 0.2794 -0.1778)
							(mid 0.249642 -0.249642)
							(end 0.1778 -0.2794)
						)
					)
					(width 0)
					(fill yes)
				)
			)
		)
		(pad "2" smd custom
			(at 0 0.4445 270)
			(size 0.1397 0.1397)
			(layers "F.Cu" "F.Mask" "F.Paste")
			(net "CFG_SEL1")
			(options
				(clearance outline)
				(anchor circle)
			)
			(primitives
				(gr_poly
					(pts
						(arc
							(start -0.1778 -0.2794)
							(mid -0.249642 -0.249642)
							(end -0.2794 -0.1778)
						)
						(arc
							(start -0.2794 0.1778)
							(mid -0.249642 0.249642)
							(end -0.1778 0.2794)
						)
						(arc
							(start 0.1778 0.2794)
							(mid 0.249642 0.249642)
							(end 0.2794 0.1778)
						)
						(arc
							(start 0.2794 -0.1778)
							(mid 0.249642 -0.249642)
							(end 0.1778 -0.2794)
						)
					)
					(width 0)
					(fill yes)
				)
			)
		)
	)
	(footprint ""
		(layer "F.Cu")
		(at 197.866 -131.699 90)
		(property "Reference" "R550"
			(at 0 0 90)
			(layer "F.SilkS")
			(hide yes)
			(effects
				(font
					(size 1.27 1.27)
				)
			)
		)
		(property "Value" "4K7R2F-GP"
			(at 0.064008 -3.993896 90)
			(unlocked yes)
			(layer "F.Fab")
			(hide yes)
			(effects
				(font
					(size 1.016 1.016)
					(thickness 0.1524)
				)
			)
		)
		(property "Device Type" "R402H16"
			(at 0.064008 -5.517896 90)
			(unlocked yes)
			(layer "F.Fab")
			(hide yes)
			(effects
				(font
					(size 1.016 1.016)
					(thickness 0.1524)
				)
			)
		)
		(duplicate_pad_numbers_are_jumpers no)
		(fp_line
			(start 0.508 -0.9398)
			(end -0.508 -0.9398)
			(stroke
				(width 0.1524)
				(type default)
			)
			(layer "F.SilkS")
		)
		(fp_line
			(start -0.508 -0.9398)
			(end -0.508 0.9398)
			(stroke
				(width 0.1524)
				(type default)
			)
			(layer "F.SilkS")
		)
		(fp_rect
			(start -0.508 0.9398)
			(end 0.508 -0.9398)
			(stroke
				(width 0)
				(type default)
			)
			(fill no)
			(layer "F.CrtYd")
		)
		(fp_rect
			(start -0.508 0.9398)
			(end 0.508 -0.9398)
			(stroke
				(width 0)
				(type default)
			)
			(fill no)
			(layer "F.Fab")
		)
		(pad "1" smd custom
			(at 0 -0.4445 90)
			(size 0.1397 0.1397)
			(layers "F.Cu" "F.Mask" "F.Paste")
			(net "P1V8")
			(options
				(clearance outline)
				(anchor circle)
			)
			(primitives
				(gr_poly
					(pts
						(arc
							(start -0.1778 -0.2794)
							(mid -0.249642 -0.249642)
							(end -0.2794 -0.1778)
						)
						(arc
							(start -0.2794 0.1778)
							(mid -0.249642 0.249642)
							(end -0.1778 0.2794)
						)
						(arc
							(start 0.1778 0.2794)
							(mid 0.249642 0.249642)
							(end 0.2794 0.1778)
						)
						(arc
							(start 0.2794 -0.1778)
							(mid 0.249642 -0.249642)
							(end 0.1778 -0.2794)
						)
					)
					(width 0)
					(fill yes)
				)
			)
		)
		(pad "2" smd custom
			(at 0 0.4445 90)
			(size 0.1397 0.1397)
			(layers "F.Cu" "F.Mask" "F.Paste")
			(net "PWRGD_P1V8")
			(options
				(clearance outline)
				(anchor circle)
			)
			(primitives
				(gr_poly
					(pts
						(arc
							(start -0.1778 -0.2794)
							(mid -0.249642 -0.249642)
							(end -0.2794 -0.1778)
						)
						(arc
							(start -0.2794 0.1778)
							(mid -0.249642 0.249642)
							(end -0.1778 0.2794)
						)
						(arc
							(start 0.1778 0.2794)
							(mid 0.249642 0.249642)
							(end 0.2794 0.1778)
						)
						(arc
							(start 0.2794 -0.1778)
							(mid 0.249642 -0.249642)
							(end 0.1778 -0.2794)
						)
					)
					(width 0)
					(fill yes)
				)
			)
		)
	)
	(footprint ""
		(layer "F.Cu")
		(at 89.65692 -162.334956 180)
		(property "Reference" "C19"
			(at 0 0 180)
			(layer "F.SilkS")
			(hide yes)
			(effects
				(font
					(size 1.27 1.27)
				)
			)
		)
		(property "Value" "SC1U16V3KX-5GP"
			(at 0 -2.8194 180)
			(unlocked yes)
			(layer "F.Fab")
			(hide yes)
			(effects
				(font
					(size 1.016 1.016)
					(thickness 0.1524)
				)
			)
		)
		(property "Device Type" "C603H36"
			(at 0 -4.3434 180)
			(unlocked yes)
			(layer "F.Fab")
			(hide yes)
			(effects
				(font
					(size 1.016 1.016)
					(thickness 0.1524)
				)
			)
		)
		(duplicate_pad_numbers_are_jumpers no)
		(fp_line
			(start 0.508 0)
			(end -0.508 0)
			(stroke
				(width 0.2032)
				(type default)
			)
			(layer "F.SilkS")
		)
		(fp_rect
			(start -0.5842 1.3335)
			(end 0.5842 -1.3335)
			(stroke
				(width 0)
				(type default)
			)
			(fill no)
			(layer "F.CrtYd")
		)
		(fp_rect
			(start -0.5842 1.3335)
			(end 0.5842 -1.3335)
			(stroke
				(width 0)
				(type default)
			)
			(fill no)
			(layer "F.Fab")
		)
		(pad "1" smd custom
			(at 0 -0.762 180)
			(size 0.2159 0.2159)
			(layers "F.Cu" "F.Mask" "F.Paste")
			(net "PLLFILT")
			(options
				(clearance outline)
				(anchor circle)
			)
			(primitives
				(gr_poly
					(pts
						(arc
							(start -0.3302 -0.4318)
							(mid -0.402042 -0.402042)
							(end -0.4318 -0.3302)
						)
						(arc
							(start -0.4318 0.3302)
							(mid -0.402042 0.402042)
							(end -0.3302 0.4318)
						)
						(arc
							(start 0.3302 0.4318)
							(mid 0.402042 0.402042)
							(end 0.4318 0.3302)
						)
						(arc
							(start 0.4318 -0.3302)
							(mid 0.402042 -0.402042)
							(end 0.3302 -0.4318)
						)
					)
					(width 0)
					(fill yes)
				)
			)
		)
		(pad "2" smd custom
			(at 0 0.762 180)
			(size 0.2159 0.2159)
			(layers "F.Cu" "F.Mask" "F.Paste")
			(net "GND")
			(options
				(clearance outline)
				(anchor circle)
			)
			(primitives
				(gr_poly
					(pts
						(arc
							(start -0.3302 -0.4318)
							(mid -0.402042 -0.402042)
							(end -0.4318 -0.3302)
						)
						(arc
							(start -0.4318 0.3302)
							(mid -0.402042 0.402042)
							(end -0.3302 0.4318)
						)
						(arc
							(start 0.3302 0.4318)
							(mid 0.402042 0.402042)
							(end 0.4318 0.3302)
						)
						(arc
							(start 0.4318 -0.3302)
							(mid 0.402042 -0.402042)
							(end 0.3302 -0.4318)
						)
					)
					(width 0)
					(fill yes)
				)
			)
		)
	)
	(footprint ""
		(layer "F.Cu")
		(at 11.999976 -6.249924)
		(property "Reference" "RST1"
			(at 0 0 0)
			(layer "F.SilkS")
			(hide yes)
			(effects
				(font
					(size 1.27 1.27)
				)
			)
		)
		(property "Value" "SW-TACT-4P-210-GP"
			(at -5.9436 2.1209 0)
			(unlocked yes)
			(layer "F.Fab")
			(hide yes)
			(effects
				(font
					(size 1.016 1.016)
					(thickness 0.1524)
				)
			)
		)
		(property "Device Type" "DIPTRONICS"
			(at -5.9436 0.5969 0)
			(unlocked yes)
			(layer "F.Fab")
			(hide yes)
			(effects
				(font
					(size 1.016 1.016)
					(thickness 0.1524)
				)
			)
		)
		(duplicate_pad_numbers_are_jumpers no)
		(fp_line
			(start -4.4704 -4.2418)
			(end 4.4704 -4.2418)
			(stroke
				(width 0.1524)
				(type default)
			)
			(layer "F.SilkS")
		)
		(fp_line
			(start -4.4704 -1.5494)
			(end -4.4704 -4.2418)
			(stroke
				(width 0.1524)
				(type default)
			)
			(layer "F.SilkS")
		)
		(fp_line
			(start -3.9497 -1.5494)
			(end -4.4704 -1.5494)
			(stroke
				(width 0.1524)
				(type default)
			)
			(layer "F.SilkS")
		)
		(fp_line
			(start -3.9497 3.2258)
			(end -3.9497 -1.5494)
			(stroke
				(width 0.1524)
				(type default)
			)
			(layer "F.SilkS")
		)
		(fp_line
			(start -2.0066 3.2258)
			(end -3.9497 3.2258)
			(stroke
				(width 0.1524)
				(type default)
			)
			(layer "F.SilkS")
		)
		(fp_line
			(start -2.0066 6.1214)
			(end -2.0066 3.2258)
			(stroke
				(width 0.1524)
				(type default)
			)
			(layer "F.SilkS")
		)
		(fp_line
			(start 2.0066 3.2258)
			(end 2.0066 6.1214)
			(stroke
				(width 0.1524)
				(type default)
			)
			(layer "F.SilkS")
		)
		(fp_line
			(start 2.0066 6.1214)
			(end -2.0066 6.1214)
			(stroke
				(width 0.1524)
				(type default)
			)
			(layer "F.SilkS")
		)
		(fp_line
			(start 3.9497 -1.5494)
			(end 3.9497 3.2258)
			(stroke
				(width 0.1524)
				(type default)
			)
			(layer "F.SilkS")
		)
		(fp_line
			(start 3.9497 3.2258)
			(end 2.0066 3.2258)
			(stroke
				(width 0.1524)
				(type default)
			)
			(layer "F.SilkS")
		)
		(fp_line
			(start 4.4704 -4.2418)
			(end 4.4704 -1.5494)
			(stroke
				(width 0.1524)
				(type default)
			)
			(layer "F.SilkS")
		)
		(fp_line
			(start 4.4704 -1.5494)
			(end 3.9497 -1.5494)
			(stroke
				(width 0.1524)
				(type default)
			)
			(layer "F.SilkS")
		)
		(fp_circle
			(center -3.50012 -2.500122)
			(end -2.43332 -2.500122)
			(stroke
				(width 0.3048)
				(type default)
			)
			(fill no)
			(layer "F.SilkS")
		)
		(fp_circle
			(center -2.249932 0)
			(end -1.183132 0)
			(stroke
				(width 0.3048)
				(type default)
			)
			(fill no)
			(layer "F.SilkS")
		)
		(fp_circle
			(center 2.249932 0)
			(end 3.316732 0)
			(stroke
				(width 0.3048)
				(type default)
			)
			(fill no)
			(layer "F.SilkS")
		)
		(fp_circle
			(center 3.50012 -2.500122)
			(end 4.56692 -2.500122)
			(stroke
				(width 0.3048)
				(type default)
			)
			(fill no)
			(layer "F.SilkS")
		)
		(fp_poly
			(pts
				(xy -1.7526 5.8674) (xy -1.7526 2.9718) (xy -3.6957 2.9718) (xy -3.6957 -3.9878) (xy 3.6957 -3.9878)
				(xy 3.6957 2.9718) (xy 1.7526 2.9718) (xy 1.7526 5.8674)
			)
			(stroke
				(width 0)
				(type default)
			)
			(fill no)
			(layer "F.CrtYd")
		)
		(fp_poly
			(pts
				(xy -2.2606 6.3754) (xy -2.2606 3.4798) (xy -4.2037 3.4798) (xy -4.2037 -1.2954) (xy -4.7244 -1.2954)
				(xy -4.7244 -4.4958) (xy 4.7244 -4.4958) (xy 4.7244 -1.2954) (xy 4.2037 -1.2954) (xy 4.2037 -0.00635)
				(xy 3.6957 -0.00635) (xy 3.6957 -3.9878) (xy -3.6957 -3.9878) (xy -3.6957 2.9718) (xy -1.7526 2.9718)
				(xy -1.7526 5.8674) (xy 1.7526 5.8674) (xy 1.7526 2.9718) (xy 3.6957 2.9718) (xy 3.6957 0.00635)
				(xy 4.2037 0.00635) (xy 4.2037 3.4798) (xy 2.2606 3.4798) (xy 2.2606 6.3754)
			)
			(stroke
				(width 0)
				(type default)
			)
			(fill no)
			(layer "F.CrtYd")
		)
		(fp_poly
			(pts
				(xy -2.2606 6.3754) (xy -2.2606 3.4798) (xy -4.2037 3.4798) (xy -4.2037 -1.2954) (xy -4.7244 -1.2954)
				(xy -4.7244 -4.4958) (xy 4.7244 -4.4958) (xy 4.7244 -1.2954) (xy 4.2037 -1.2954) (xy 4.2037 3.4798)
				(xy 2.2606 3.4798) (xy 2.2606 6.3754)
			)
			(stroke
				(width 0)
				(type default)
			)
			(fill no)
			(layer "F.Fab")
		)
		(pad "1" thru_hole circle
			(at -2.249932 0)
			(size 1.4224 1.4224)
			(drill 1.016)
			(layers "*.Cu" "*.Mask")
			(remove_unused_layers no)
			(net "SYS_RST_BTN_IN_N")
			(clearance 0.1524)
			(thermal_gap 0.1524)
		)
		(pad "2" thru_hole circle
			(at 2.249932 0)
			(size 1.4224 1.4224)
			(drill 1.016)
			(layers "*.Cu" "*.Mask")
			(remove_unused_layers no)
			(net "GND")
			(clearance 0.1524)
			(thermal_gap 0.1524)
		)
		(pad "3" thru_hole circle
			(at -3.50012 -2.500122)
			(size 1.4224 1.4224)
			(drill 1.016)
			(layers "*.Cu" "*.Mask")
			(remove_unused_layers no)
			(net "RST_BTN_GND")
			(clearance 0.1524)
			(thermal_gap 0.1524)
		)
		(pad "4" thru_hole circle
			(at 3.50012 -2.500122)
			(size 1.4224 1.4224)
			(drill 1.016)
			(layers "*.Cu" "*.Mask")
			(remove_unused_layers no)
			(net "RST_BTN_GND")
			(clearance 0.1524)
			(thermal_gap 0.1524)
		)
		(zone
			(layer "F.Cu")
			(hatch none 0.5)
			(connect_pads
				(clearance 0)
			)
			(min_thickness 0.25)
			(keepout
				(tracks not_allowed)
				(vias allowed)
				(pads allowed)
				(copperpour not_allowed)
				(footprints allowed)
			)
			(placement
				(enabled no)
				(sheetname "")
			)
			(fill
				(thermal_gap 0.5)
				(thermal_bridge_width 0.5)
				(island_removal_mode 0)
			)
			(polygon
				(pts
					(xy 8.177276 -9.461246) (xy 8.837676 -9.461246) (xy 8.837676 -10.364724) (xy 8.177276 -10.364724)
				)
			)
		)
		(zone
			(layer "F.Cu")
			(hatch none 0.5)
			(connect_pads
				(clearance 0)
			)
			(min_thickness 0.25)
			(keepout
				(tracks allowed)
				(vias not_allowed)
				(pads allowed)
				(copperpour not_allowed)
				(footprints allowed)
			)
			(placement
				(enabled no)
				(sheetname "")
			)
			(fill
				(thermal_gap 0.5)
				(thermal_bridge_width 0.5)
				(island_removal_mode 0)
			)
			(polygon
				(pts
					(xy 8.177276 -9.461246) (xy 8.837676 -9.461246) (xy 8.837676 -10.364724) (xy 8.177276 -10.364724)
				)
			)
		)
		(zone
			(layer "F.Cu")
			(hatch none 0.5)
			(connect_pads
				(clearance 0)
			)
			(min_thickness 0.25)
			(keepout
				(tracks allowed)
				(vias not_allowed)
				(pads allowed)
				(copperpour not_allowed)
				(footprints allowed)
			)
			(placement
				(enabled no)
				(sheetname "")
			)
			(fill
				(thermal_gap 0.5)
				(thermal_bridge_width 0.5)
				(island_removal_mode 0)
			)
			(polygon
				(pts
					(xy 8.177276 -3.532124) (xy 8.837676 -3.532124) (xy 8.837676 -8.038846) (xy 8.177276 -8.038846)
				)
			)
		)
		(zone
			(layer "F.Cu")
			(hatch none 0.5)
			(connect_pads
				(clearance 0)
			)
			(min_thickness 0.25)
			(keepout
				(tracks not_allowed)
				(vias allowed)
				(pads allowed)
				(copperpour not_allowed)
				(footprints allowed)
			)
			(placement
				(enabled no)
				(sheetname "")
			)
			(fill
				(thermal_gap 0.5)
				(thermal_bridge_width 0.5)
				(island_removal_mode 0)
			)
			(polygon
				(pts
					(xy 8.177276 -3.532124) (xy 8.837676 -3.532124) (xy 8.837676 -8.038846) (xy 8.177276 -8.038846)
				)
			)
		)
		(zone
			(layer "F.Cu")
			(hatch none 0.5)
			(connect_pads
				(clearance 0)
			)
			(min_thickness 0.25)
			(keepout
				(tracks allowed)
				(vias not_allowed)
				(pads allowed)
				(copperpour not_allowed)
				(footprints allowed)
			)
			(placement
				(enabled no)
				(sheetname "")
			)
			(fill
				(thermal_gap 0.5)
				(thermal_bridge_width 0.5)
				(island_removal_mode 0)
			)
			(polygon
				(pts
					(xy 11.072876 -3.532124) (xy 12.927076 -3.532124) (xy 12.927076 -4.294124) (xy 11.072876 -4.294124)
				)
			)
		)
		(zone
			(layer "F.Cu")
			(hatch none 0.5)
			(connect_pads
				(clearance 0)
			)
			(min_thickness 0.25)
			(keepout
				(tracks not_allowed)
				(vias allowed)
				(pads allowed)
				(copperpour not_allowed)
				(footprints allowed)
			)
			(placement
				(enabled no)
				(sheetname "")
			)
			(fill
				(thermal_gap 0.5)
				(thermal_bridge_width 0.5)
				(island_removal_mode 0)
			)
			(polygon
				(pts
					(xy 11.072876 -3.532124) (xy 12.927076 -3.532124) (xy 12.927076 -4.294124) (xy 11.072876 -4.294124)
				)
			)
		)
		(zone
			(layer "F.Cu")
			(hatch none 0.5)
			(connect_pads
				(clearance 0)
			)
			(min_thickness 0.25)
			(keepout
				(tracks allowed)
				(vias not_allowed)
				(pads allowed)
				(copperpour not_allowed)
				(footprints allowed)
			)
			(placement
				(enabled no)
				(sheetname "")
			)
			(fill
				(thermal_gap 0.5)
				(thermal_bridge_width 0.5)
				(island_removal_mode 0)
			)
			(polygon
				(pts
					(xy 15.162276 -9.461246) (xy 15.822676 -9.461246) (xy 15.822676 -10.364724) (xy 15.162276 -10.364724)
				)
			)
		)
		(zone
			(layer "F.Cu")
			(hatch none 0.5)
			(connect_pads
				(clearance 0)
			)
			(min_thickness 0.25)
			(keepout
				(tracks not_allowed)
				(vias allowed)
				(pads allowed)
				(copperpour not_allowed)
				(footprints allowed)
			)
			(placement
				(enabled no)
				(sheetname "")
			)
			(fill
				(thermal_gap 0.5)
				(thermal_bridge_width 0.5)
				(island_removal_mode 0)
			)
			(polygon
				(pts
					(xy 15.162276 -9.461246) (xy 15.822676 -9.461246) (xy 15.822676 -10.364724) (xy 15.162276 -10.364724)
				)
			)
		)
		(zone
			(layer "F.Cu")
			(hatch none 0.5)
			(connect_pads
				(clearance 0)
			)
			(min_thickness 0.25)
			(keepout
				(tracks not_allowed)
				(vias allowed)
				(pads allowed)
				(copperpour not_allowed)
				(footprints allowed)
			)
			(placement
				(enabled no)
				(sheetname "")
			)
			(fill
				(thermal_gap 0.5)
				(thermal_bridge_width 0.5)
				(island_removal_mode 0)
			)
			(polygon
				(pts
					(xy 15.162276 -3.532124) (xy 15.822676 -3.532124) (xy 15.822676 -8.038846) (xy 15.162276 -8.038846)
				)
			)
		)
		(zone
			(layer "F.Cu")
			(hatch none 0.5)
			(connect_pads
				(clearance 0)
			)
			(min_thickness 0.25)
			(keepout
				(tracks allowed)
				(vias not_allowed)
				(pads allowed)
				(copperpour not_allowed)
				(footprints allowed)
			)
			(placement
				(enabled no)
				(sheetname "")
			)
			(fill
				(thermal_gap 0.5)
				(thermal_bridge_width 0.5)
				(island_removal_mode 0)
			)
			(polygon
				(pts
					(xy 15.162276 -3.532124) (xy 15.822676 -3.532124) (xy 15.822676 -8.038846) (xy 15.162276 -8.038846)
				)
			)
		)
	)
	(footprint ""
		(layer "F.Cu")
		(at 175.1076 -39.497)
		(property "Reference" "TP174"
			(at 0 0 0)
			(layer "F.SilkS")
			(hide yes)
			(effects
				(font
					(size 1.27 1.27)
				)
			)
		)
		(property "Value" "TPAD28-2-GP"
			(at -0.0127 -1.6637 0)
			(unlocked yes)
			(layer "F.Fab")
			(hide yes)
			(effects
				(font
					(size 1.016 1.016)
					(thickness 0.1524)
				)
			)
		)
		(property "Device Type" "TPAD28"
			(at -0.0127 -3.1877 0)
			(unlocked yes)
			(layer "F.Fab")
			(hide yes)
			(effects
				(font
					(size 1.016 1.016)
					(thickness 0.1524)
				)
			)
		)
		(duplicate_pad_numbers_are_jumpers no)
		(fp_poly
			(pts
				(arc
					(start 0.3556 0)
					(mid -0.3556 0)
					(end 0.3556 0)
				)
			)
			(stroke
				(width 0)
				(type default)
			)
			(fill no)
			(layer "F.CrtYd")
		)
		(fp_poly
			(pts
				(arc
					(start 0.6096 0)
					(mid -0.6096 0)
					(end 0.6096 0)
				)
			)
			(stroke
				(width 0)
				(type default)
			)
			(fill no)
			(layer "F.Fab")
		)
		(pad "1" smd circle
			(at 0 0)
			(size 0.7112 0.7112)
			(layers "F.Cu" "F.Mask" "F.Paste")
			(net "ZDEF_EXTA_TP_B1")
		)
	)
	(footprint ""
		(layer "F.Cu")
		(at 177.1396 -39.497)
		(property "Reference" "TP171"
			(at 0 0 0)
			(layer "F.SilkS")
			(hide yes)
			(effects
				(font
					(size 1.27 1.27)
				)
			)
		)
		(property "Value" "TPAD28-2-GP"
			(at -0.0127 -1.6637 0)
			(unlocked yes)
			(layer "F.Fab")
			(hide yes)
			(effects
				(font
					(size 1.016 1.016)
					(thickness 0.1524)
				)
			)
		)
		(property "Device Type" "TPAD28"
			(at -0.0127 -3.1877 0)
			(unlocked yes)
			(layer "F.Fab")
			(hide yes)
			(effects
				(font
					(size 1.016 1.016)
					(thickness 0.1524)
				)
			)
		)
		(duplicate_pad_numbers_are_jumpers no)
		(fp_poly
			(pts
				(arc
					(start 0.3556 0)
					(mid -0.3556 0)
					(end 0.3556 0)
				)
			)
			(stroke
				(width 0)
				(type default)
			)
			(fill no)
			(layer "F.CrtYd")
		)
		(fp_poly
			(pts
				(arc
					(start 0.6096 0)
					(mid -0.6096 0)
					(end 0.6096 0)
				)
			)
			(stroke
				(width 0)
				(type default)
			)
			(fill no)
			(layer "F.Fab")
		)
		(pad "1" smd circle
			(at 0 0)
			(size 0.7112 0.7112)
			(layers "F.Cu" "F.Mask" "F.Paste")
			(net "ZDEF_EXTA_TP_C1")
		)
	)
	(footprint ""
		(layer "F.Cu")
		(at 9.85012 -12.63904)
		(property "Reference" "R65"
			(at 0 0 0)
			(layer "F.SilkS")
			(hide yes)
			(effects
				(font
					(size 1.27 1.27)
				)
			)
		)
		(property "Value" "8K2R2J-3-GP"
			(at 0.064008 -3.993896 0)
			(unlocked yes)
			(layer "F.Fab")
			(hide yes)
			(effects
				(font
					(size 1.016 1.016)
					(thickness 0.1524)
				)
			)
		)
		(property "Device Type" "R402H16"
			(at 0.064008 -5.517896 0)
			(unlocked yes)
			(layer "F.Fab")
			(hide yes)
			(effects
				(font
					(size 1.016 1.016)
					(thickness 0.1524)
				)
			)
		)
		(duplicate_pad_numbers_are_jumpers no)
		(fp_line
			(start -0.508 -0.9398)
			(end -0.508 0.9398)
			(stroke
				(width 0.1524)
				(type default)
			)
			(layer "F.SilkS")
		)
		(fp_line
			(start 0.508 -0.9398)
			(end -0.508 -0.9398)
			(stroke
				(width 0.1524)
				(type default)
			)
			(layer "F.SilkS")
		)
		(fp_rect
			(start -0.508 0.9398)
			(end 0.508 -0.9398)
			(stroke
				(width 0)
				(type default)
			)
			(fill no)
			(layer "F.CrtYd")
		)
		(fp_rect
			(start -0.508 0.9398)
			(end 0.508 -0.9398)
			(stroke
				(width 0)
				(type default)
			)
			(fill no)
			(layer "F.Fab")
		)
		(pad "1" smd custom
			(at 0 -0.4445)
			(size 0.1397 0.1397)
			(layers "F.Cu" "F.Mask" "F.Paste")
			(net "P3V3_STBY")
			(options
				(clearance outline)
				(anchor circle)
			)
			(primitives
				(gr_poly
					(pts
						(arc
							(start -0.1778 -0.2794)
							(mid -0.249642 -0.249642)
							(end -0.2794 -0.1778)
						)
						(arc
							(start -0.2794 0.1778)
							(mid -0.249642 0.249642)
							(end -0.1778 0.2794)
						)
						(arc
							(start 0.1778 0.2794)
							(mid 0.249642 0.249642)
							(end 0.2794 0.1778)
						)
						(arc
							(start 0.2794 -0.1778)
							(mid 0.249642 -0.249642)
							(end 0.1778 -0.2794)
						)
					)
					(width 0)
					(fill yes)
				)
			)
		)
		(pad "2" smd custom
			(at 0 0.4445)
			(size 0.1397 0.1397)
			(layers "F.Cu" "F.Mask" "F.Paste")
			(net "SYS_RST_BTN_IN_N")
			(options
				(clearance outline)
				(anchor circle)
			)
			(primitives
				(gr_poly
					(pts
						(arc
							(start -0.1778 -0.2794)
							(mid -0.249642 -0.249642)
							(end -0.2794 -0.1778)
						)
						(arc
							(start -0.2794 0.1778)
							(mid -0.249642 0.249642)
							(end -0.1778 0.2794)
						)
						(arc
							(start 0.1778 0.2794)
							(mid 0.249642 0.249642)
							(end 0.2794 0.1778)
						)
						(arc
							(start 0.2794 -0.1778)
							(mid 0.249642 -0.249642)
							(end 0.1778 -0.2794)
						)
					)
					(width 0)
					(fill yes)
				)
			)
		)
	)
	(footprint ""
		(layer "F.Cu")
		(at 86.863428 -65.144396 -90)
		(property "Reference" "R8"
			(at 0 0 270)
			(layer "F.SilkS")
			(hide yes)
			(effects
				(font
					(size 1.27 1.27)
				)
			)
		)
		(property "Value" "0R2J-2-GP"
			(at 0.064008 -3.993896 270)
			(unlocked yes)
			(layer "F.Fab")
			(hide yes)
			(effects
				(font
					(size 1.016 1.016)
					(thickness 0.1524)
				)
			)
		)
		(property "Device Type" "R402H16"
			(at 0.064008 -5.517896 270)
			(unlocked yes)
			(layer "F.Fab")
			(hide yes)
			(effects
				(font
					(size 1.016 1.016)
					(thickness 0.1524)
				)
			)
		)
		(duplicate_pad_numbers_are_jumpers no)
		(fp_line
			(start -0.508 -0.9398)
			(end -0.508 0.9398)
			(stroke
				(width 0.1524)
				(type default)
			)
			(layer "F.SilkS")
		)
		(fp_line
			(start 0.508 -0.9398)
			(end -0.508 -0.9398)
			(stroke
				(width 0.1524)
				(type default)
			)
			(layer "F.SilkS")
		)
		(fp_rect
			(start -0.508 0.9398)
			(end 0.508 -0.9398)
			(stroke
				(width 0)
				(type default)
			)
			(fill no)
			(layer "F.CrtYd")
		)
		(fp_rect
			(start -0.508 0.9398)
			(end 0.508 -0.9398)
			(stroke
				(width 0)
				(type default)
			)
			(fill no)
			(layer "F.Fab")
		)
		(pad "1" smd custom
			(at 0 -0.4445 270)
			(size 0.1397 0.1397)
			(layers "F.Cu" "F.Mask" "F.Paste")
			(net "PCIE_COMP_TO_IOM_RST_4")
			(options
				(clearance outline)
				(anchor circle)
			)
			(primitives
				(gr_poly
					(pts
						(arc
							(start -0.1778 -0.2794)
							(mid -0.249642 -0.249642)
							(end -0.2794 -0.1778)
						)
						(arc
							(start -0.2794 0.1778)
							(mid -0.249642 0.249642)
							(end -0.1778 0.2794)
						)
						(arc
							(start 0.1778 0.2794)
							(mid 0.249642 0.249642)
							(end 0.2794 0.1778)
						)
						(arc
							(start 0.2794 -0.1778)
							(mid 0.249642 -0.249642)
							(end 0.1778 -0.2794)
						)
					)
					(width 0)
					(fill yes)
				)
			)
		)
		(pad "2" smd custom
			(at 0 0.4445 270)
			(size 0.1397 0.1397)
			(layers "F.Cu" "F.Mask" "F.Paste")
			(net "PCIE_COMP_TO_IOM_RST_4_R")
			(options
				(clearance outline)
				(anchor circle)
			)
			(primitives
				(gr_poly
					(pts
						(arc
							(start -0.1778 -0.2794)
							(mid -0.249642 -0.249642)
							(end -0.2794 -0.1778)
						)
						(arc
							(start -0.2794 0.1778)
							(mid -0.249642 0.249642)
							(end -0.1778 0.2794)
						)
						(arc
							(start 0.1778 0.2794)
							(mid 0.249642 0.249642)
							(end 0.2794 0.1778)
						)
						(arc
							(start 0.2794 -0.1778)
							(mid 0.249642 -0.249642)
							(end 0.1778 -0.2794)
						)
					)
					(width 0)
					(fill yes)
				)
			)
		)
	)
	(footprint ""
		(layer "F.Cu")
		(at 61.3664 -152.654 90)
		(property "Reference" "R340"
			(at 0 0 90)
			(layer "F.SilkS")
			(hide yes)
			(effects
				(font
					(size 1.27 1.27)
				)
			)
		)
		(property "Value" "8K2R2J-3-GP"
			(at 0.064008 -3.993896 90)
			(unlocked yes)
			(layer "F.Fab")
			(hide yes)
			(effects
				(font
					(size 1.016 1.016)
					(thickness 0.1524)
				)
			)
		)
		(property "Device Type" "R402H16"
			(at 0.064008 -5.517896 90)
			(unlocked yes)
			(layer "F.Fab")
			(hide yes)
			(effects
				(font
					(size 1.016 1.016)
					(thickness 0.1524)
				)
			)
		)
		(duplicate_pad_numbers_are_jumpers no)
		(fp_line
			(start 0.508 -0.9398)
			(end -0.508 -0.9398)
			(stroke
				(width 0.1524)
				(type default)
			)
			(layer "F.SilkS")
		)
		(fp_line
			(start -0.508 -0.9398)
			(end -0.508 0.9398)
			(stroke
				(width 0.1524)
				(type default)
			)
			(layer "F.SilkS")
		)
		(fp_rect
			(start -0.508 0.9398)
			(end 0.508 -0.9398)
			(stroke
				(width 0)
				(type default)
			)
			(fill no)
			(layer "F.CrtYd")
		)
		(fp_rect
			(start -0.508 0.9398)
			(end 0.508 -0.9398)
			(stroke
				(width 0)
				(type default)
			)
			(fill no)
			(layer "F.Fab")
		)
		(pad "1" smd custom
			(at 0 -0.4445 90)
			(size 0.1397 0.1397)
			(layers "F.Cu" "F.Mask" "F.Paste")
			(net "PD_USB2BVRES")
			(options
				(clearance outline)
				(anchor circle)
			)
			(primitives
				(gr_poly
					(pts
						(arc
							(start -0.1778 -0.2794)
							(mid -0.249642 -0.249642)
							(end -0.2794 -0.1778)
						)
						(arc
							(start -0.2794 0.1778)
							(mid -0.249642 0.249642)
							(end -0.1778 0.2794)
						)
						(arc
							(start 0.1778 0.2794)
							(mid 0.249642 0.249642)
							(end 0.2794 0.1778)
						)
						(arc
							(start 0.2794 -0.1778)
							(mid 0.249642 -0.249642)
							(end 0.1778 -0.2794)
						)
					)
					(width 0)
					(fill yes)
				)
			)
		)
		(pad "2" smd custom
			(at 0 0.4445 90)
			(size 0.1397 0.1397)
			(layers "F.Cu" "F.Mask" "F.Paste")
			(net "GND")
			(options
				(clearance outline)
				(anchor circle)
			)
			(primitives
				(gr_poly
					(pts
						(arc
							(start -0.1778 -0.2794)
							(mid -0.249642 -0.249642)
							(end -0.2794 -0.1778)
						)
						(arc
							(start -0.2794 0.1778)
							(mid -0.249642 0.249642)
							(end -0.1778 0.2794)
						)
						(arc
							(start 0.1778 0.2794)
							(mid 0.249642 0.249642)
							(end 0.2794 0.1778)
						)
						(arc
							(start 0.2794 -0.1778)
							(mid 0.249642 -0.249642)
							(end 0.1778 -0.2794)
						)
					)
					(width 0)
					(fill yes)
				)
			)
		)
	)
	(footprint ""
		(layer "F.Cu")
		(at 69.52488 -182.60568 90)
		(property "Reference" "R509"
			(at 0 0 90)
			(layer "F.SilkS")
			(hide yes)
			(effects
				(font
					(size 1.27 1.27)
				)
			)
		)
		(property "Value" "4K75R2F-1-GP"
			(at 0.064008 -3.993896 90)
			(unlocked yes)
			(layer "F.Fab")
			(hide yes)
			(effects
				(font
					(size 1.016 1.016)
					(thickness 0.1524)
				)
			)
		)
		(property "Device Type" "R402H16"
			(at 0.064008 -5.517896 90)
			(unlocked yes)
			(layer "F.Fab")
			(hide yes)
			(effects
				(font
					(size 1.016 1.016)
					(thickness 0.1524)
				)
			)
		)
		(duplicate_pad_numbers_are_jumpers no)
		(fp_line
			(start 0.508 -0.9398)
			(end -0.508 -0.9398)
			(stroke
				(width 0.1524)
				(type default)
			)
			(layer "F.SilkS")
		)
		(fp_line
			(start -0.508 -0.9398)
			(end -0.508 0.9398)
			(stroke
				(width 0.1524)
				(type default)
			)
			(layer "F.SilkS")
		)
		(fp_rect
			(start -0.508 0.9398)
			(end 0.508 -0.9398)
			(stroke
				(width 0)
				(type default)
			)
			(fill no)
			(layer "F.CrtYd")
		)
		(fp_rect
			(start -0.508 0.9398)
			(end 0.508 -0.9398)
			(stroke
				(width 0)
				(type default)
			)
			(fill no)
			(layer "F.Fab")
		)
		(pad "1" smd custom
			(at 0 -0.4445 90)
			(size 0.1397 0.1397)
			(layers "F.Cu" "F.Mask" "F.Paste")
			(net "P3V3_STBY")
			(options
				(clearance outline)
				(anchor circle)
			)
			(primitives
				(gr_poly
					(pts
						(arc
							(start -0.1778 -0.2794)
							(mid -0.249642 -0.249642)
							(end -0.2794 -0.1778)
						)
						(arc
							(start -0.2794 0.1778)
							(mid -0.249642 0.249642)
							(end -0.1778 0.2794)
						)
						(arc
							(start 0.1778 0.2794)
							(mid 0.249642 0.249642)
							(end 0.2794 0.1778)
						)
						(arc
							(start 0.2794 -0.1778)
							(mid 0.249642 -0.249642)
							(end 0.1778 -0.2794)
						)
					)
					(width 0)
					(fill yes)
				)
			)
		)
		(pad "2" smd custom
			(at 0 0.4445 90)
			(size 0.1397 0.1397)
			(layers "F.Cu" "F.Mask" "F.Paste")
			(net "TPS74801_P2V5_STBY_EN")
			(options
				(clearance outline)
				(anchor circle)
			)
			(primitives
				(gr_poly
					(pts
						(arc
							(start -0.1778 -0.2794)
							(mid -0.249642 -0.249642)
							(end -0.2794 -0.1778)
						)
						(arc
							(start -0.2794 0.1778)
							(mid -0.249642 0.249642)
							(end -0.1778 0.2794)
						)
						(arc
							(start 0.1778 0.2794)
							(mid 0.249642 0.249642)
							(end 0.2794 0.1778)
						)
						(arc
							(start 0.2794 -0.1778)
							(mid 0.249642 -0.249642)
							(end 0.1778 -0.2794)
						)
					)
					(width 0)
					(fill yes)
				)
			)
		)
	)
	(footprint ""
		(layer "F.Cu")
		(at 162.60064 -132.979922 180)
		(property "Reference" "R517"
			(at 0 0 180)
			(layer "F.SilkS")
			(hide yes)
			(effects
				(font
					(size 1.27 1.27)
				)
			)
		)
		(property "Value" "0R2J-2-GP"
			(at 0.064008 -3.993896 180)
			(unlocked yes)
			(layer "F.Fab")
			(hide yes)
			(effects
				(font
					(size 1.016 1.016)
					(thickness 0.1524)
				)
			)
		)
		(property "Device Type" "R402H16"
			(at 0.064008 -5.517896 180)
			(unlocked yes)
			(layer "F.Fab")
			(hide yes)
			(effects
				(font
					(size 1.016 1.016)
					(thickness 0.1524)
				)
			)
		)
		(duplicate_pad_numbers_are_jumpers no)
		(fp_line
			(start 0.508 -0.9398)
			(end -0.508 -0.9398)
			(stroke
				(width 0.1524)
				(type default)
			)
			(layer "F.SilkS")
		)
		(fp_line
			(start -0.508 -0.9398)
			(end -0.508 0.9398)
			(stroke
				(width 0.1524)
				(type default)
			)
			(layer "F.SilkS")
		)
		(fp_rect
			(start -0.508 0.9398)
			(end 0.508 -0.9398)
			(stroke
				(width 0)
				(type default)
			)
			(fill no)
			(layer "F.CrtYd")
		)
		(fp_rect
			(start -0.508 0.9398)
			(end 0.508 -0.9398)
			(stroke
				(width 0)
				(type default)
			)
			(fill no)
			(layer "F.Fab")
		)
		(pad "1" smd custom
			(at 0 -0.4445 180)
			(size 0.1397 0.1397)
			(layers "F.Cu" "F.Mask" "F.Paste")
			(net "P1V8_STBY_VBST_RR")
			(options
				(clearance outline)
				(anchor circle)
			)
			(primitives
				(gr_poly
					(pts
						(arc
							(start -0.1778 -0.2794)
							(mid -0.249642 -0.249642)
							(end -0.2794 -0.1778)
						)
						(arc
							(start -0.2794 0.1778)
							(mid -0.249642 0.249642)
							(end -0.1778 0.2794)
						)
						(arc
							(start 0.1778 0.2794)
							(mid 0.249642 0.249642)
							(end 0.2794 0.1778)
						)
						(arc
							(start 0.2794 -0.1778)
							(mid 0.249642 -0.249642)
							(end 0.1778 -0.2794)
						)
					)
					(width 0)
					(fill yes)
				)
			)
		)
		(pad "2" smd custom
			(at 0 0.4445 180)
			(size 0.1397 0.1397)
			(layers "F.Cu" "F.Mask" "F.Paste")
			(net "P1V8_STBY_VBST")
			(options
				(clearance outline)
				(anchor circle)
			)
			(primitives
				(gr_poly
					(pts
						(arc
							(start -0.1778 -0.2794)
							(mid -0.249642 -0.249642)
							(end -0.2794 -0.1778)
						)
						(arc
							(start -0.2794 0.1778)
							(mid -0.249642 0.249642)
							(end -0.1778 0.2794)
						)
						(arc
							(start 0.1778 0.2794)
							(mid 0.249642 0.249642)
							(end 0.2794 0.1778)
						)
						(arc
							(start 0.2794 -0.1778)
							(mid 0.249642 -0.249642)
							(end 0.1778 -0.2794)
						)
					)
					(width 0)
					(fill yes)
				)
			)
		)
	)
	(footprint ""
		(layer "F.Cu")
		(at 20.21078 -14.41704 180)
		(property "Reference" "R45"
			(at 0 0 180)
			(layer "F.SilkS")
			(hide yes)
			(effects
				(font
					(size 1.27 1.27)
				)
			)
		)
		(property "Value" "1MR2F-GP"
			(at 0.064008 -3.993896 180)
			(unlocked yes)
			(layer "F.Fab")
			(hide yes)
			(effects
				(font
					(size 1.016 1.016)
					(thickness 0.1524)
				)
			)
		)
		(property "Device Type" "R402H16"
			(at 0.064008 -5.517896 180)
			(unlocked yes)
			(layer "F.Fab")
			(hide yes)
			(effects
				(font
					(size 1.016 1.016)
					(thickness 0.1524)
				)
			)
		)
		(duplicate_pad_numbers_are_jumpers no)
		(fp_line
			(start 0.508 -0.9398)
			(end -0.508 -0.9398)
			(stroke
				(width 0.1524)
				(type default)
			)
			(layer "F.SilkS")
		)
		(fp_line
			(start -0.508 -0.9398)
			(end -0.508 0.9398)
			(stroke
				(width 0.1524)
				(type default)
			)
			(layer "F.SilkS")
		)
		(fp_rect
			(start -0.508 0.9398)
			(end 0.508 -0.9398)
			(stroke
				(width 0)
				(type default)
			)
			(fill no)
			(layer "F.CrtYd")
		)
		(fp_rect
			(start -0.508 0.9398)
			(end 0.508 -0.9398)
			(stroke
				(width 0)
				(type default)
			)
			(fill no)
			(layer "F.Fab")
		)
		(pad "1" smd custom
			(at 0 -0.4445 180)
			(size 0.1397 0.1397)
			(layers "F.Cu" "F.Mask" "F.Paste")
			(net "PWR_BTN_GND")
			(options
				(clearance outline)
				(anchor circle)
			)
			(primitives
				(gr_poly
					(pts
						(arc
							(start -0.1778 -0.2794)
							(mid -0.249642 -0.249642)
							(end -0.2794 -0.1778)
						)
						(arc
							(start -0.2794 0.1778)
							(mid -0.249642 0.249642)
							(end -0.1778 0.2794)
						)
						(arc
							(start 0.1778 0.2794)
							(mid 0.249642 0.249642)
							(end 0.2794 0.1778)
						)
						(arc
							(start 0.2794 -0.1778)
							(mid 0.249642 -0.249642)
							(end 0.1778 -0.2794)
						)
					)
					(width 0)
					(fill yes)
				)
			)
		)
		(pad "2" smd custom
			(at 0 0.4445 180)
			(size 0.1397 0.1397)
			(layers "F.Cu" "F.Mask" "F.Paste")
			(net "GND")
			(options
				(clearance outline)
				(anchor circle)
			)
			(primitives
				(gr_poly
					(pts
						(arc
							(start -0.1778 -0.2794)
							(mid -0.249642 -0.249642)
							(end -0.2794 -0.1778)
						)
						(arc
							(start -0.2794 0.1778)
							(mid -0.249642 0.249642)
							(end -0.1778 0.2794)
						)
						(arc
							(start 0.1778 0.2794)
							(mid 0.249642 0.249642)
							(end 0.2794 0.1778)
						)
						(arc
							(start 0.2794 -0.1778)
							(mid 0.249642 -0.249642)
							(end 0.1778 -0.2794)
						)
					)
					(width 0)
					(fill yes)
				)
			)
		)
	)
	(footprint ""
		(layer "F.Cu")
		(at 174.560738 -69.45122 90)
		(property "Reference" "R576"
			(at 0 0 90)
			(layer "F.SilkS")
			(hide yes)
			(effects
				(font
					(size 1.27 1.27)
				)
			)
		)
		(property "Value" "2K2R2F-GP"
			(at 0.064008 -3.993896 90)
			(unlocked yes)
			(layer "F.Fab")
			(hide yes)
			(effects
				(font
					(size 1.016 1.016)
					(thickness 0.1524)
				)
			)
		)
		(property "Device Type" "R402H16"
			(at 0.064008 -5.517896 90)
			(unlocked yes)
			(layer "F.Fab")
			(hide yes)
			(effects
				(font
					(size 1.016 1.016)
					(thickness 0.1524)
				)
			)
		)
		(duplicate_pad_numbers_are_jumpers no)
		(fp_line
			(start 0.508 -0.9398)
			(end -0.508 -0.9398)
			(stroke
				(width 0.1524)
				(type default)
			)
			(layer "F.SilkS")
		)
		(fp_line
			(start -0.508 -0.9398)
			(end -0.508 0.9398)
			(stroke
				(width 0.1524)
				(type default)
			)
			(layer "F.SilkS")
		)
		(fp_rect
			(start -0.508 0.9398)
			(end 0.508 -0.9398)
			(stroke
				(width 0)
				(type default)
			)
			(fill no)
			(layer "F.CrtYd")
		)
		(fp_rect
			(start -0.508 0.9398)
			(end 0.508 -0.9398)
			(stroke
				(width 0)
				(type default)
			)
			(fill no)
			(layer "F.Fab")
		)
		(pad "1" smd custom
			(at 0 -0.4445 90)
			(size 0.1397 0.1397)
			(layers "F.Cu" "F.Mask" "F.Paste")
			(net "P1V8")
			(options
				(clearance outline)
				(anchor circle)
			)
			(primitives
				(gr_poly
					(pts
						(arc
							(start -0.1778 -0.2794)
							(mid -0.249642 -0.249642)
							(end -0.2794 -0.1778)
						)
						(arc
							(start -0.2794 0.1778)
							(mid -0.249642 0.249642)
							(end -0.1778 0.2794)
						)
						(arc
							(start 0.1778 0.2794)
							(mid 0.249642 0.249642)
							(end 0.2794 0.1778)
						)
						(arc
							(start 0.2794 -0.1778)
							(mid 0.249642 -0.249642)
							(end 0.1778 -0.2794)
						)
					)
					(width 0)
					(fill yes)
				)
			)
		)
		(pad "2" smd custom
			(at 0 0.4445 90)
			(size 0.1397 0.1397)
			(layers "F.Cu" "F.Mask" "F.Paste")
			(net "IOC_SDA_1")
			(options
				(clearance outline)
				(anchor circle)
			)
			(primitives
				(gr_poly
					(pts
						(arc
							(start -0.1778 -0.2794)
							(mid -0.249642 -0.249642)
							(end -0.2794 -0.1778)
						)
						(arc
							(start -0.2794 0.1778)
							(mid -0.249642 0.249642)
							(end -0.1778 0.2794)
						)
						(arc
							(start 0.1778 0.2794)
							(mid 0.249642 0.249642)
							(end 0.2794 0.1778)
						)
						(arc
							(start 0.2794 -0.1778)
							(mid 0.249642 -0.249642)
							(end 0.1778 -0.2794)
						)
					)
					(width 0)
					(fill yes)
				)
			)
		)
	)
	(footprint ""
		(layer "F.Cu")
		(at 22.614636 -14.63929)
		(property "Reference" "R48"
			(at 0 0 0)
			(layer "F.SilkS")
			(hide yes)
			(effects
				(font
					(size 1.27 1.27)
				)
			)
		)
		(property "Value" "4K7R2F-GP"
			(at 0.064008 -3.993896 0)
			(unlocked yes)
			(layer "F.Fab")
			(hide yes)
			(effects
				(font
					(size 1.016 1.016)
					(thickness 0.1524)
				)
			)
		)
		(property "Device Type" "R402H16"
			(at 0.064008 -5.517896 0)
			(unlocked yes)
			(layer "F.Fab")
			(hide yes)
			(effects
				(font
					(size 1.016 1.016)
					(thickness 0.1524)
				)
			)
		)
		(duplicate_pad_numbers_are_jumpers no)
		(fp_line
			(start -0.508 -0.9398)
			(end -0.508 0.9398)
			(stroke
				(width 0.1524)
				(type default)
			)
			(layer "F.SilkS")
		)
		(fp_line
			(start 0.508 -0.9398)
			(end -0.508 -0.9398)
			(stroke
				(width 0.1524)
				(type default)
			)
			(layer "F.SilkS")
		)
		(fp_rect
			(start -0.508 0.9398)
			(end 0.508 -0.9398)
			(stroke
				(width 0)
				(type default)
			)
			(fill no)
			(layer "F.CrtYd")
		)
		(fp_rect
			(start -0.508 0.9398)
			(end 0.508 -0.9398)
			(stroke
				(width 0)
				(type default)
			)
			(fill no)
			(layer "F.Fab")
		)
		(pad "1" smd custom
			(at 0 -0.4445)
			(size 0.1397 0.1397)
			(layers "F.Cu" "F.Mask" "F.Paste")
			(net "P3V3_STBY")
			(options
				(clearance outline)
				(anchor circle)
			)
			(primitives
				(gr_poly
					(pts
						(arc
							(start -0.1778 -0.2794)
							(mid -0.249642 -0.249642)
							(end -0.2794 -0.1778)
						)
						(arc
							(start -0.2794 0.1778)
							(mid -0.249642 0.249642)
							(end -0.1778 0.2794)
						)
						(arc
							(start 0.1778 0.2794)
							(mid 0.249642 0.249642)
							(end 0.2794 0.1778)
						)
						(arc
							(start 0.2794 -0.1778)
							(mid 0.249642 -0.249642)
							(end 0.1778 -0.2794)
						)
					)
					(width 0)
					(fill yes)
				)
			)
		)
		(pad "2" smd custom
			(at 0 0.4445)
			(size 0.1397 0.1397)
			(layers "F.Cu" "F.Mask" "F.Paste")
			(net "FP_PWR_BTN_N")
			(options
				(clearance outline)
				(anchor circle)
			)
			(primitives
				(gr_poly
					(pts
						(arc
							(start -0.1778 -0.2794)
							(mid -0.249642 -0.249642)
							(end -0.2794 -0.1778)
						)
						(arc
							(start -0.2794 0.1778)
							(mid -0.249642 0.249642)
							(end -0.1778 0.2794)
						)
						(arc
							(start 0.1778 0.2794)
							(mid 0.249642 0.249642)
							(end 0.2794 0.1778)
						)
						(arc
							(start 0.2794 -0.1778)
							(mid 0.249642 -0.249642)
							(end 0.1778 -0.2794)
						)
					)
					(width 0)
					(fill yes)
				)
			)
		)
	)
	(footprint ""
		(layer "F.Cu")
		(at 94.810072 -12.502642 90)
		(property "Reference" "D14"
			(at 0 0 90)
			(layer "F.SilkS")
			(hide yes)
			(effects
				(font
					(size 1.27 1.27)
				)
			)
		)
		(property "Value" "PESD5V0S1BL-1-GP"
			(at 1.8923 -1.5621 90)
			(unlocked yes)
			(layer "F.Fab")
			(hide yes)
			(effects
				(font
					(size 1.016 1.016)
					(thickness 0.1524)
				)
			)
		)
		(property "Device Type" "SOD882-10D6-1H20"
			(at 1.8923 -3.0861 90)
			(unlocked yes)
			(layer "F.Fab")
			(hide yes)
			(effects
				(font
					(size 1.016 1.016)
					(thickness 0.1524)
				)
			)
		)
		(duplicate_pad_numbers_are_jumpers no)
		(fp_line
			(start -0.3048 -0.9271)
			(end 0.3048 -0.9271)
			(stroke
				(width 0.254)
				(type default)
			)
			(layer "F.SilkS")
		)
		(fp_rect
			(start -0.2921 0.4953)
			(end 0.2921 -0.4953)
			(stroke
				(width 0)
				(type default)
			)
			(fill no)
			(layer "F.CrtYd")
		)
		(fp_poly
			(pts
				(xy -0.4318 0.8001) (xy -0.4318 -0.266192) (xy -0.2921 -0.266192) (xy -0.2921 0.4953) (xy 0.2921 0.4953)
				(xy 0.2921 -0.4953) (xy -0.2921 -0.4953) (xy -0.2921 -0.2667) (xy -0.4318 -0.2667) (xy -0.4318 -0.8001)
				(xy 0.4318 -0.8001) (xy 0.4318 0.8001)
			)
			(stroke
				(width 0)
				(type default)
			)
			(fill no)
			(layer "F.CrtYd")
		)
		(fp_rect
			(start -0.4318 0.8001)
			(end 0.4318 -0.8001)
			(stroke
				(width 0)
				(type default)
			)
			(fill no)
			(layer "F.Fab")
		)
		(pad "1" smd custom
			(at 0 -0.4445 90)
			(size 0.1143 0.1143)
			(layers "F.Cu" "F.Mask" "F.Paste")
			(net "I2C_DEBUG_SCL")
			(options
				(clearance outline)
				(anchor circle)
			)
			(primitives
				(gr_poly
					(pts
						(arc
							(start -0.2032 0.2286)
							(mid -0.275042 0.198842)
							(end -0.3048 0.127)
						)
						(arc
							(start -0.3048 -0.127)
							(mid -0.275042 -0.198842)
							(end -0.2032 -0.2286)
						)
						(arc
							(start 0.2032 -0.2286)
							(mid 0.275042 -0.198842)
							(end 0.3048 -0.127)
						)
						(arc
							(start 0.3048 0.127)
							(mid 0.275042 0.198842)
							(end 0.2032 0.2286)
						)
					)
					(width 0)
					(fill yes)
				)
			)
		)
		(pad "2" smd custom
			(at 0 0.4445 90)
			(size 0.1143 0.1143)
			(layers "F.Cu" "F.Mask" "F.Paste")
			(net "GND")
			(options
				(clearance outline)
				(anchor circle)
			)
			(primitives
				(gr_poly
					(pts
						(arc
							(start 0.2032 -0.2286)
							(mid 0.275042 -0.198842)
							(end 0.3048 -0.127)
						)
						(arc
							(start 0.3048 0.127)
							(mid 0.275042 0.198842)
							(end 0.2032 0.2286)
						)
						(arc
							(start -0.2032 0.2286)
							(mid -0.275042 0.198842)
							(end -0.3048 0.127)
						)
						(arc
							(start -0.3048 -0.127)
							(mid -0.275042 -0.198842)
							(end -0.2032 -0.2286)
						)
					)
					(width 0)
					(fill yes)
				)
			)
		)
	)
	(footprint ""
		(layer "F.Cu")
		(at 198.4756 -113.5126 180)
		(property "Reference" "C258"
			(at 0 0 180)
			(layer "F.SilkS")
			(hide yes)
			(effects
				(font
					(size 1.27 1.27)
				)
			)
		)
		(property "Value" "SC22U6D3V6KX-2-GP"
			(at -0.0762 -5.1308 180)
			(unlocked yes)
			(layer "F.Fab")
			(hide yes)
			(effects
				(font
					(size 1.016 1.016)
					(thickness 0.1524)
				)
			)
		)
		(property "Device Type" "C1206H71"
			(at -0.127 -6.6548 180)
			(unlocked yes)
			(layer "F.Fab")
			(hide yes)
			(effects
				(font
					(size 1.016 1.016)
					(thickness 0.1524)
				)
			)
		)
		(duplicate_pad_numbers_are_jumpers no)
		(fp_line
			(start 1.016 2.2352)
			(end -1.016 2.2352)
			(stroke
				(width 0.1524)
				(type default)
			)
			(layer "F.SilkS")
		)
		(fp_line
			(start 1.016 0.8382)
			(end 1.016 2.2352)
			(stroke
				(width 0.1524)
				(type default)
			)
			(layer "F.SilkS")
		)
		(fp_line
			(start 1.016 -2.2352)
			(end 1.016 -0.8382)
			(stroke
				(width 0.1524)
				(type default)
			)
			(layer "F.SilkS")
		)
		(fp_line
			(start -1.016 2.2352)
			(end -1.016 0.8382)
			(stroke
				(width 0.1524)
				(type default)
			)
			(layer "F.SilkS")
		)
		(fp_line
			(start -1.016 -0.8382)
			(end -1.016 -2.2352)
			(stroke
				(width 0.1524)
				(type default)
			)
			(layer "F.SilkS")
		)
		(fp_line
			(start -1.016 -2.2352)
			(end 1.016 -2.2352)
			(stroke
				(width 0.1524)
				(type default)
			)
			(layer "F.SilkS")
		)
		(fp_rect
			(start -1.0922 2.3114)
			(end 1.0922 -2.3114)
			(stroke
				(width 0)
				(type default)
			)
			(fill no)
			(layer "F.CrtYd")
		)
		(fp_poly
			(pts
				(xy 1.0922 -2.3114) (xy 1.0922 2.3114) (xy -1.0922 2.3114) (xy -1.0922 -2.3114)
			)
			(stroke
				(width 0)
				(type default)
			)
			(fill no)
			(layer "F.Fab")
		)
		(pad "1" smd rect
			(at 0 -1.397 180)
			(size 1.651 1.27)
			(layers "F.Cu" "F.Mask" "F.Paste")
			(net "P0V975")
		)
		(pad "2" smd rect
			(at 0 1.397 180)
			(size 1.651 1.27)
			(layers "F.Cu" "F.Mask" "F.Paste")
			(net "GND")
		)
	)
	(footprint ""
		(layer "F.Cu")
		(at 175.006 -127.381)
		(property "Reference" "R526"
			(at 0 0 0)
			(layer "F.SilkS")
			(hide yes)
			(effects
				(font
					(size 1.27 1.27)
				)
			)
		)
		(property "Value" "4K7R2F-GP"
			(at 0.064008 -3.993896 0)
			(unlocked yes)
			(layer "F.Fab")
			(hide yes)
			(effects
				(font
					(size 1.016 1.016)
					(thickness 0.1524)
				)
			)
		)
		(property "Device Type" "R402H16"
			(at 0.064008 -5.517896 0)
			(unlocked yes)
			(layer "F.Fab")
			(hide yes)
			(effects
				(font
					(size 1.016 1.016)
					(thickness 0.1524)
				)
			)
		)
		(duplicate_pad_numbers_are_jumpers no)
		(fp_line
			(start -0.508 -0.9398)
			(end -0.508 0.9398)
			(stroke
				(width 0.1524)
				(type default)
			)
			(layer "F.SilkS")
		)
		(fp_line
			(start 0.508 -0.9398)
			(end -0.508 -0.9398)
			(stroke
				(width 0.1524)
				(type default)
			)
			(layer "F.SilkS")
		)
		(fp_rect
			(start -0.508 0.9398)
			(end 0.508 -0.9398)
			(stroke
				(width 0)
				(type default)
			)
			(fill no)
			(layer "F.CrtYd")
		)
		(fp_rect
			(start -0.508 0.9398)
			(end 0.508 -0.9398)
			(stroke
				(width 0)
				(type default)
			)
			(fill no)
			(layer "F.Fab")
		)
		(pad "1" smd custom
			(at 0 -0.4445)
			(size 0.1397 0.1397)
			(layers "F.Cu" "F.Mask" "F.Paste")
			(net "P3V3_STBY")
			(options
				(clearance outline)
				(anchor circle)
			)
			(primitives
				(gr_poly
					(pts
						(arc
							(start -0.1778 -0.2794)
							(mid -0.249642 -0.249642)
							(end -0.2794 -0.1778)
						)
						(arc
							(start -0.2794 0.1778)
							(mid -0.249642 0.249642)
							(end -0.1778 0.2794)
						)
						(arc
							(start 0.1778 0.2794)
							(mid 0.249642 0.249642)
							(end 0.2794 0.1778)
						)
						(arc
							(start 0.2794 -0.1778)
							(mid 0.249642 -0.249642)
							(end 0.1778 -0.2794)
						)
					)
					(width 0)
					(fill yes)
				)
			)
		)
		(pad "2" smd custom
			(at 0 0.4445)
			(size 0.1397 0.1397)
			(layers "F.Cu" "F.Mask" "F.Paste")
			(net "Q6_G")
			(options
				(clearance outline)
				(anchor circle)
			)
			(primitives
				(gr_poly
					(pts
						(arc
							(start -0.1778 -0.2794)
							(mid -0.249642 -0.249642)
							(end -0.2794 -0.1778)
						)
						(arc
							(start -0.2794 0.1778)
							(mid -0.249642 0.249642)
							(end -0.1778 0.2794)
						)
						(arc
							(start 0.1778 0.2794)
							(mid 0.249642 0.249642)
							(end 0.2794 0.1778)
						)
						(arc
							(start 0.2794 -0.1778)
							(mid 0.249642 -0.249642)
							(end 0.1778 -0.2794)
						)
					)
					(width 0)
					(fill yes)
				)
			)
		)
	)
	(footprint ""
		(layer "F.Cu")
		(at 91.64828 -149.488144 180)
		(property "Reference" "R24"
			(at 0 0 180)
			(layer "F.SilkS")
			(hide yes)
			(effects
				(font
					(size 1.27 1.27)
				)
			)
		)
		(property "Value" "10KR2F-2-GP"
			(at 0.064008 -3.993896 180)
			(unlocked yes)
			(layer "F.Fab")
			(hide yes)
			(effects
				(font
					(size 1.016 1.016)
					(thickness 0.1524)
				)
			)
		)
		(property "Device Type" "R402H16"
			(at 0.064008 -5.517896 180)
			(unlocked yes)
			(layer "F.Fab")
			(hide yes)
			(effects
				(font
					(size 1.016 1.016)
					(thickness 0.1524)
				)
			)
		)
		(duplicate_pad_numbers_are_jumpers no)
		(fp_line
			(start 0.508 -0.9398)
			(end -0.508 -0.9398)
			(stroke
				(width 0.1524)
				(type default)
			)
			(layer "F.SilkS")
		)
		(fp_line
			(start -0.508 -0.9398)
			(end -0.508 0.9398)
			(stroke
				(width 0.1524)
				(type default)
			)
			(layer "F.SilkS")
		)
		(fp_rect
			(start -0.508 0.9398)
			(end 0.508 -0.9398)
			(stroke
				(width 0)
				(type default)
			)
			(fill no)
			(layer "F.CrtYd")
		)
		(fp_rect
			(start -0.508 0.9398)
			(end 0.508 -0.9398)
			(stroke
				(width 0)
				(type default)
			)
			(fill no)
			(layer "F.Fab")
		)
		(pad "1" smd custom
			(at 0 -0.4445 180)
			(size 0.1397 0.1397)
			(layers "F.Cu" "F.Mask" "F.Paste")
			(net "P3V3_STBY")
			(options
				(clearance outline)
				(anchor circle)
			)
			(primitives
				(gr_poly
					(pts
						(arc
							(start -0.1778 -0.2794)
							(mid -0.249642 -0.249642)
							(end -0.2794 -0.1778)
						)
						(arc
							(start -0.2794 0.1778)
							(mid -0.249642 0.249642)
							(end -0.1778 0.2794)
						)
						(arc
							(start 0.1778 0.2794)
							(mid 0.249642 0.249642)
							(end 0.2794 0.1778)
						)
						(arc
							(start 0.2794 -0.1778)
							(mid 0.249642 -0.249642)
							(end 0.1778 -0.2794)
						)
					)
					(width 0)
					(fill yes)
				)
			)
		)
		(pad "2" smd custom
			(at 0 0.4445 180)
			(size 0.1397 0.1397)
			(layers "F.Cu" "F.Mask" "F.Paste")
			(net "USB_OCS_N1")
			(options
				(clearance outline)
				(anchor circle)
			)
			(primitives
				(gr_poly
					(pts
						(arc
							(start -0.1778 -0.2794)
							(mid -0.249642 -0.249642)
							(end -0.2794 -0.1778)
						)
						(arc
							(start -0.2794 0.1778)
							(mid -0.249642 0.249642)
							(end -0.1778 0.2794)
						)
						(arc
							(start 0.1778 0.2794)
							(mid 0.249642 0.249642)
							(end 0.2794 0.1778)
						)
						(arc
							(start 0.2794 -0.1778)
							(mid 0.249642 -0.249642)
							(end 0.1778 -0.2794)
						)
					)
					(width 0)
					(fill yes)
				)
			)
		)
	)
	(footprint ""
		(layer "F.Cu")
		(at 174.5234 -72.6186 90)
		(property "Reference" "R586"
			(at 0 0 90)
			(layer "F.SilkS")
			(hide yes)
			(effects
				(font
					(size 1.27 1.27)
				)
			)
		)
		(property "Value" "2K2R2F-GP"
			(at 0.064008 -3.993896 90)
			(unlocked yes)
			(layer "F.Fab")
			(hide yes)
			(effects
				(font
					(size 1.016 1.016)
					(thickness 0.1524)
				)
			)
		)
		(property "Device Type" "R402H16"
			(at 0.064008 -5.517896 90)
			(unlocked yes)
			(layer "F.Fab")
			(hide yes)
			(effects
				(font
					(size 1.016 1.016)
					(thickness 0.1524)
				)
			)
		)
		(duplicate_pad_numbers_are_jumpers no)
		(fp_line
			(start 0.508 -0.9398)
			(end -0.508 -0.9398)
			(stroke
				(width 0.1524)
				(type default)
			)
			(layer "F.SilkS")
		)
		(fp_line
			(start -0.508 -0.9398)
			(end -0.508 0.9398)
			(stroke
				(width 0.1524)
				(type default)
			)
			(layer "F.SilkS")
		)
		(fp_rect
			(start -0.508 0.9398)
			(end 0.508 -0.9398)
			(stroke
				(width 0)
				(type default)
			)
			(fill no)
			(layer "F.CrtYd")
		)
		(fp_rect
			(start -0.508 0.9398)
			(end 0.508 -0.9398)
			(stroke
				(width 0)
				(type default)
			)
			(fill no)
			(layer "F.Fab")
		)
		(pad "1" smd custom
			(at 0 -0.4445 90)
			(size 0.1397 0.1397)
			(layers "F.Cu" "F.Mask" "F.Paste")
			(net "P1V8")
			(options
				(clearance outline)
				(anchor circle)
			)
			(primitives
				(gr_poly
					(pts
						(arc
							(start -0.1778 -0.2794)
							(mid -0.249642 -0.249642)
							(end -0.2794 -0.1778)
						)
						(arc
							(start -0.2794 0.1778)
							(mid -0.249642 0.249642)
							(end -0.1778 0.2794)
						)
						(arc
							(start 0.1778 0.2794)
							(mid 0.249642 0.249642)
							(end 0.2794 0.1778)
						)
						(arc
							(start 0.2794 -0.1778)
							(mid 0.249642 -0.249642)
							(end 0.1778 -0.2794)
						)
					)
					(width 0)
					(fill yes)
				)
			)
		)
		(pad "2" smd custom
			(at 0 0.4445 90)
			(size 0.1397 0.1397)
			(layers "F.Cu" "F.Mask" "F.Paste")
			(net "IOC_SCL_4")
			(options
				(clearance outline)
				(anchor circle)
			)
			(primitives
				(gr_poly
					(pts
						(arc
							(start -0.1778 -0.2794)
							(mid -0.249642 -0.249642)
							(end -0.2794 -0.1778)
						)
						(arc
							(start -0.2794 0.1778)
							(mid -0.249642 0.249642)
							(end -0.1778 0.2794)
						)
						(arc
							(start 0.1778 0.2794)
							(mid 0.249642 0.249642)
							(end 0.2794 0.1778)
						)
						(arc
							(start 0.2794 -0.1778)
							(mid 0.249642 -0.249642)
							(end 0.1778 -0.2794)
						)
					)
					(width 0)
					(fill yes)
				)
			)
		)
	)
	(footprint ""
		(layer "F.Cu")
		(at 132.0546 -26.2001)
		(property "Reference" "TP2"
			(at 0 0 0)
			(layer "F.SilkS")
			(hide yes)
			(effects
				(font
					(size 1.27 1.27)
				)
			)
		)
		(property "Value" "TPAD28-2-GP"
			(at -0.0127 -1.6637 0)
			(unlocked yes)
			(layer "F.Fab")
			(hide yes)
			(effects
				(font
					(size 1.016 1.016)
					(thickness 0.1524)
				)
			)
		)
		(property "Device Type" "TPAD28"
			(at -0.0127 -3.1877 0)
			(unlocked yes)
			(layer "F.Fab")
			(hide yes)
			(effects
				(font
					(size 1.016 1.016)
					(thickness 0.1524)
				)
			)
		)
		(duplicate_pad_numbers_are_jumpers no)
		(fp_poly
			(pts
				(arc
					(start 0.3556 0)
					(mid -0.3556 0)
					(end 0.3556 0)
				)
			)
			(stroke
				(width 0)
				(type default)
			)
			(fill no)
			(layer "F.CrtYd")
		)
		(fp_poly
			(pts
				(arc
					(start 0.6096 0)
					(mid -0.6096 0)
					(end 0.6096 0)
				)
			)
			(stroke
				(width 0)
				(type default)
			)
			(fill no)
			(layer "F.Fab")
		)
		(pad "1" smd circle
			(at 0 0)
			(size 0.7112 0.7112)
			(layers "F.Cu" "F.Mask" "F.Paste")
			(net "PCIE_COMP_TO_IOM_CLK_3_DP")
		)
	)
	(footprint ""
		(layer "F.Cu")
		(at 79.11338 -133.677914 90)
		(property "Reference" "U45"
			(at 0 0 90)
			(layer "F.SilkS")
			(hide yes)
			(effects
				(font
					(size 1.27 1.27)
				)
			)
		)
		(property "Value" "PCA9306DCTT-GP"
			(at 0 -11.6332 90)
			(unlocked yes)
			(layer "F.Fab")
			(hide yes)
			(effects
				(font
					(size 1.016 1.016)
					(thickness 0.1524)
				)
			)
		)
		(property "Device Type" "SSOIC8H52"
			(at 0 -13.1572 90)
			(unlocked yes)
			(layer "F.Fab")
			(hide yes)
			(effects
				(font
					(size 1.016 1.016)
					(thickness 0.1524)
				)
			)
		)
		(duplicate_pad_numbers_are_jumpers no)
		(fp_line
			(start 1.0668 -0.5842)
			(end 1.0668 0.5842)
			(stroke
				(width 0.1524)
				(type default)
			)
			(layer "F.SilkS")
		)
		(fp_line
			(start -1.7018 -0.5842)
			(end 1.0668 -0.5842)
			(stroke
				(width 0.1524)
				(type default)
			)
			(layer "F.SilkS")
		)
		(fp_line
			(start -1.7018 -0.5842)
			(end -1.7018 2.286)
			(stroke
				(width 0.1524)
				(type default)
			)
			(layer "F.SilkS")
		)
		(fp_line
			(start -1.397 0)
			(end -1.7018 -0.3048)
			(stroke
				(width 0.1524)
				(type default)
			)
			(layer "F.SilkS")
		)
		(fp_line
			(start -1.397 0)
			(end -1.7018 0.3048)
			(stroke
				(width 0.1524)
				(type default)
			)
			(layer "F.SilkS")
		)
		(fp_line
			(start 1.0668 0.5842)
			(end -1.524 0.5842)
			(stroke
				(width 0.1524)
				(type default)
			)
			(layer "F.SilkS")
		)
		(fp_line
			(start -1.524 0.5842)
			(end -1.524 2.286)
			(stroke
				(width 0.508)
				(type default)
			)
			(layer "F.SilkS")
		)
		(fp_poly
			(pts
				(xy -1.1684 -0.5842) (xy 1.0668 -0.5842) (xy 1.0668 0.5842) (xy -1.1684 0.5842)
			)
			(stroke
				(width 0)
				(type default)
			)
			(fill yes)
			(layer "F.SilkS")
		)
		(fp_poly
			(pts
				(xy -1.778 2.54) (xy 1.778 2.54) (xy 1.778 -2.54) (xy -1.778 -2.54)
			)
			(stroke
				(width 0)
				(type default)
			)
			(fill no)
			(layer "F.CrtYd")
		)
		(fp_poly
			(pts
				(xy -1.778 -2.54) (xy 1.778 -2.54) (xy 1.778 2.54) (xy -1.778 2.54)
			)
			(stroke
				(width 0)
				(type default)
			)
			(fill no)
			(layer "F.Fab")
		)
		(pad "1" smd rect
			(at -0.97536 1.6256 90)
			(size 0.3556 1.524)
			(layers "F.Cu" "F.Mask" "F.Paste")
			(net "GND")
		)
		(pad "2" smd rect
			(at -0.32512 1.6256 90)
			(size 0.3556 1.524)
			(layers "F.Cu" "F.Mask" "F.Paste")
			(net "P3V3_STBY")
		)
		(pad "3" smd rect
			(at 0.32512 1.6256 90)
			(size 0.3556 1.524)
			(layers "F.Cu" "F.Mask" "F.Paste")
			(net "I2C_DEBUG_SCL")
		)
		(pad "4" smd rect
			(at 0.97536 1.6256 90)
			(size 0.3556 1.524)
			(layers "F.Cu" "F.Mask" "F.Paste")
			(net "I2C_DEBUG_SDA")
		)
		(pad "5" smd rect
			(at 0.97536 -1.6256 90)
			(size 0.3556 1.524)
			(layers "F.Cu" "F.Mask" "F.Paste")
			(net "I2C_DEBUG_SDA_L")
		)
		(pad "6" smd rect
			(at 0.32512 -1.6256 90)
			(size 0.3556 1.524)
			(layers "F.Cu" "F.Mask" "F.Paste")
			(net "I2C_DEBUG_SCL_L")
		)
		(pad "7" smd rect
			(at -0.32512 -1.6256 90)
			(size 0.3556 1.524)
			(layers "F.Cu" "F.Mask" "F.Paste")
			(net "P3V3_STBY")
		)
		(pad "8" smd rect
			(at -0.97536 -1.6256 90)
			(size 0.3556 1.524)
			(layers "F.Cu" "F.Mask" "F.Paste")
			(net "DEBUG_CARD_PRSNT")
		)
	)
	(footprint ""
		(layer "F.Cu")
		(at 191.287146 -133.290564)
		(property "Reference" "R556"
			(at 0 0 0)
			(layer "F.SilkS")
			(hide yes)
			(effects
				(font
					(size 1.27 1.27)
				)
			)
		)
		(property "Value" "10KR2F-2-GP"
			(at 0.064008 -3.993896 0)
			(unlocked yes)
			(layer "F.Fab")
			(hide yes)
			(effects
				(font
					(size 1.016 1.016)
					(thickness 0.1524)
				)
			)
		)
		(property "Device Type" "R402H16"
			(at 0.064008 -5.517896 0)
			(unlocked yes)
			(layer "F.Fab")
			(hide yes)
			(effects
				(font
					(size 1.016 1.016)
					(thickness 0.1524)
				)
			)
		)
		(duplicate_pad_numbers_are_jumpers no)
		(fp_line
			(start -0.508 -0.9398)
			(end -0.508 0.9398)
			(stroke
				(width 0.1524)
				(type default)
			)
			(layer "F.SilkS")
		)
		(fp_line
			(start 0.508 -0.9398)
			(end -0.508 -0.9398)
			(stroke
				(width 0.1524)
				(type default)
			)
			(layer "F.SilkS")
		)
		(fp_rect
			(start -0.508 0.9398)
			(end 0.508 -0.9398)
			(stroke
				(width 0)
				(type default)
			)
			(fill no)
			(layer "F.CrtYd")
		)
		(fp_rect
			(start -0.508 0.9398)
			(end 0.508 -0.9398)
			(stroke
				(width 0)
				(type default)
			)
			(fill no)
			(layer "F.Fab")
		)
		(pad "1" smd custom
			(at 0 -0.4445)
			(size 0.1397 0.1397)
			(layers "F.Cu" "F.Mask" "F.Paste")
			(net "P3V3_STBY")
			(options
				(clearance outline)
				(anchor circle)
			)
			(primitives
				(gr_poly
					(pts
						(arc
							(start -0.1778 -0.2794)
							(mid -0.249642 -0.249642)
							(end -0.2794 -0.1778)
						)
						(arc
							(start -0.2794 0.1778)
							(mid -0.249642 0.249642)
							(end -0.1778 0.2794)
						)
						(arc
							(start 0.1778 0.2794)
							(mid 0.249642 0.249642)
							(end 0.2794 0.1778)
						)
						(arc
							(start 0.2794 -0.1778)
							(mid 0.249642 -0.249642)
							(end 0.1778 -0.2794)
						)
					)
					(width 0)
					(fill yes)
				)
			)
		)
		(pad "2" smd custom
			(at 0 0.4445)
			(size 0.1397 0.1397)
			(layers "F.Cu" "F.Mask" "F.Paste")
			(net "VT235_EN")
			(options
				(clearance outline)
				(anchor circle)
			)
			(primitives
				(gr_poly
					(pts
						(arc
							(start -0.1778 -0.2794)
							(mid -0.249642 -0.249642)
							(end -0.2794 -0.1778)
						)
						(arc
							(start -0.2794 0.1778)
							(mid -0.249642 0.249642)
							(end -0.1778 0.2794)
						)
						(arc
							(start 0.1778 0.2794)
							(mid 0.249642 0.249642)
							(end 0.2794 0.1778)
						)
						(arc
							(start 0.2794 -0.1778)
							(mid 0.249642 -0.249642)
							(end 0.1778 -0.2794)
						)
					)
					(width 0)
					(fill yes)
				)
			)
		)
	)
	(footprint ""
		(layer "F.Cu")
		(at 176.8348 -76.6318 90)
		(property "Reference" "TP96"
			(at 0 0 90)
			(layer "F.SilkS")
			(hide yes)
			(effects
				(font
					(size 1.27 1.27)
				)
			)
		)
		(property "Value" "TPAD28-2-GP"
			(at -0.0127 -1.6637 90)
			(unlocked yes)
			(layer "F.Fab")
			(hide yes)
			(effects
				(font
					(size 1.016 1.016)
					(thickness 0.1524)
				)
			)
		)
		(property "Device Type" "TPAD28"
			(at -0.0127 -3.1877 90)
			(unlocked yes)
			(layer "F.Fab")
			(hide yes)
			(effects
				(font
					(size 1.016 1.016)
					(thickness 0.1524)
				)
			)
		)
		(duplicate_pad_numbers_are_jumpers no)
		(fp_poly
			(pts
				(arc
					(start 0 0.3556)
					(mid 0 -0.3556)
					(end 0 0.3556)
				)
			)
			(stroke
				(width 0)
				(type default)
			)
			(fill no)
			(layer "F.CrtYd")
		)
		(fp_poly
			(pts
				(arc
					(start 0 0.6096)
					(mid 0 -0.6096)
					(end 0 0.6096)
				)
			)
			(stroke
				(width 0)
				(type default)
			)
			(fill no)
			(layer "F.Fab")
		)
		(pad "1" smd circle
			(at 0 0 90)
			(size 0.7112 0.7112)
			(layers "F.Cu" "F.Mask" "F.Paste")
			(net "IOC_GPIO_11")
		)
	)
	(footprint ""
		(layer "F.Cu")
		(at 177.2539 -51.70424 90)
		(property "Reference" "R729"
			(at 0 0 90)
			(layer "F.SilkS")
			(hide yes)
			(effects
				(font
					(size 1.27 1.27)
				)
			)
		)
		(property "Value" "10KR2F-2-GP"
			(at 0.064008 -3.993896 90)
			(unlocked yes)
			(layer "F.Fab")
			(hide yes)
			(effects
				(font
					(size 1.016 1.016)
					(thickness 0.1524)
				)
			)
		)
		(property "Device Type" "R402H16"
			(at 0.064008 -5.517896 90)
			(unlocked yes)
			(layer "F.Fab")
			(hide yes)
			(effects
				(font
					(size 1.016 1.016)
					(thickness 0.1524)
				)
			)
		)
		(duplicate_pad_numbers_are_jumpers no)
		(fp_line
			(start 0.508 -0.9398)
			(end -0.508 -0.9398)
			(stroke
				(width 0.1524)
				(type default)
			)
			(layer "F.SilkS")
		)
		(fp_line
			(start -0.508 -0.9398)
			(end -0.508 0.9398)
			(stroke
				(width 0.1524)
				(type default)
			)
			(layer "F.SilkS")
		)
		(fp_rect
			(start -0.508 0.9398)
			(end 0.508 -0.9398)
			(stroke
				(width 0)
				(type default)
			)
			(fill no)
			(layer "F.CrtYd")
		)
		(fp_rect
			(start -0.508 0.9398)
			(end 0.508 -0.9398)
			(stroke
				(width 0)
				(type default)
			)
			(fill no)
			(layer "F.Fab")
		)
		(pad "1" smd custom
			(at 0 -0.4445 90)
			(size 0.1397 0.1397)
			(layers "F.Cu" "F.Mask" "F.Paste")
			(net "P1V8")
			(options
				(clearance outline)
				(anchor circle)
			)
			(primitives
				(gr_poly
					(pts
						(arc
							(start -0.1778 -0.2794)
							(mid -0.249642 -0.249642)
							(end -0.2794 -0.1778)
						)
						(arc
							(start -0.2794 0.1778)
							(mid -0.249642 0.249642)
							(end -0.1778 0.2794)
						)
						(arc
							(start 0.1778 0.2794)
							(mid 0.249642 0.249642)
							(end 0.2794 0.1778)
						)
						(arc
							(start 0.2794 -0.1778)
							(mid 0.249642 -0.249642)
							(end 0.1778 -0.2794)
						)
					)
					(width 0)
					(fill yes)
				)
			)
		)
		(pad "2" smd custom
			(at 0 0.4445 90)
			(size 0.1397 0.1397)
			(layers "F.Cu" "F.Mask" "F.Paste")
			(net "XM_OE_N")
			(options
				(clearance outline)
				(anchor circle)
			)
			(primitives
				(gr_poly
					(pts
						(arc
							(start -0.1778 -0.2794)
							(mid -0.249642 -0.249642)
							(end -0.2794 -0.1778)
						)
						(arc
							(start -0.2794 0.1778)
							(mid -0.249642 0.249642)
							(end -0.1778 0.2794)
						)
						(arc
							(start 0.1778 0.2794)
							(mid 0.249642 0.249642)
							(end 0.2794 0.1778)
						)
						(arc
							(start 0.2794 -0.1778)
							(mid 0.249642 -0.249642)
							(end 0.1778 -0.2794)
						)
					)
					(width 0)
					(fill yes)
				)
			)
		)
	)
	(footprint ""
		(layer "F.Cu")
		(at 157.099 -122.174 -90)
		(property "Reference" "C217"
			(at 0 0 270)
			(layer "F.SilkS")
			(hide yes)
			(effects
				(font
					(size 1.27 1.27)
				)
			)
		)
		(property "Value" "SC10U6D3V5KX-4GP"
			(at -0.0762 -6.1214 270)
			(unlocked yes)
			(layer "F.Fab")
			(hide yes)
			(effects
				(font
					(size 1.016 1.016)
					(thickness 0.1524)
				)
			)
		)
		(property "Device Type" "C805H58"
			(at -0.0762 -8.1534 270)
			(unlocked yes)
			(layer "F.Fab")
			(hide yes)
			(effects
				(font
					(size 1.016 1.016)
					(thickness 0.1524)
				)
			)
		)
		(duplicate_pad_numbers_are_jumpers no)
		(fp_line
			(start 0.635 0)
			(end -0.635 0)
			(stroke
				(width 0.508)
				(type default)
			)
			(layer "F.SilkS")
		)
		(fp_rect
			(start -0.9652 1.778)
			(end 0.9652 -1.778)
			(stroke
				(width 0)
				(type default)
			)
			(fill no)
			(layer "F.CrtYd")
		)
		(fp_poly
			(pts
				(xy -0.9652 -1.778) (xy 0.9652 -1.778) (xy 0.9652 1.778) (xy -0.9652 1.778)
			)
			(stroke
				(width 0)
				(type default)
			)
			(fill no)
			(layer "F.Fab")
		)
		(pad "1" smd rect
			(at 0 -0.9652 270)
			(size 1.397 1.143)
			(layers "F.Cu" "F.Mask" "F.Paste")
			(net "P1V8_STBY")
		)
		(pad "2" smd rect
			(at 0 0.9652 270)
			(size 1.397 1.143)
			(layers "F.Cu" "F.Mask" "F.Paste")
			(net "GND")
		)
	)
	(footprint ""
		(layer "F.Cu")
		(at 182.8546 -146.3802 -90)
		(property "Reference" "G2"
			(at 0 0 270)
			(layer "F.SilkS")
			(hide yes)
			(effects
				(font
					(size 1.27 1.27)
				)
			)
		)
		(property "Value" "COPPER-CLOSE-GP-U"
			(at 0.0762 -2.8702 270)
			(unlocked yes)
			(layer "F.Fab")
			(hide yes)
			(effects
				(font
					(size 1.016 1.016)
					(thickness 0.1524)
				)
			)
		)
		(property "Device Type" "CON2C-U"
			(at 0.0762 -4.3942 270)
			(unlocked yes)
			(layer "F.Fab")
			(hide yes)
			(effects
				(font
					(size 1.016 1.016)
					(thickness 0.1524)
				)
			)
		)
		(duplicate_pad_numbers_are_jumpers no)
		(fp_rect
			(start -0.9398 0.9652)
			(end 0.9398 -0.9652)
			(stroke
				(width 0)
				(type default)
			)
			(fill no)
			(layer "F.CrtYd")
		)
		(fp_rect
			(start -0.9398 0.9652)
			(end 0.9398 -0.9652)
			(stroke
				(width 0)
				(type default)
			)
			(fill no)
			(layer "F.Fab")
		)
		(pad "1" smd custom
			(at 0 -0.5334 270)
			(size 0.17145 0.17145)
			(layers "F.Cu" "F.Mask" "F.Paste")
			(net "AGND_P5V")
			(options
				(clearance outline)
				(anchor circle)
			)
			(primitives
				(gr_poly
					(pts
						(xy -0.127 0.3429) (xy -0.127 0.1651) (xy -0.635 -0.3429) (xy 0.635 -0.3429) (xy 0.127 0.1651)
						(xy 0.127 0.3429)
					)
					(width 0)
					(fill yes)
				)
			)
		)
		(pad "2" smd custom
			(at 0 0.5334 270)
			(size 0.17145 0.17145)
			(layers "F.Cu" "F.Mask" "F.Paste")
			(net "GND")
			(options
				(clearance outline)
				(anchor circle)
			)
			(primitives
				(gr_poly
					(pts
						(xy -0.635 0.3429) (xy -0.127 -0.1651) (xy -0.127 -0.3429) (xy 0.127 -0.3429) (xy 0.127 -0.1651)
						(xy 0.635 0.3429)
					)
					(width 0)
					(fill yes)
				)
			)
		)
	)
	(footprint ""
		(layer "F.Cu")
		(at 208.68132 -84.393786 135)
		(property "Reference" "VIA26"
			(at 0 0 135)
			(layer "F.SilkS")
			(hide yes)
			(effects
				(font
					(size 1.27 1.27)
				)
			)
		)
		(property "Value" "85OHM-8L-1D6MM-L16L18-GP"
			(at 4.063925 0.609475 135)
			(unlocked yes)
			(layer "F.Fab")
			(hide yes)
			(effects
				(font
					(size 1.016 1.016)
					(thickness 0.1524)
				)
			)
		)
		(property "Device Type" "VIA-PCIE-4P-368076"
			(at 4.064105 -0.914474 135)
			(unlocked yes)
			(layer "F.Fab")
			(hide yes)
			(effects
				(font
					(size 1.016 1.016)
					(thickness 0.1524)
				)
			)
		)
		(duplicate_pad_numbers_are_jumpers no)
		(fp_poly
			(pts
				(xy -1.841491 -0.381057) (xy 1.841509 -0.381058) (xy 1.841508 0.380942) (xy -1.841491 0.380942)
			)
			(stroke
				(width 0)
				(type default)
			)
			(fill no)
			(layer "F.CrtYd")
		)
		(fp_poly
			(pts
				(xy -1.841491 -0.381057) (xy 1.841509 -0.381058) (xy 1.841508 0.380942) (xy -1.841491 0.380942)
			)
			(stroke
				(width 0)
				(type default)
			)
			(fill no)
			(layer "F.Fab")
		)
		(pad "1" thru_hole circle
			(at -1.460499 0 135)
			(size 0.508 0.508)
			(drill 0.254)
			(layers "*.Cu" "*.Mask")
			(remove_unused_layers no)
			(net "GND")
			(clearance 0.127)
			(thermal_gap 0.127)
		)
		(pad "2" thru_hole circle
			(at -0.4445 0 135)
			(size 0.508 0.508)
			(drill 0.254)
			(layers "*.Cu" "*.Mask")
			(remove_unused_layers no)
			(net "PCIE_COMP_TO_IOM_CLK_2_DP")
			(clearance 0.127)
			(thermal_gap 0.127)
		)
		(pad "3" thru_hole circle
			(at 0.4445 0 135)
			(size 0.508 0.508)
			(drill 0.254)
			(layers "*.Cu" "*.Mask")
			(remove_unused_layers no)
			(net "PCIE_COMP_TO_IOM_CLK_2_DN")
			(clearance 0.127)
			(thermal_gap 0.127)
		)
		(pad "4" thru_hole circle
			(at 1.460499 0 135)
			(size 0.508 0.508)
			(drill 0.254)
			(layers "*.Cu" "*.Mask")
			(remove_unused_layers no)
			(net "GND")
			(clearance 0.127)
			(thermal_gap 0.127)
		)
	)
	(footprint ""
		(layer "F.Cu")
		(at 34.151062 -154.883358 -90)
		(property "Reference" "R322"
			(at 0 0 270)
			(layer "F.SilkS")
			(hide yes)
			(effects
				(font
					(size 1.27 1.27)
				)
			)
		)
		(property "Value" "0R2J-2-GP"
			(at 0.064008 -3.993896 270)
			(unlocked yes)
			(layer "F.Fab")
			(hide yes)
			(effects
				(font
					(size 1.016 1.016)
					(thickness 0.1524)
				)
			)
		)
		(property "Device Type" "R402H16"
			(at 0.064008 -5.517896 270)
			(unlocked yes)
			(layer "F.Fab")
			(hide yes)
			(effects
				(font
					(size 1.016 1.016)
					(thickness 0.1524)
				)
			)
		)
		(duplicate_pad_numbers_are_jumpers no)
		(fp_line
			(start -0.508 -0.9398)
			(end -0.508 0.9398)
			(stroke
				(width 0.1524)
				(type default)
			)
			(layer "F.SilkS")
		)
		(fp_line
			(start 0.508 -0.9398)
			(end -0.508 -0.9398)
			(stroke
				(width 0.1524)
				(type default)
			)
			(layer "F.SilkS")
		)
		(fp_rect
			(start -0.508 0.9398)
			(end 0.508 -0.9398)
			(stroke
				(width 0)
				(type default)
			)
			(fill no)
			(layer "F.CrtYd")
		)
		(fp_rect
			(start -0.508 0.9398)
			(end 0.508 -0.9398)
			(stroke
				(width 0)
				(type default)
			)
			(fill no)
			(layer "F.Fab")
		)
		(pad "1" smd custom
			(at 0 -0.4445 270)
			(size 0.1397 0.1397)
			(layers "F.Cu" "F.Mask" "F.Paste")
			(net "COMP_POWER_FAIL_R_N")
			(options
				(clearance outline)
				(anchor circle)
			)
			(primitives
				(gr_poly
					(pts
						(arc
							(start -0.1778 -0.2794)
							(mid -0.249642 -0.249642)
							(end -0.2794 -0.1778)
						)
						(arc
							(start -0.2794 0.1778)
							(mid -0.249642 0.249642)
							(end -0.1778 0.2794)
						)
						(arc
							(start 0.1778 0.2794)
							(mid 0.249642 0.249642)
							(end 0.2794 0.1778)
						)
						(arc
							(start 0.2794 -0.1778)
							(mid 0.249642 -0.249642)
							(end 0.1778 -0.2794)
						)
					)
					(width 0)
					(fill yes)
				)
			)
		)
		(pad "2" smd custom
			(at 0 0.4445 270)
			(size 0.1397 0.1397)
			(layers "F.Cu" "F.Mask" "F.Paste")
			(net "COMP_POWER_FAIL_N")
			(options
				(clearance outline)
				(anchor circle)
			)
			(primitives
				(gr_poly
					(pts
						(arc
							(start -0.1778 -0.2794)
							(mid -0.249642 -0.249642)
							(end -0.2794 -0.1778)
						)
						(arc
							(start -0.2794 0.1778)
							(mid -0.249642 0.249642)
							(end -0.1778 0.2794)
						)
						(arc
							(start 0.1778 0.2794)
							(mid 0.249642 0.249642)
							(end 0.2794 0.1778)
						)
						(arc
							(start 0.2794 -0.1778)
							(mid 0.249642 -0.249642)
							(end 0.1778 -0.2794)
						)
					)
					(width 0)
					(fill yes)
				)
			)
		)
	)
	(footprint ""
		(layer "F.Cu")
		(at 52.59324 -160.38068)
		(property "Reference" "C86"
			(at 0 0 0)
			(layer "F.SilkS")
			(hide yes)
			(effects
				(font
					(size 1.27 1.27)
				)
			)
		)
		(property "Value" "SCD1U16V2KX-3GP"
			(at 1.1811 -2.7051 0)
			(unlocked yes)
			(layer "F.Fab")
			(hide yes)
			(effects
				(font
					(size 1.016 1.016)
					(thickness 0.1524)
				)
			)
		)
		(property "Device Type" "C402H22"
			(at 1.1811 -4.2291 0)
			(unlocked yes)
			(layer "F.Fab")
			(hide yes)
			(effects
				(font
					(size 1.016 1.016)
					(thickness 0.1524)
				)
			)
		)
		(duplicate_pad_numbers_are_jumpers no)
		(fp_rect
			(start -0.4318 0.9525)
			(end 0.4318 -0.9525)
			(stroke
				(width 0)
				(type default)
			)
			(fill no)
			(layer "F.CrtYd")
		)
		(fp_rect
			(start -0.4318 0.9525)
			(end 0.4318 -0.9525)
			(stroke
				(width 0)
				(type default)
			)
			(fill no)
			(layer "F.Fab")
		)
		(pad "1" smd custom
			(at 0 -0.4445)
			(size 0.1524 0.1524)
			(layers "F.Cu" "F.Mask" "F.Paste")
			(net "ADCVREFFN")
			(options
				(clearance outline)
				(anchor circle)
			)
			(primitives
				(gr_poly
					(pts
						(arc
							(start 0.3048 -0.2032)
							(mid 0.275042 -0.275042)
							(end 0.2032 -0.3048)
						)
						(arc
							(start -0.2032 -0.3048)
							(mid -0.275042 -0.275042)
							(end -0.3048 -0.2032)
						)
						(arc
							(start -0.3048 0.2032)
							(mid -0.275042 0.275042)
							(end -0.2032 0.3048)
						)
						(arc
							(start 0.2032 0.3048)
							(mid 0.275042 0.275042)
							(end 0.3048 0.2032)
						)
					)
					(width 0)
					(fill yes)
				)
			)
		)
		(pad "2" smd custom
			(at 0 0.4445)
			(size 0.1524 0.1524)
			(layers "F.Cu" "F.Mask" "F.Paste")
			(net "ADCVREFFP")
			(options
				(clearance outline)
				(anchor circle)
			)
			(primitives
				(gr_poly
					(pts
						(arc
							(start 0.3048 -0.2032)
							(mid 0.275042 -0.275042)
							(end 0.2032 -0.3048)
						)
						(arc
							(start -0.2032 -0.3048)
							(mid -0.275042 -0.275042)
							(end -0.3048 -0.2032)
						)
						(arc
							(start -0.3048 0.2032)
							(mid -0.275042 0.275042)
							(end -0.2032 0.3048)
						)
						(arc
							(start 0.2032 0.3048)
							(mid 0.275042 0.275042)
							(end 0.3048 0.2032)
						)
					)
					(width 0)
					(fill yes)
				)
			)
		)
	)
	(footprint ""
		(layer "F.Cu")
		(at 174.1424 -38.4556)
		(property "Reference" "TP176"
			(at 0 0 0)
			(layer "F.SilkS")
			(hide yes)
			(effects
				(font
					(size 1.27 1.27)
				)
			)
		)
		(property "Value" "TPAD28-2-GP"
			(at -0.0127 -1.6637 0)
			(unlocked yes)
			(layer "F.Fab")
			(hide yes)
			(effects
				(font
					(size 1.016 1.016)
					(thickness 0.1524)
				)
			)
		)
		(property "Device Type" "TPAD28"
			(at -0.0127 -3.1877 0)
			(unlocked yes)
			(layer "F.Fab")
			(hide yes)
			(effects
				(font
					(size 1.016 1.016)
					(thickness 0.1524)
				)
			)
		)
		(duplicate_pad_numbers_are_jumpers no)
		(fp_poly
			(pts
				(arc
					(start 0.3556 0)
					(mid -0.3556 0)
					(end 0.3556 0)
				)
			)
			(stroke
				(width 0)
				(type default)
			)
			(fill no)
			(layer "F.CrtYd")
		)
		(fp_poly
			(pts
				(arc
					(start 0.6096 0)
					(mid -0.6096 0)
					(end 0.6096 0)
				)
			)
			(stroke
				(width 0)
				(type default)
			)
			(fill no)
			(layer "F.Fab")
		)
		(pad "1" smd circle
			(at 0 0)
			(size 0.7112 0.7112)
			(layers "F.Cu" "F.Mask" "F.Paste")
			(net "ZDEF_EXTA_TP_B2")
		)
	)
	(footprint ""
		(layer "F.Cu")
		(at 217.822526 -98.204782 180)
		(property "Reference" "R603"
			(at 0 0 180)
			(layer "F.SilkS")
			(hide yes)
			(effects
				(font
					(size 1.27 1.27)
				)
			)
		)
		(property "Value" "4K7R2F-GP"
			(at 0.064008 -3.993896 180)
			(unlocked yes)
			(layer "F.Fab")
			(hide yes)
			(effects
				(font
					(size 1.016 1.016)
					(thickness 0.1524)
				)
			)
		)
		(property "Device Type" "R402H16"
			(at 0.064008 -5.517896 180)
			(unlocked yes)
			(layer "F.Fab")
			(hide yes)
			(effects
				(font
					(size 1.016 1.016)
					(thickness 0.1524)
				)
			)
		)
		(duplicate_pad_numbers_are_jumpers no)
		(fp_line
			(start 0.508 -0.9398)
			(end -0.508 -0.9398)
			(stroke
				(width 0.1524)
				(type default)
			)
			(layer "F.SilkS")
		)
		(fp_line
			(start -0.508 -0.9398)
			(end -0.508 0.9398)
			(stroke
				(width 0.1524)
				(type default)
			)
			(layer "F.SilkS")
		)
		(fp_rect
			(start -0.508 0.9398)
			(end 0.508 -0.9398)
			(stroke
				(width 0)
				(type default)
			)
			(fill no)
			(layer "F.CrtYd")
		)
		(fp_rect
			(start -0.508 0.9398)
			(end 0.508 -0.9398)
			(stroke
				(width 0)
				(type default)
			)
			(fill no)
			(layer "F.Fab")
		)
		(pad "1" smd custom
			(at 0 -0.4445 180)
			(size 0.1397 0.1397)
			(layers "F.Cu" "F.Mask" "F.Paste")
			(net "IOC_EEPROM_A0")
			(options
				(clearance outline)
				(anchor circle)
			)
			(primitives
				(gr_poly
					(pts
						(arc
							(start -0.1778 -0.2794)
							(mid -0.249642 -0.249642)
							(end -0.2794 -0.1778)
						)
						(arc
							(start -0.2794 0.1778)
							(mid -0.249642 0.249642)
							(end -0.1778 0.2794)
						)
						(arc
							(start 0.1778 0.2794)
							(mid 0.249642 0.249642)
							(end 0.2794 0.1778)
						)
						(arc
							(start 0.2794 -0.1778)
							(mid 0.249642 -0.249642)
							(end 0.1778 -0.2794)
						)
					)
					(width 0)
					(fill yes)
				)
			)
		)
		(pad "2" smd custom
			(at 0 0.4445 180)
			(size 0.1397 0.1397)
			(layers "F.Cu" "F.Mask" "F.Paste")
			(net "GND")
			(options
				(clearance outline)
				(anchor circle)
			)
			(primitives
				(gr_poly
					(pts
						(arc
							(start -0.1778 -0.2794)
							(mid -0.249642 -0.249642)
							(end -0.2794 -0.1778)
						)
						(arc
							(start -0.2794 0.1778)
							(mid -0.249642 0.249642)
							(end -0.1778 0.2794)
						)
						(arc
							(start 0.1778 0.2794)
							(mid 0.249642 0.249642)
							(end 0.2794 0.1778)
						)
						(arc
							(start 0.2794 -0.1778)
							(mid 0.249642 -0.249642)
							(end 0.1778 -0.2794)
						)
					)
					(width 0)
					(fill yes)
				)
			)
		)
	)
	(footprint ""
		(layer "F.Cu")
		(at 20.034504 -142.561564)
		(property "Reference" "U28"
			(at 0 0 0)
			(layer "F.SilkS")
			(hide yes)
			(effects
				(font
					(size 1.27 1.27)
				)
			)
		)
		(property "Value" "H5AN4G6NAFR-TFC-GP"
			(at -8.423656 -15.9766 0)
			(unlocked yes)
			(layer "F.Fab")
			(hide yes)
			(effects
				(font
					(size 1.016 1.016)
					(thickness 0.1524)
				)
			)
		)
		(property "Device Type" "BGA96D075130H48"
			(at -8.423656 -17.5006 0)
			(unlocked yes)
			(layer "F.Fab")
			(hide yes)
			(effects
				(font
					(size 1.016 1.016)
					(thickness 0.1524)
				)
			)
		)
		(duplicate_pad_numbers_are_jumpers no)
		(fp_line
			(start -4.080256 -6.830314)
			(end -2.480056 -6.830314)
			(stroke
				(width 0.508)
				(type default)
			)
			(layer "F.SilkS")
		)
		(fp_line
			(start -4.080256 -5.230114)
			(end -4.080256 -6.830314)
			(stroke
				(width 0.508)
				(type default)
			)
			(layer "F.SilkS")
		)
		(fp_line
			(start -3.750056 -6.500114)
			(end -3.750056 6.500114)
			(stroke
				(width 0.1524)
				(type default)
			)
			(layer "F.SilkS")
		)
		(fp_line
			(start -3.750056 6.500114)
			(end 3.750056 6.500114)
			(stroke
				(width 0.1524)
				(type default)
			)
			(layer "F.SilkS")
		)
		(fp_line
			(start 3.750056 -6.500114)
			(end -3.750056 -6.500114)
			(stroke
				(width 0.1524)
				(type default)
			)
			(layer "F.SilkS")
		)
		(fp_line
			(start 3.750056 6.500114)
			(end 3.750056 -6.500114)
			(stroke
				(width 0.1524)
				(type default)
			)
			(layer "F.SilkS")
		)
		(fp_rect
			(start -3.750056 6.500114)
			(end 3.750056 -6.500114)
			(stroke
				(width 0)
				(type default)
			)
			(fill no)
			(layer "F.CrtYd")
		)
		(fp_poly
			(pts
				(xy -4.7498 7.5057) (xy -4.7498 -7.5057) (xy 4.7498 -7.5057) (xy 4.7498 -0.54864) (xy 3.750056 -0.54864)
				(xy 3.750056 -6.500114) (xy -3.750056 -6.500114) (xy -3.750056 6.500114) (xy 3.750056 6.500114)
				(xy 3.750056 -0.54356) (xy 4.7498 -0.54356) (xy 4.7498 7.5057)
			)
			(stroke
				(width 0)
				(type default)
			)
			(fill no)
			(layer "F.CrtYd")
		)
		(fp_rect
			(start -5.750052 8.50011)
			(end 5.750052 -8.50011)
			(stroke
				(width 0)
				(type default)
			)
			(fill no)
			(layer "F.Fab")
		)
		(pad "A1" smd circle
			(at -3.199892 -5.999988)
			(size 0.3556 0.3556)
			(layers "F.Cu" "F.Mask" "F.Paste")
			(net "P1V2_STBY")
		)
		(pad "A2" smd circle
			(at -2.400046 -5.999988)
			(size 0.3556 0.3556)
			(layers "F.Cu" "F.Mask" "F.Paste")
			(net "GND")
		)
		(pad "A3" smd circle
			(at -1.599946 -5.999988)
			(size 0.3556 0.3556)
			(layers "F.Cu" "F.Mask" "F.Paste")
			(net "MEMDQ_8")
		)
		(pad "A7" smd circle
			(at 1.599946 -5.999988)
			(size 0.3556 0.3556)
			(layers "F.Cu" "F.Mask" "F.Paste")
			(net "MEMDQS_N1")
		)
		(pad "A8" smd circle
			(at 2.400046 -5.999988)
			(size 0.3556 0.3556)
			(layers "F.Cu" "F.Mask" "F.Paste")
			(net "GND")
		)
		(pad "A9" smd circle
			(at 3.199892 -5.999988)
			(size 0.3556 0.3556)
			(layers "F.Cu" "F.Mask" "F.Paste")
			(net "P1V2_STBY")
		)
		(pad "B1" smd circle
			(at -3.199892 -5.199888)
			(size 0.3556 0.3556)
			(layers "F.Cu" "F.Mask" "F.Paste")
			(net "P2V5_STBY")
		)
		(pad "B2" smd circle
			(at -2.400046 -5.199888)
			(size 0.3556 0.3556)
			(layers "F.Cu" "F.Mask" "F.Paste")
			(net "GND")
		)
		(pad "B3" smd circle
			(at -1.599946 -5.199888)
			(size 0.3556 0.3556)
			(layers "F.Cu" "F.Mask" "F.Paste")
			(net "P1V2_STBY")
		)
		(pad "B7" smd circle
			(at 1.599946 -5.199888)
			(size 0.3556 0.3556)
			(layers "F.Cu" "F.Mask" "F.Paste")
			(net "MEMDQS_P1")
		)
		(pad "B8" smd circle
			(at 2.400046 -5.199888)
			(size 0.3556 0.3556)
			(layers "F.Cu" "F.Mask" "F.Paste")
			(net "MEMDQ_9")
		)
		(pad "B9" smd circle
			(at 3.199892 -5.199888)
			(size 0.3556 0.3556)
			(layers "F.Cu" "F.Mask" "F.Paste")
			(net "P1V2_STBY")
		)
		(pad "C1" smd circle
			(at -3.199892 -4.400042)
			(size 0.3556 0.3556)
			(layers "F.Cu" "F.Mask" "F.Paste")
			(net "P1V2_STBY")
		)
		(pad "C2" smd circle
			(at -2.400046 -4.400042)
			(size 0.3556 0.3556)
			(layers "F.Cu" "F.Mask" "F.Paste")
			(net "MEMDQ_12")
		)
		(pad "C3" smd circle
			(at -1.599946 -4.400042)
			(size 0.3556 0.3556)
			(layers "F.Cu" "F.Mask" "F.Paste")
			(net "MEMDQ_10")
		)
		(pad "C7" smd circle
			(at 1.599946 -4.400042)
			(size 0.3556 0.3556)
			(layers "F.Cu" "F.Mask" "F.Paste")
			(net "MEMDQ_11")
		)
		(pad "C8" smd circle
			(at 2.400046 -4.400042)
			(size 0.3556 0.3556)
			(layers "F.Cu" "F.Mask" "F.Paste")
			(net "MEMDQ_13")
		)
		(pad "C9" smd circle
			(at 3.199892 -4.400042)
			(size 0.3556 0.3556)
			(layers "F.Cu" "F.Mask" "F.Paste")
			(net "GND")
		)
		(pad "D1" smd circle
			(at -3.199892 -3.599942)
			(size 0.3556 0.3556)
			(layers "F.Cu" "F.Mask" "F.Paste")
			(net "P1V2_STBY")
		)
		(pad "D2" smd circle
			(at -2.400046 -3.599942)
			(size 0.3556 0.3556)
			(layers "F.Cu" "F.Mask" "F.Paste")
			(net "GND")
		)
		(pad "D3" smd circle
			(at -1.599946 -3.599942)
			(size 0.3556 0.3556)
			(layers "F.Cu" "F.Mask" "F.Paste")
			(net "MEMDQ_14")
		)
		(pad "D7" smd circle
			(at 1.599946 -3.599942)
			(size 0.3556 0.3556)
			(layers "F.Cu" "F.Mask" "F.Paste")
			(net "MEMDQ_15")
		)
		(pad "D8" smd circle
			(at 2.400046 -3.599942)
			(size 0.3556 0.3556)
			(layers "F.Cu" "F.Mask" "F.Paste")
			(net "GND")
		)
		(pad "D9" smd circle
			(at 3.199892 -3.599942)
			(size 0.3556 0.3556)
			(layers "F.Cu" "F.Mask" "F.Paste")
			(net "P1V2_STBY")
		)
		(pad "E1" smd circle
			(at -3.199892 -2.800096)
			(size 0.3556 0.3556)
			(layers "F.Cu" "F.Mask" "F.Paste")
			(net "GND")
		)
		(pad "E2" smd circle
			(at -2.400046 -2.800096)
			(size 0.3556 0.3556)
			(layers "F.Cu" "F.Mask" "F.Paste")
			(net "MEMDM_1")
		)
		(pad "E3" smd circle
			(at -1.599946 -2.800096)
			(size 0.3556 0.3556)
			(layers "F.Cu" "F.Mask" "F.Paste")
			(net "GND")
		)
		(pad "E7" smd circle
			(at 1.599946 -2.800096)
			(size 0.3556 0.3556)
			(layers "F.Cu" "F.Mask" "F.Paste")
			(net "MEMDM_0")
		)
		(pad "E8" smd circle
			(at 2.400046 -2.800096)
			(size 0.3556 0.3556)
			(layers "F.Cu" "F.Mask" "F.Paste")
			(net "GND")
		)
		(pad "E9" smd circle
			(at 3.199892 -2.800096)
			(size 0.3556 0.3556)
			(layers "F.Cu" "F.Mask" "F.Paste")
			(net "GND")
		)
		(pad "F1" smd circle
			(at -3.199892 -1.999996)
			(size 0.3556 0.3556)
			(layers "F.Cu" "F.Mask" "F.Paste")
			(net "GND")
		)
		(pad "F2" smd circle
			(at -2.400046 -1.999996)
			(size 0.3556 0.3556)
			(layers "F.Cu" "F.Mask" "F.Paste")
			(net "P1V2_STBY")
		)
		(pad "F3" smd circle
			(at -1.599946 -1.999996)
			(size 0.3556 0.3556)
			(layers "F.Cu" "F.Mask" "F.Paste")
			(net "MEMDQS_N0")
		)
		(pad "F7" smd circle
			(at 1.599946 -1.999996)
			(size 0.3556 0.3556)
			(layers "F.Cu" "F.Mask" "F.Paste")
			(net "MEMDQ_1")
		)
		(pad "F8" smd circle
			(at 2.400046 -1.999996)
			(size 0.3556 0.3556)
			(layers "F.Cu" "F.Mask" "F.Paste")
			(net "P1V2_STBY")
		)
		(pad "F9" smd circle
			(at 3.199892 -1.999996)
			(size 0.3556 0.3556)
			(layers "F.Cu" "F.Mask" "F.Paste")
			(net "PD_ZQ")
		)
		(pad "G1" smd circle
			(at -3.199892 -1.199896)
			(size 0.3556 0.3556)
			(layers "F.Cu" "F.Mask" "F.Paste")
			(net "P1V2_STBY")
		)
		(pad "G2" smd circle
			(at -2.400046 -1.199896)
			(size 0.3556 0.3556)
			(layers "F.Cu" "F.Mask" "F.Paste")
			(net "MEMDQ_0")
		)
		(pad "G3" smd circle
			(at -1.599946 -1.199896)
			(size 0.3556 0.3556)
			(layers "F.Cu" "F.Mask" "F.Paste")
			(net "MEMDQS_P0")
		)
		(pad "G7" smd circle
			(at 1.599946 -1.199896)
			(size 0.3556 0.3556)
			(layers "F.Cu" "F.Mask" "F.Paste")
			(net "P1V2_STBY")
		)
		(pad "G8" smd circle
			(at 2.400046 -1.199896)
			(size 0.3556 0.3556)
			(layers "F.Cu" "F.Mask" "F.Paste")
			(net "GND")
		)
		(pad "G9" smd circle
			(at 3.199892 -1.199896)
			(size 0.3556 0.3556)
			(layers "F.Cu" "F.Mask" "F.Paste")
			(net "P1V2_STBY")
		)
		(pad "H1" smd circle
			(at -3.199892 -0.40005)
			(size 0.3556 0.3556)
			(layers "F.Cu" "F.Mask" "F.Paste")
			(net "GND")
		)
		(pad "H2" smd circle
			(at -2.400046 -0.40005)
			(size 0.3556 0.3556)
			(layers "F.Cu" "F.Mask" "F.Paste")
			(net "MEMDQ_4")
		)
		(pad "H3" smd circle
			(at -1.599946 -0.40005)
			(size 0.3556 0.3556)
			(layers "F.Cu" "F.Mask" "F.Paste")
			(net "MEMDQ_2")
		)
		(pad "H7" smd circle
			(at 1.599946 -0.40005)
			(size 0.3556 0.3556)
			(layers "F.Cu" "F.Mask" "F.Paste")
			(net "MEMDQ_3")
		)
		(pad "H8" smd circle
			(at 2.400046 -0.40005)
			(size 0.3556 0.3556)
			(layers "F.Cu" "F.Mask" "F.Paste")
			(net "MEMDQ_5")
		)
		(pad "H9" smd circle
			(at 3.199892 -0.40005)
			(size 0.3556 0.3556)
			(layers "F.Cu" "F.Mask" "F.Paste")
			(net "GND")
		)
		(pad "J1" smd circle
			(at -3.199892 0.40005)
			(size 0.3556 0.3556)
			(layers "F.Cu" "F.Mask" "F.Paste")
			(net "P1V2_STBY")
		)
		(pad "J2" smd circle
			(at -2.400046 0.40005)
			(size 0.3556 0.3556)
			(layers "F.Cu" "F.Mask" "F.Paste")
			(net "P1V2_STBY")
		)
		(pad "J3" smd circle
			(at -1.599946 0.40005)
			(size 0.3556 0.3556)
			(layers "F.Cu" "F.Mask" "F.Paste")
			(net "MEMDQ_6")
		)
		(pad "J7" smd circle
			(at 1.599946 0.40005)
			(size 0.3556 0.3556)
			(layers "F.Cu" "F.Mask" "F.Paste")
			(net "MEMDQ_7")
		)
		(pad "J8" smd circle
			(at 2.400046 0.40005)
			(size 0.3556 0.3556)
			(layers "F.Cu" "F.Mask" "F.Paste")
			(net "P1V2_STBY")
		)
		(pad "J9" smd circle
			(at 3.199892 0.40005)
			(size 0.3556 0.3556)
			(layers "F.Cu" "F.Mask" "F.Paste")
			(net "P1V2_STBY")
		)
		(pad "K1" smd circle
			(at -3.199892 1.199896)
			(size 0.3556 0.3556)
			(layers "F.Cu" "F.Mask" "F.Paste")
			(net "GND")
		)
		(pad "K2" smd circle
			(at -2.400046 1.199896)
			(size 0.3556 0.3556)
			(layers "F.Cu" "F.Mask" "F.Paste")
			(net "MEMCKE")
		)
		(pad "K3" smd circle
			(at -1.599946 1.199896)
			(size 0.3556 0.3556)
			(layers "F.Cu" "F.Mask" "F.Paste")
			(net "MEMODT")
		)
		(pad "K7" smd circle
			(at 1.599946 1.199896)
			(size 0.3556 0.3556)
			(layers "F.Cu" "F.Mask" "F.Paste")
			(net "MEMCK_P")
		)
		(pad "K8" smd circle
			(at 2.400046 1.199896)
			(size 0.3556 0.3556)
			(layers "F.Cu" "F.Mask" "F.Paste")
			(net "MEMCK_N")
		)
		(pad "K9" smd circle
			(at 3.199892 1.199896)
			(size 0.3556 0.3556)
			(layers "F.Cu" "F.Mask" "F.Paste")
			(net "GND")
		)
		(pad "L1" smd circle
			(at -3.199892 1.999996)
			(size 0.3556 0.3556)
			(layers "F.Cu" "F.Mask" "F.Paste")
			(net "P1V2_STBY")
		)
		(pad "L2" smd circle
			(at -2.400046 1.999996)
			(size 0.3556 0.3556)
			(layers "F.Cu" "F.Mask" "F.Paste")
			(net "MEMWEN")
		)
		(pad "L3" smd circle
			(at -1.599946 1.999996)
			(size 0.3556 0.3556)
			(layers "F.Cu" "F.Mask" "F.Paste")
			(net "DDR4_ACT")
		)
		(pad "L7" smd circle
			(at 1.599946 1.999996)
			(size 0.3556 0.3556)
			(layers "F.Cu" "F.Mask" "F.Paste")
			(net "MEMCSN")
		)
		(pad "L8" smd circle
			(at 2.400046 1.999996)
			(size 0.3556 0.3556)
			(layers "F.Cu" "F.Mask" "F.Paste")
			(net "MEMRASN")
		)
		(pad "L9" smd circle
			(at 3.199892 1.999996)
			(size 0.3556 0.3556)
			(layers "F.Cu" "F.Mask" "F.Paste")
			(net "P1V2_STBY")
		)
		(pad "M1" smd circle
			(at -3.199892 2.800096)
			(size 0.3556 0.3556)
			(layers "F.Cu" "F.Mask" "F.Paste")
			(net "DDR_VREF")
		)
		(pad "M2" smd circle
			(at -2.400046 2.800096)
			(size 0.3556 0.3556)
			(layers "F.Cu" "F.Mask" "F.Paste")
			(net "MEMBG_0")
		)
		(pad "M3" smd circle
			(at -1.599946 2.800096)
			(size 0.3556 0.3556)
			(layers "F.Cu" "F.Mask" "F.Paste")
			(net "MEMA_10")
		)
		(pad "M7" smd circle
			(at 1.599946 2.800096)
			(size 0.3556 0.3556)
			(layers "F.Cu" "F.Mask" "F.Paste")
			(net "MEMA_12")
		)
		(pad "M8" smd circle
			(at 2.400046 2.800096)
			(size 0.3556 0.3556)
			(layers "F.Cu" "F.Mask" "F.Paste")
			(net "MEMCASN")
		)
		(pad "M9" smd circle
			(at 3.199892 2.800096)
			(size 0.3556 0.3556)
			(layers "F.Cu" "F.Mask" "F.Paste")
			(net "GND")
		)
		(pad "N1" smd circle
			(at -3.199892 3.599942)
			(size 0.3556 0.3556)
			(layers "F.Cu" "F.Mask" "F.Paste")
			(net "GND")
		)
		(pad "N2" smd circle
			(at -2.400046 3.599942)
			(size 0.3556 0.3556)
			(layers "F.Cu" "F.Mask" "F.Paste")
			(net "MEMBA_0")
		)
		(pad "N3" smd circle
			(at -1.599946 3.599942)
			(size 0.3556 0.3556)
			(layers "F.Cu" "F.Mask" "F.Paste")
			(net "MEMA_4")
		)
		(pad "N7" smd circle
			(at 1.599946 3.599942)
			(size 0.3556 0.3556)
			(layers "F.Cu" "F.Mask" "F.Paste")
			(net "MEMA_3")
		)
		(pad "N8" smd circle
			(at 2.400046 3.599942)
			(size 0.3556 0.3556)
			(layers "F.Cu" "F.Mask" "F.Paste")
			(net "MEMBA_1")
		)
		(pad "N9" smd circle
			(at 3.199892 3.599942)
			(size 0.3556 0.3556)
			(layers "F.Cu" "F.Mask" "F.Paste")
			(net "GND")
		)
		(pad "P1" smd circle
			(at -3.199892 4.400042)
			(size 0.3556 0.3556)
			(layers "F.Cu" "F.Mask" "F.Paste")
			(net "DDR4_RST_N")
		)
		(pad "P2" smd circle
			(at -2.400046 4.400042)
			(size 0.3556 0.3556)
			(layers "F.Cu" "F.Mask" "F.Paste")
			(net "MEMA_6")
		)
		(pad "P3" smd circle
			(at -1.599946 4.400042)
			(size 0.3556 0.3556)
			(layers "F.Cu" "F.Mask" "F.Paste")
			(net "MEMA_0")
		)
		(pad "P7" smd circle
			(at 1.599946 4.400042)
			(size 0.3556 0.3556)
			(layers "F.Cu" "F.Mask" "F.Paste")
			(net "MEMA_1")
		)
		(pad "P8" smd circle
			(at 2.400046 4.400042)
			(size 0.3556 0.3556)
			(layers "F.Cu" "F.Mask" "F.Paste")
			(net "MEMA_5")
		)
		(pad "P9" smd circle
			(at 3.199892 4.400042)
			(size 0.3556 0.3556)
			(layers "F.Cu" "F.Mask" "F.Paste")
			(net "DDR4_ALERT")
		)
		(pad "R1" smd circle
			(at -3.199892 5.199888)
			(size 0.3556 0.3556)
			(layers "F.Cu" "F.Mask" "F.Paste")
			(net "P1V2_STBY")
		)
		(pad "R2" smd circle
			(at -2.400046 5.199888)
			(size 0.3556 0.3556)
			(layers "F.Cu" "F.Mask" "F.Paste")
			(net "MEMA_8")
		)
		(pad "R3" smd circle
			(at -1.599946 5.199888)
			(size 0.3556 0.3556)
			(layers "F.Cu" "F.Mask" "F.Paste")
			(net "MEMA_2")
		)
		(pad "R7" smd circle
			(at 1.599946 5.199888)
			(size 0.3556 0.3556)
			(layers "F.Cu" "F.Mask" "F.Paste")
			(net "MEMA_9")
		)
		(pad "R8" smd circle
			(at 2.400046 5.199888)
			(size 0.3556 0.3556)
			(layers "F.Cu" "F.Mask" "F.Paste")
			(net "MEMA_7")
		)
		(pad "R9" smd circle
			(at 3.199892 5.199888)
			(size 0.3556 0.3556)
			(layers "F.Cu" "F.Mask" "F.Paste")
			(net "P2V5_STBY")
		)
		(pad "T1" smd circle
			(at -3.199892 5.999988)
			(size 0.3556 0.3556)
			(layers "F.Cu" "F.Mask" "F.Paste")
			(net "GND")
		)
		(pad "T2" smd circle
			(at -2.400046 5.999988)
			(size 0.3556 0.3556)
			(layers "F.Cu" "F.Mask" "F.Paste")
			(net "MEMA_11")
		)
		(pad "T3" smd circle
			(at -1.599946 5.999988)
			(size 0.3556 0.3556)
			(layers "F.Cu" "F.Mask" "F.Paste")
			(net "MEM_PAR")
		)
		(pad "T7" smd circle
			(at 1.599946 5.999988)
			(size 0.3556 0.3556)
			(layers "F.Cu" "F.Mask" "F.Paste")
			(net "Net_335")
		)
		(pad "T8" smd circle
			(at 2.400046 5.999988)
			(size 0.3556 0.3556)
			(layers "F.Cu" "F.Mask" "F.Paste")
			(net "MEMA_13")
		)
		(pad "T9" smd circle
			(at 3.199892 5.999988)
			(size 0.3556 0.3556)
			(layers "F.Cu" "F.Mask" "F.Paste")
			(net "P1V2_STBY")
		)
	)
	(footprint ""
		(layer "F.Cu")
		(at 51.906678 -166.417244 180)
		(property "Reference" "R777"
			(at 0 0 180)
			(layer "F.SilkS")
			(hide yes)
			(effects
				(font
					(size 1.27 1.27)
				)
			)
		)
		(property "Value" "1KR2F-3-GP"
			(at 0.064008 -3.993896 180)
			(unlocked yes)
			(layer "F.Fab")
			(hide yes)
			(effects
				(font
					(size 1.016 1.016)
					(thickness 0.1524)
				)
			)
		)
		(property "Device Type" "R402H16"
			(at 0.064008 -5.517896 180)
			(unlocked yes)
			(layer "F.Fab")
			(hide yes)
			(effects
				(font
					(size 1.016 1.016)
					(thickness 0.1524)
				)
			)
		)
		(duplicate_pad_numbers_are_jumpers no)
		(fp_line
			(start 0.508 -0.9398)
			(end -0.508 -0.9398)
			(stroke
				(width 0.1524)
				(type default)
			)
			(layer "F.SilkS")
		)
		(fp_line
			(start -0.508 -0.9398)
			(end -0.508 0.9398)
			(stroke
				(width 0.1524)
				(type default)
			)
			(layer "F.SilkS")
		)
		(fp_rect
			(start -0.508 0.9398)
			(end 0.508 -0.9398)
			(stroke
				(width 0)
				(type default)
			)
			(fill no)
			(layer "F.CrtYd")
		)
		(fp_rect
			(start -0.508 0.9398)
			(end 0.508 -0.9398)
			(stroke
				(width 0)
				(type default)
			)
			(fill no)
			(layer "F.Fab")
		)
		(pad "1" smd custom
			(at 0 -0.4445 180)
			(size 0.1397 0.1397)
			(layers "F.Cu" "F.Mask" "F.Paste")
			(net "ADC_P1V2_STBY")
			(options
				(clearance outline)
				(anchor circle)
			)
			(primitives
				(gr_poly
					(pts
						(arc
							(start -0.1778 -0.2794)
							(mid -0.249642 -0.249642)
							(end -0.2794 -0.1778)
						)
						(arc
							(start -0.2794 0.1778)
							(mid -0.249642 0.249642)
							(end -0.1778 0.2794)
						)
						(arc
							(start 0.1778 0.2794)
							(mid 0.249642 0.249642)
							(end 0.2794 0.1778)
						)
						(arc
							(start 0.2794 -0.1778)
							(mid 0.249642 -0.249642)
							(end 0.1778 -0.2794)
						)
					)
					(width 0)
					(fill yes)
				)
			)
		)
		(pad "2" smd custom
			(at 0 0.4445 180)
			(size 0.1397 0.1397)
			(layers "F.Cu" "F.Mask" "F.Paste")
			(net "GND")
			(options
				(clearance outline)
				(anchor circle)
			)
			(primitives
				(gr_poly
					(pts
						(arc
							(start -0.1778 -0.2794)
							(mid -0.249642 -0.249642)
							(end -0.2794 -0.1778)
						)
						(arc
							(start -0.2794 0.1778)
							(mid -0.249642 0.249642)
							(end -0.1778 0.2794)
						)
						(arc
							(start 0.1778 0.2794)
							(mid 0.249642 0.249642)
							(end 0.2794 0.1778)
						)
						(arc
							(start 0.2794 -0.1778)
							(mid 0.249642 -0.249642)
							(end 0.1778 -0.2794)
						)
					)
					(width 0)
					(fill yes)
				)
			)
		)
	)
	(footprint ""
		(layer "F.Cu")
		(at 78.905608 -138.01598 -90)
		(property "Reference" "U19"
			(at 0 0 270)
			(layer "F.SilkS")
			(hide yes)
			(effects
				(font
					(size 1.27 1.27)
				)
			)
		)
		(property "Value" "SN74LVC1G74DCUT-GP"
			(at 0 -11.1252 270)
			(unlocked yes)
			(layer "F.Fab")
			(hide yes)
			(effects
				(font
					(size 1.016 1.016)
					(thickness 0.1524)
				)
			)
		)
		(property "Device Type" "SSOIC8-4H36"
			(at 0 -12.6492 270)
			(unlocked yes)
			(layer "F.Fab")
			(hide yes)
			(effects
				(font
					(size 1.016 1.016)
					(thickness 0.1524)
				)
			)
		)
		(duplicate_pad_numbers_are_jumpers no)
		(fp_line
			(start -1.2573 2.1844)
			(end -1.2573 -2.1844)
			(stroke
				(width 0.1524)
				(type default)
			)
			(layer "F.SilkS")
		)
		(fp_line
			(start 1.2573 2.1844)
			(end -1.2573 2.1844)
			(stroke
				(width 0.1524)
				(type default)
			)
			(layer "F.SilkS")
		)
		(fp_line
			(start -1.2954 0.4572)
			(end -1.2954 2.159)
			(stroke
				(width 0.4064)
				(type default)
			)
			(layer "F.SilkS")
		)
		(fp_line
			(start -1.2065 0.2667)
			(end -1.27 0.2667)
			(stroke
				(width 0.1524)
				(type default)
			)
			(layer "F.SilkS")
		)
		(fp_line
			(start -0.9017 -0.0381)
			(end -1.2065 0.2667)
			(stroke
				(width 0.1524)
				(type default)
			)
			(layer "F.SilkS")
		)
		(fp_line
			(start -1.2573 -0.3556)
			(end -1.2192 -0.3556)
			(stroke
				(width 0.1524)
				(type default)
			)
			(layer "F.SilkS")
		)
		(fp_line
			(start -1.2192 -0.3556)
			(end -0.9017 -0.0381)
			(stroke
				(width 0.1524)
				(type default)
			)
			(layer "F.SilkS")
		)
		(fp_line
			(start -1.2573 -2.1844)
			(end 1.2573 -2.1844)
			(stroke
				(width 0.1524)
				(type default)
			)
			(layer "F.SilkS")
		)
		(fp_line
			(start 1.2573 -2.1844)
			(end 1.2573 2.1844)
			(stroke
				(width 0.1524)
				(type default)
			)
			(layer "F.SilkS")
		)
		(fp_poly
			(pts
				(xy -1.5113 2.4384) (xy 1.5113 2.4384) (xy 1.5113 -2.4384) (xy -1.5113 -2.4384)
			)
			(stroke
				(width 0)
				(type default)
			)
			(fill no)
			(layer "F.CrtYd")
		)
		(fp_poly
			(pts
				(xy -1.5113 -2.4384) (xy 1.5113 -2.4384) (xy 1.5113 2.4384) (xy -1.5113 2.4384)
			)
			(stroke
				(width 0)
				(type default)
			)
			(fill no)
			(layer "F.Fab")
		)
		(pad "1" smd rect
			(at -0.75057 1.1684 270)
			(size 0.3048 1.524)
			(layers "F.Cu" "F.Mask" "F.Paste")
			(net "DEBUG_HDR_UART_SEL")
		)
		(pad "2" smd rect
			(at -0.25019 1.1684 270)
			(size 0.3048 1.524)
			(layers "F.Cu" "F.Mask" "F.Paste")
			(net "D_FLIP_D")
		)
		(pad "3" smd rect
			(at 0.25019 1.1684 270)
			(size 0.3048 1.524)
			(layers "F.Cu" "F.Mask" "F.Paste")
			(net "D_FLIP_Q#")
		)
		(pad "4" smd rect
			(at 0.75057 1.1684 270)
			(size 0.3048 1.524)
			(layers "F.Cu" "F.Mask" "F.Paste")
			(net "GND")
		)
		(pad "5" smd rect
			(at 0.75057 -1.1684 270)
			(size 0.3048 1.524)
			(layers "F.Cu" "F.Mask" "F.Paste")
			(net "D_FLIP_Q")
		)
		(pad "6" smd rect
			(at 0.25019 -1.1684 270)
			(size 0.3048 1.524)
			(layers "F.Cu" "F.Mask" "F.Paste")
			(net "D_FLIP_CLR#")
		)
		(pad "7" smd rect
			(at -0.25019 -1.1684 270)
			(size 0.3048 1.524)
			(layers "F.Cu" "F.Mask" "F.Paste")
			(net "D_FLIP_PRE#")
		)
		(pad "8" smd rect
			(at -0.75057 -1.1684 270)
			(size 0.3048 1.524)
			(layers "F.Cu" "F.Mask" "F.Paste")
			(net "P3V3_STBY")
		)
	)
	(footprint ""
		(layer "F.Cu")
		(at 97.1677 -148.108924 180)
		(property "Reference" "R29"
			(at 0 0 180)
			(layer "F.SilkS")
			(hide yes)
			(effects
				(font
					(size 1.27 1.27)
				)
			)
		)
		(property "Value" "4K7R2F-GP"
			(at 0.064008 -3.993896 180)
			(unlocked yes)
			(layer "F.Fab")
			(hide yes)
			(effects
				(font
					(size 1.016 1.016)
					(thickness 0.1524)
				)
			)
		)
		(property "Device Type" "R402H16"
			(at 0.064008 -5.517896 180)
			(unlocked yes)
			(layer "F.Fab")
			(hide yes)
			(effects
				(font
					(size 1.016 1.016)
					(thickness 0.1524)
				)
			)
		)
		(duplicate_pad_numbers_are_jumpers no)
		(fp_line
			(start 0.508 -0.9398)
			(end -0.508 -0.9398)
			(stroke
				(width 0.1524)
				(type default)
			)
			(layer "F.SilkS")
		)
		(fp_line
			(start -0.508 -0.9398)
			(end -0.508 0.9398)
			(stroke
				(width 0.1524)
				(type default)
			)
			(layer "F.SilkS")
		)
		(fp_rect
			(start -0.508 0.9398)
			(end 0.508 -0.9398)
			(stroke
				(width 0)
				(type default)
			)
			(fill no)
			(layer "F.CrtYd")
		)
		(fp_rect
			(start -0.508 0.9398)
			(end 0.508 -0.9398)
			(stroke
				(width 0)
				(type default)
			)
			(fill no)
			(layer "F.Fab")
		)
		(pad "1" smd custom
			(at 0 -0.4445 180)
			(size 0.1397 0.1397)
			(layers "F.Cu" "F.Mask" "F.Paste")
			(net "P3V3_STBY")
			(options
				(clearance outline)
				(anchor circle)
			)
			(primitives
				(gr_poly
					(pts
						(arc
							(start -0.1778 -0.2794)
							(mid -0.249642 -0.249642)
							(end -0.2794 -0.1778)
						)
						(arc
							(start -0.2794 0.1778)
							(mid -0.249642 0.249642)
							(end -0.1778 0.2794)
						)
						(arc
							(start 0.1778 0.2794)
							(mid 0.249642 0.249642)
							(end 0.2794 0.1778)
						)
						(arc
							(start 0.2794 -0.1778)
							(mid 0.249642 -0.249642)
							(end 0.1778 -0.2794)
						)
					)
					(width 0)
					(fill yes)
				)
			)
		)
		(pad "2" smd custom
			(at 0 0.4445 180)
			(size 0.1397 0.1397)
			(layers "F.Cu" "F.Mask" "F.Paste")
			(net "USB_OCS_N2")
			(options
				(clearance outline)
				(anchor circle)
			)
			(primitives
				(gr_poly
					(pts
						(arc
							(start -0.1778 -0.2794)
							(mid -0.249642 -0.249642)
							(end -0.2794 -0.1778)
						)
						(arc
							(start -0.2794 0.1778)
							(mid -0.249642 0.249642)
							(end -0.1778 0.2794)
						)
						(arc
							(start 0.1778 0.2794)
							(mid 0.249642 0.249642)
							(end 0.2794 0.1778)
						)
						(arc
							(start 0.2794 -0.1778)
							(mid 0.249642 -0.249642)
							(end 0.1778 -0.2794)
						)
					)
					(width 0)
					(fill yes)
				)
			)
		)
	)
	(footprint ""
		(layer "F.Cu")
		(at 73.4822 -156.718 -90)
		(property "Reference" "R305"
			(at 0 0 270)
			(layer "F.SilkS")
			(hide yes)
			(effects
				(font
					(size 1.27 1.27)
				)
			)
		)
		(property "Value" "10KR2F-2-GP"
			(at 0.064008 -3.993896 270)
			(unlocked yes)
			(layer "F.Fab")
			(hide yes)
			(effects
				(font
					(size 1.016 1.016)
					(thickness 0.1524)
				)
			)
		)
		(property "Device Type" "R402H16"
			(at 0.064008 -5.517896 270)
			(unlocked yes)
			(layer "F.Fab")
			(hide yes)
			(effects
				(font
					(size 1.016 1.016)
					(thickness 0.1524)
				)
			)
		)
		(duplicate_pad_numbers_are_jumpers no)
		(fp_line
			(start -0.508 -0.9398)
			(end -0.508 0.9398)
			(stroke
				(width 0.1524)
				(type default)
			)
			(layer "F.SilkS")
		)
		(fp_line
			(start 0.508 -0.9398)
			(end -0.508 -0.9398)
			(stroke
				(width 0.1524)
				(type default)
			)
			(layer "F.SilkS")
		)
		(fp_rect
			(start -0.508 0.9398)
			(end 0.508 -0.9398)
			(stroke
				(width 0)
				(type default)
			)
			(fill no)
			(layer "F.CrtYd")
		)
		(fp_rect
			(start -0.508 0.9398)
			(end 0.508 -0.9398)
			(stroke
				(width 0)
				(type default)
			)
			(fill no)
			(layer "F.Fab")
		)
		(pad "1" smd custom
			(at 0 -0.4445 270)
			(size 0.1397 0.1397)
			(layers "F.Cu" "F.Mask" "F.Paste")
			(net "P3V3_STBY")
			(options
				(clearance outline)
				(anchor circle)
			)
			(primitives
				(gr_poly
					(pts
						(arc
							(start -0.1778 -0.2794)
							(mid -0.249642 -0.249642)
							(end -0.2794 -0.1778)
						)
						(arc
							(start -0.2794 0.1778)
							(mid -0.249642 0.249642)
							(end -0.1778 0.2794)
						)
						(arc
							(start 0.1778 0.2794)
							(mid 0.249642 0.249642)
							(end 0.2794 0.1778)
						)
						(arc
							(start 0.2794 -0.1778)
							(mid 0.249642 -0.249642)
							(end 0.1778 -0.2794)
						)
					)
					(width 0)
					(fill yes)
				)
			)
		)
		(pad "2" smd custom
			(at 0 0.4445 270)
			(size 0.1397 0.1397)
			(layers "F.Cu" "F.Mask" "F.Paste")
			(net "FM_OSC_50M_EN")
			(options
				(clearance outline)
				(anchor circle)
			)
			(primitives
				(gr_poly
					(pts
						(arc
							(start -0.1778 -0.2794)
							(mid -0.249642 -0.249642)
							(end -0.2794 -0.1778)
						)
						(arc
							(start -0.2794 0.1778)
							(mid -0.249642 0.249642)
							(end -0.1778 0.2794)
						)
						(arc
							(start 0.1778 0.2794)
							(mid 0.249642 0.249642)
							(end 0.2794 0.1778)
						)
						(arc
							(start 0.2794 -0.1778)
							(mid 0.249642 -0.249642)
							(end 0.1778 -0.2794)
						)
					)
					(width 0)
					(fill yes)
				)
			)
		)
	)
	(footprint ""
		(layer "F.Cu")
		(at 208.055972 -71.6788 90)
		(property "Reference" "C313"
			(at 0 0 90)
			(layer "F.SilkS")
			(hide yes)
			(effects
				(font
					(size 1.27 1.27)
				)
			)
		)
		(property "Value" "SCD01U16V1KX-GP"
			(at -2.8321 -1.7399 90)
			(unlocked yes)
			(layer "F.Fab")
			(hide yes)
			(effects
				(font
					(size 1.016 1.016)
					(thickness 0.1524)
				)
			)
		)
		(property "Device Type" "C0201H13"
			(at -2.8321 -3.2639 90)
			(unlocked yes)
			(layer "F.Fab")
			(hide yes)
			(effects
				(font
					(size 1.016 1.016)
					(thickness 0.1524)
				)
			)
		)
		(duplicate_pad_numbers_are_jumpers no)
		(fp_rect
			(start -0.2794 0.6477)
			(end 0.2794 -0.6477)
			(stroke
				(width 0)
				(type default)
			)
			(fill no)
			(layer "F.CrtYd")
		)
		(fp_rect
			(start -0.2794 0.6477)
			(end 0.2794 -0.6477)
			(stroke
				(width 0)
				(type default)
			)
			(fill no)
			(layer "F.Fab")
		)
		(pad "1" smd custom
			(at 0 -0.2794 90)
			(size 0.0762 0.0762)
			(layers "F.Cu" "F.Mask" "F.Paste")
			(net "PHY_IOC_TO_CON_A_3_DP_C")
			(options
				(clearance outline)
				(anchor circle)
			)
			(primitives
				(gr_poly
					(pts
						(arc
							(start 0.1524 -0.127)
							(mid 0.137521 -0.162921)
							(end 0.1016 -0.1778)
						)
						(arc
							(start -0.1016 -0.1778)
							(mid -0.137521 -0.162921)
							(end -0.1524 -0.127)
						)
						(arc
							(start -0.1524 0.127)
							(mid -0.137521 0.162921)
							(end -0.1016 0.1778)
						)
						(arc
							(start 0.1016 0.1778)
							(mid 0.137521 0.162921)
							(end 0.1524 0.127)
						)
					)
					(width 0)
					(fill yes)
				)
			)
		)
		(pad "2" smd custom
			(at 0 0.2794 90)
			(size 0.0762 0.0762)
			(layers "F.Cu" "F.Mask" "F.Paste")
			(net "PHY_IOC_TO_CON_A_3_DP")
			(options
				(clearance outline)
				(anchor circle)
			)
			(primitives
				(gr_poly
					(pts
						(arc
							(start 0.1524 -0.127)
							(mid 0.137521 -0.162921)
							(end 0.1016 -0.1778)
						)
						(arc
							(start -0.1016 -0.1778)
							(mid -0.137521 -0.162921)
							(end -0.1524 -0.127)
						)
						(arc
							(start -0.1524 0.127)
							(mid -0.137521 0.162921)
							(end -0.1016 0.1778)
						)
						(arc
							(start 0.1016 0.1778)
							(mid 0.137521 0.162921)
							(end 0.1524 0.127)
						)
					)
					(width 0)
					(fill yes)
				)
			)
		)
	)
	(footprint ""
		(layer "F.Cu")
		(at 61.2394 -137.5664)
		(property "Reference" "TP71"
			(at 0 0 0)
			(layer "F.SilkS")
			(hide yes)
			(effects
				(font
					(size 1.27 1.27)
				)
			)
		)
		(property "Value" "TPAD28-2-GP"
			(at -0.0127 -1.6637 0)
			(unlocked yes)
			(layer "F.Fab")
			(hide yes)
			(effects
				(font
					(size 1.016 1.016)
					(thickness 0.1524)
				)
			)
		)
		(property "Device Type" "TPAD28"
			(at -0.0127 -3.1877 0)
			(unlocked yes)
			(layer "F.Fab")
			(hide yes)
			(effects
				(font
					(size 1.016 1.016)
					(thickness 0.1524)
				)
			)
		)
		(duplicate_pad_numbers_are_jumpers no)
		(fp_poly
			(pts
				(arc
					(start 0.3556 0)
					(mid -0.3556 0)
					(end 0.3556 0)
				)
			)
			(stroke
				(width 0)
				(type default)
			)
			(fill no)
			(layer "F.CrtYd")
		)
		(fp_poly
			(pts
				(arc
					(start 0.6096 0)
					(mid -0.6096 0)
					(end 0.6096 0)
				)
			)
			(stroke
				(width 0)
				(type default)
			)
			(fill no)
			(layer "F.Fab")
		)
		(pad "1" smd circle
			(at 0 0)
			(size 0.7112 0.7112)
			(layers "F.Cu" "F.Mask" "F.Paste")
			(net "TP_BMC_GPIOI4")
		)
	)
	(footprint ""
		(layer "F.Cu")
		(at 70.7898 -168.5544 -90)
		(property "Reference" "D11"
			(at 0 0 270)
			(layer "F.SilkS")
			(hide yes)
			(effects
				(font
					(size 1.27 1.27)
				)
			)
		)
		(property "Value" "BAT54WS-7-F-GP"
			(at 0 -6.7818 270)
			(unlocked yes)
			(layer "F.Fab")
			(hide yes)
			(effects
				(font
					(size 1.016 1.016)
					(thickness 0.1524)
				)
			)
		)
		(property "Device Type" "SOD323AKH42"
			(at 0 -8.6868 270)
			(unlocked yes)
			(layer "F.Fab")
			(hide yes)
			(effects
				(font
					(size 1.016 1.016)
					(thickness 0.1524)
				)
			)
		)
		(duplicate_pad_numbers_are_jumpers no)
		(fp_line
			(start -0.889 2.159)
			(end -0.889 -1.9304)
			(stroke
				(width 0.1524)
				(type default)
			)
			(layer "F.SilkS")
		)
		(fp_line
			(start 0.889 2.159)
			(end -0.889 2.159)
			(stroke
				(width 0.1524)
				(type default)
			)
			(layer "F.SilkS")
		)
		(fp_line
			(start 0.762 2.0574)
			(end -0.762 2.0574)
			(stroke
				(width 0.508)
				(type default)
			)
			(layer "F.SilkS")
		)
		(fp_line
			(start -0.889 -1.9304)
			(end 0.889 -1.9304)
			(stroke
				(width 0.1524)
				(type default)
			)
			(layer "F.SilkS")
		)
		(fp_line
			(start 0.889 -1.9304)
			(end 0.889 2.159)
			(stroke
				(width 0.1524)
				(type default)
			)
			(layer "F.SilkS")
		)
		(fp_rect
			(start -1.016 2.3114)
			(end 1.016 -2.0066)
			(stroke
				(width 0)
				(type default)
			)
			(fill no)
			(layer "F.CrtYd")
		)
		(fp_poly
			(pts
				(xy -1.016 -2.0066) (xy 1.016 -2.0066) (xy 1.016 2.3114) (xy -1.016 2.3114)
			)
			(stroke
				(width 0)
				(type default)
			)
			(fill no)
			(layer "F.Fab")
		)
		(pad "A" smd rect
			(at 0 -1.143 270)
			(size 0.5588 1.016)
			(layers "F.Cu" "F.Mask" "F.Paste")
			(net "BMC_SELF_HW_RST")
		)
		(pad "K" smd rect
			(at 0 1.143 270)
			(size 0.5588 1.016)
			(layers "F.Cu" "F.Mask" "F.Paste")
			(net "BMC_SELF_HW_RST_D")
		)
	)
	(footprint ""
		(layer "F.Cu")
		(at 135.40232 -27.5082)
		(property "Reference" "TP3"
			(at 0 0 0)
			(layer "F.SilkS")
			(hide yes)
			(effects
				(font
					(size 1.27 1.27)
				)
			)
		)
		(property "Value" "TPAD28-2-GP"
			(at -0.0127 -1.6637 0)
			(unlocked yes)
			(layer "F.Fab")
			(hide yes)
			(effects
				(font
					(size 1.016 1.016)
					(thickness 0.1524)
				)
			)
		)
		(property "Device Type" "TPAD28"
			(at -0.0127 -3.1877 0)
			(unlocked yes)
			(layer "F.Fab")
			(hide yes)
			(effects
				(font
					(size 1.016 1.016)
					(thickness 0.1524)
				)
			)
		)
		(duplicate_pad_numbers_are_jumpers no)
		(fp_poly
			(pts
				(arc
					(start 0.3556 0)
					(mid -0.3556 0)
					(end 0.3556 0)
				)
			)
			(stroke
				(width 0)
				(type default)
			)
			(fill no)
			(layer "F.CrtYd")
		)
		(fp_poly
			(pts
				(arc
					(start 0.6096 0)
					(mid -0.6096 0)
					(end 0.6096 0)
				)
			)
			(stroke
				(width 0)
				(type default)
			)
			(fill no)
			(layer "F.Fab")
		)
		(pad "1" smd circle
			(at 0 0)
			(size 0.7112 0.7112)
			(layers "F.Cu" "F.Mask" "F.Paste")
			(net "PCIE_COMP_TO_IOM_RST_3")
		)
	)
	(footprint ""
		(layer "F.Cu")
		(at 182.340504 -151.975566 -90)
		(property "Reference" "R463"
			(at 0 0 270)
			(layer "F.SilkS")
			(hide yes)
			(effects
				(font
					(size 1.27 1.27)
				)
			)
		)
		(property "Value" "10KR2F-2-GP"
			(at 0.064008 -3.993896 270)
			(unlocked yes)
			(layer "F.Fab")
			(hide yes)
			(effects
				(font
					(size 1.016 1.016)
					(thickness 0.1524)
				)
			)
		)
		(property "Device Type" "R402H16"
			(at 0.064008 -5.517896 270)
			(unlocked yes)
			(layer "F.Fab")
			(hide yes)
			(effects
				(font
					(size 1.016 1.016)
					(thickness 0.1524)
				)
			)
		)
		(duplicate_pad_numbers_are_jumpers no)
		(fp_line
			(start -0.508 -0.9398)
			(end -0.508 0.9398)
			(stroke
				(width 0.1524)
				(type default)
			)
			(layer "F.SilkS")
		)
		(fp_line
			(start 0.508 -0.9398)
			(end -0.508 -0.9398)
			(stroke
				(width 0.1524)
				(type default)
			)
			(layer "F.SilkS")
		)
		(fp_rect
			(start -0.508 0.9398)
			(end 0.508 -0.9398)
			(stroke
				(width 0)
				(type default)
			)
			(fill no)
			(layer "F.CrtYd")
		)
		(fp_rect
			(start -0.508 0.9398)
			(end 0.508 -0.9398)
			(stroke
				(width 0)
				(type default)
			)
			(fill no)
			(layer "F.Fab")
		)
		(pad "1" smd custom
			(at 0 -0.4445 270)
			(size 0.1397 0.1397)
			(layers "F.Cu" "F.Mask" "F.Paste")
			(net "P12V_STBY")
			(options
				(clearance outline)
				(anchor circle)
			)
			(primitives
				(gr_poly
					(pts
						(arc
							(start -0.1778 -0.2794)
							(mid -0.249642 -0.249642)
							(end -0.2794 -0.1778)
						)
						(arc
							(start -0.2794 0.1778)
							(mid -0.249642 0.249642)
							(end -0.1778 0.2794)
						)
						(arc
							(start 0.1778 0.2794)
							(mid 0.249642 0.249642)
							(end 0.2794 0.1778)
						)
						(arc
							(start 0.2794 -0.1778)
							(mid 0.249642 -0.249642)
							(end 0.1778 -0.2794)
						)
					)
					(width 0)
					(fill yes)
				)
			)
		)
		(pad "2" smd custom
			(at 0 0.4445 270)
			(size 0.1397 0.1397)
			(layers "F.Cu" "F.Mask" "F.Paste")
			(net "P5V_EN_R")
			(options
				(clearance outline)
				(anchor circle)
			)
			(primitives
				(gr_poly
					(pts
						(arc
							(start -0.1778 -0.2794)
							(mid -0.249642 -0.249642)
							(end -0.2794 -0.1778)
						)
						(arc
							(start -0.2794 0.1778)
							(mid -0.249642 0.249642)
							(end -0.1778 0.2794)
						)
						(arc
							(start 0.1778 0.2794)
							(mid 0.249642 0.249642)
							(end 0.2794 0.1778)
						)
						(arc
							(start 0.2794 -0.1778)
							(mid 0.249642 -0.249642)
							(end 0.1778 -0.2794)
						)
					)
					(width 0)
					(fill yes)
				)
			)
		)
	)
	(footprint ""
		(layer "F.Cu")
		(at 61.974222 -135.331708 -90)
		(property "Reference" "R352"
			(at 0 0 270)
			(layer "F.SilkS")
			(hide yes)
			(effects
				(font
					(size 1.27 1.27)
				)
			)
		)
		(property "Value" "4K7R2F-GP"
			(at 0.064008 -3.993896 270)
			(unlocked yes)
			(layer "F.Fab")
			(hide yes)
			(effects
				(font
					(size 1.016 1.016)
					(thickness 0.1524)
				)
			)
		)
		(property "Device Type" "R402H16"
			(at 0.064008 -5.517896 270)
			(unlocked yes)
			(layer "F.Fab")
			(hide yes)
			(effects
				(font
					(size 1.016 1.016)
					(thickness 0.1524)
				)
			)
		)
		(duplicate_pad_numbers_are_jumpers no)
		(fp_line
			(start -0.508 -0.9398)
			(end -0.508 0.9398)
			(stroke
				(width 0.1524)
				(type default)
			)
			(layer "F.SilkS")
		)
		(fp_line
			(start 0.508 -0.9398)
			(end -0.508 -0.9398)
			(stroke
				(width 0.1524)
				(type default)
			)
			(layer "F.SilkS")
		)
		(fp_rect
			(start -0.508 0.9398)
			(end 0.508 -0.9398)
			(stroke
				(width 0)
				(type default)
			)
			(fill no)
			(layer "F.CrtYd")
		)
		(fp_rect
			(start -0.508 0.9398)
			(end 0.508 -0.9398)
			(stroke
				(width 0)
				(type default)
			)
			(fill no)
			(layer "F.Fab")
		)
		(pad "1" smd custom
			(at 0 -0.4445 270)
			(size 0.1397 0.1397)
			(layers "F.Cu" "F.Mask" "F.Paste")
			(net "P3V3_STBY")
			(options
				(clearance outline)
				(anchor circle)
			)
			(primitives
				(gr_poly
					(pts
						(arc
							(start -0.1778 -0.2794)
							(mid -0.249642 -0.249642)
							(end -0.2794 -0.1778)
						)
						(arc
							(start -0.2794 0.1778)
							(mid -0.249642 0.249642)
							(end -0.1778 0.2794)
						)
						(arc
							(start 0.1778 0.2794)
							(mid 0.249642 0.249642)
							(end 0.2794 0.1778)
						)
						(arc
							(start 0.2794 -0.1778)
							(mid 0.249642 -0.249642)
							(end 0.1778 -0.2794)
						)
					)
					(width 0)
					(fill yes)
				)
			)
		)
		(pad "2" smd custom
			(at 0 0.4445 270)
			(size 0.1397 0.1397)
			(layers "F.Cu" "F.Mask" "F.Paste")
			(net "SLOTID_0")
			(options
				(clearance outline)
				(anchor circle)
			)
			(primitives
				(gr_poly
					(pts
						(arc
							(start -0.1778 -0.2794)
							(mid -0.249642 -0.249642)
							(end -0.2794 -0.1778)
						)
						(arc
							(start -0.2794 0.1778)
							(mid -0.249642 0.249642)
							(end -0.1778 0.2794)
						)
						(arc
							(start 0.1778 0.2794)
							(mid 0.249642 0.249642)
							(end 0.2794 0.1778)
						)
						(arc
							(start 0.2794 -0.1778)
							(mid 0.249642 -0.249642)
							(end 0.1778 -0.2794)
						)
					)
					(width 0)
					(fill yes)
				)
			)
		)
	)
	(footprint ""
		(layer "F.Cu")
		(at 84.983828 -72.525636 90)
		(property "Reference" "VIA9"
			(at 0 0 90)
			(layer "F.SilkS")
			(hide yes)
			(effects
				(font
					(size 1.27 1.27)
				)
			)
		)
		(property "Value" "85OHM-8L-1D6MM-L16L18-GP"
			(at 4.064 0.6096 90)
			(unlocked yes)
			(layer "F.Fab")
			(hide yes)
			(effects
				(font
					(size 1.016 1.016)
					(thickness 0.1524)
				)
			)
		)
		(property "Device Type" "VIA-PCIE-4P-368076"
			(at 4.064 -0.9144 90)
			(unlocked yes)
			(layer "F.Fab")
			(hide yes)
			(effects
				(font
					(size 1.016 1.016)
					(thickness 0.1524)
				)
			)
		)
		(duplicate_pad_numbers_are_jumpers no)
		(fp_rect
			(start -1.8415 0.381)
			(end 1.8415 -0.381)
			(stroke
				(width 0)
				(type default)
			)
			(fill no)
			(layer "F.CrtYd")
		)
		(fp_rect
			(start -1.8415 0.381)
			(end 1.8415 -0.381)
			(stroke
				(width 0)
				(type default)
			)
			(fill no)
			(layer "F.Fab")
		)
		(pad "1" thru_hole circle
			(at -1.4605 0 90)
			(size 0.508 0.508)
			(drill 0.254)
			(layers "*.Cu" "*.Mask")
			(remove_unused_layers no)
			(net "GND")
			(clearance 0.127)
			(thermal_gap 0.127)
		)
		(pad "2" thru_hole circle
			(at -0.4445 0 90)
			(size 0.508 0.508)
			(drill 0.254)
			(layers "*.Cu" "*.Mask")
			(remove_unused_layers no)
			(net "PCIE_IOM_TO_COMP_16_DP")
			(clearance 0.127)
			(thermal_gap 0.127)
		)
		(pad "3" thru_hole circle
			(at 0.4445 0 90)
			(size 0.508 0.508)
			(drill 0.254)
			(layers "*.Cu" "*.Mask")
			(remove_unused_layers no)
			(net "PCIE_IOM_TO_COMP_16_DN")
			(clearance 0.127)
			(thermal_gap 0.127)
		)
		(pad "4" thru_hole circle
			(at 1.4605 0 90)
			(size 0.508 0.508)
			(drill 0.254)
			(layers "*.Cu" "*.Mask")
			(remove_unused_layers no)
			(net "GND")
			(clearance 0.127)
			(thermal_gap 0.127)
		)
	)
	(footprint ""
		(layer "F.Cu")
		(at 202.164188 -133.250432)
		(property "Reference" "R547"
			(at 0 0 0)
			(layer "F.SilkS")
			(hide yes)
			(effects
				(font
					(size 1.27 1.27)
				)
			)
		)
		(property "Value" "0R2J-2-GP"
			(at 0.064008 -3.993896 0)
			(unlocked yes)
			(layer "F.Fab")
			(hide yes)
			(effects
				(font
					(size 1.016 1.016)
					(thickness 0.1524)
				)
			)
		)
		(property "Device Type" "R402H16"
			(at 0.064008 -5.517896 0)
			(unlocked yes)
			(layer "F.Fab")
			(hide yes)
			(effects
				(font
					(size 1.016 1.016)
					(thickness 0.1524)
				)
			)
		)
		(duplicate_pad_numbers_are_jumpers no)
		(fp_line
			(start -0.508 -0.9398)
			(end -0.508 0.9398)
			(stroke
				(width 0.1524)
				(type default)
			)
			(layer "F.SilkS")
		)
		(fp_line
			(start 0.508 -0.9398)
			(end -0.508 -0.9398)
			(stroke
				(width 0.1524)
				(type default)
			)
			(layer "F.SilkS")
		)
		(fp_rect
			(start -0.508 0.9398)
			(end 0.508 -0.9398)
			(stroke
				(width 0)
				(type default)
			)
			(fill no)
			(layer "F.CrtYd")
		)
		(fp_rect
			(start -0.508 0.9398)
			(end 0.508 -0.9398)
			(stroke
				(width 0)
				(type default)
			)
			(fill no)
			(layer "F.Fab")
		)
		(pad "1" smd custom
			(at 0 -0.4445)
			(size 0.1397 0.1397)
			(layers "F.Cu" "F.Mask" "F.Paste")
			(net "P5V_STBY")
			(options
				(clearance outline)
				(anchor circle)
			)
			(primitives
				(gr_poly
					(pts
						(arc
							(start -0.1778 -0.2794)
							(mid -0.249642 -0.249642)
							(end -0.2794 -0.1778)
						)
						(arc
							(start -0.2794 0.1778)
							(mid -0.249642 0.249642)
							(end -0.1778 0.2794)
						)
						(arc
							(start 0.1778 0.2794)
							(mid 0.249642 0.249642)
							(end 0.2794 0.1778)
						)
						(arc
							(start 0.2794 -0.1778)
							(mid 0.249642 -0.249642)
							(end 0.1778 -0.2794)
						)
					)
					(width 0)
					(fill yes)
				)
			)
		)
		(pad "2" smd custom
			(at 0 0.4445)
			(size 0.1397 0.1397)
			(layers "F.Cu" "F.Mask" "F.Paste")
			(net "TPS74801_1V5_BIAS")
			(options
				(clearance outline)
				(anchor circle)
			)
			(primitives
				(gr_poly
					(pts
						(arc
							(start -0.1778 -0.2794)
							(mid -0.249642 -0.249642)
							(end -0.2794 -0.1778)
						)
						(arc
							(start -0.2794 0.1778)
							(mid -0.249642 0.249642)
							(end -0.1778 0.2794)
						)
						(arc
							(start 0.1778 0.2794)
							(mid 0.249642 0.249642)
							(end 0.2794 0.1778)
						)
						(arc
							(start 0.2794 -0.1778)
							(mid 0.249642 -0.249642)
							(end 0.1778 -0.2794)
						)
					)
					(width 0)
					(fill yes)
				)
			)
		)
	)
	(footprint ""
		(layer "F.Cu")
		(at 164.6174 -128.0414 90)
		(property "Reference" "R519"
			(at 0 0 90)
			(layer "F.SilkS")
			(hide yes)
			(effects
				(font
					(size 1.27 1.27)
				)
			)
		)
		(property "Value" "1KR2F-3-GP"
			(at 0.064008 -3.993896 90)
			(unlocked yes)
			(layer "F.Fab")
			(hide yes)
			(effects
				(font
					(size 1.016 1.016)
					(thickness 0.1524)
				)
			)
		)
		(property "Device Type" "R402H16"
			(at 0.064008 -5.517896 90)
			(unlocked yes)
			(layer "F.Fab")
			(hide yes)
			(effects
				(font
					(size 1.016 1.016)
					(thickness 0.1524)
				)
			)
		)
		(duplicate_pad_numbers_are_jumpers no)
		(fp_line
			(start 0.508 -0.9398)
			(end -0.508 -0.9398)
			(stroke
				(width 0.1524)
				(type default)
			)
			(layer "F.SilkS")
		)
		(fp_line
			(start -0.508 -0.9398)
			(end -0.508 0.9398)
			(stroke
				(width 0.1524)
				(type default)
			)
			(layer "F.SilkS")
		)
		(fp_rect
			(start -0.508 0.9398)
			(end 0.508 -0.9398)
			(stroke
				(width 0)
				(type default)
			)
			(fill no)
			(layer "F.CrtYd")
		)
		(fp_rect
			(start -0.508 0.9398)
			(end 0.508 -0.9398)
			(stroke
				(width 0)
				(type default)
			)
			(fill no)
			(layer "F.Fab")
		)
		(pad "1" smd custom
			(at 0 -0.4445 90)
			(size 0.1397 0.1397)
			(layers "F.Cu" "F.Mask" "F.Paste")
			(net "P1V8_STBY_SW")
			(options
				(clearance outline)
				(anchor circle)
			)
			(primitives
				(gr_poly
					(pts
						(arc
							(start -0.1778 -0.2794)
							(mid -0.249642 -0.249642)
							(end -0.2794 -0.1778)
						)
						(arc
							(start -0.2794 0.1778)
							(mid -0.249642 0.249642)
							(end -0.1778 0.2794)
						)
						(arc
							(start 0.1778 0.2794)
							(mid 0.249642 0.249642)
							(end 0.2794 0.1778)
						)
						(arc
							(start 0.2794 -0.1778)
							(mid 0.249642 -0.249642)
							(end 0.1778 -0.2794)
						)
					)
					(width 0)
					(fill yes)
				)
			)
		)
		(pad "2" smd custom
			(at 0 0.4445 90)
			(size 0.1397 0.1397)
			(layers "F.Cu" "F.Mask" "F.Paste")
			(net "P1V8_STBY_VFB_R")
			(options
				(clearance outline)
				(anchor circle)
			)
			(primitives
				(gr_poly
					(pts
						(arc
							(start -0.1778 -0.2794)
							(mid -0.249642 -0.249642)
							(end -0.2794 -0.1778)
						)
						(arc
							(start -0.2794 0.1778)
							(mid -0.249642 0.249642)
							(end -0.1778 0.2794)
						)
						(arc
							(start 0.1778 0.2794)
							(mid 0.249642 0.249642)
							(end 0.2794 0.1778)
						)
						(arc
							(start 0.2794 -0.1778)
							(mid 0.249642 -0.249642)
							(end 0.1778 -0.2794)
						)
					)
					(width 0)
					(fill yes)
				)
			)
		)
	)
	(footprint ""
		(layer "F.Cu")
		(at 195.6562 -49.9618)
		(property "Reference" "TP143"
			(at 0 0 0)
			(layer "F.SilkS")
			(hide yes)
			(effects
				(font
					(size 1.27 1.27)
				)
			)
		)
		(property "Value" "TPAD28-2-GP"
			(at -0.0127 -1.6637 0)
			(unlocked yes)
			(layer "F.Fab")
			(hide yes)
			(effects
				(font
					(size 1.016 1.016)
					(thickness 0.1524)
				)
			)
		)
		(property "Device Type" "TPAD28"
			(at -0.0127 -3.1877 0)
			(unlocked yes)
			(layer "F.Fab")
			(hide yes)
			(effects
				(font
					(size 1.016 1.016)
					(thickness 0.1524)
				)
			)
		)
		(duplicate_pad_numbers_are_jumpers no)
		(fp_poly
			(pts
				(arc
					(start 0.3556 0)
					(mid -0.3556 0)
					(end 0.3556 0)
				)
			)
			(stroke
				(width 0)
				(type default)
			)
			(fill no)
			(layer "F.CrtYd")
		)
		(fp_poly
			(pts
				(arc
					(start 0.6096 0)
					(mid -0.6096 0)
					(end 0.6096 0)
				)
			)
			(stroke
				(width 0)
				(type default)
			)
			(fill no)
			(layer "F.Fab")
		)
		(pad "1" smd circle
			(at 0 0)
			(size 0.7112 0.7112)
			(layers "F.Cu" "F.Mask" "F.Paste")
			(net "ICE1_TDO")
		)
	)
	(footprint ""
		(layer "F.Cu")
		(at 27.800046 -186.56681 180)
		(property "Reference" "C176"
			(at 0 0 180)
			(layer "F.SilkS")
			(hide yes)
			(effects
				(font
					(size 1.27 1.27)
				)
			)
		)
		(property "Value" "SC10U16V5KX-7-GP-U"
			(at -0.0762 -6.1214 180)
			(unlocked yes)
			(layer "F.Fab")
			(hide yes)
			(effects
				(font
					(size 1.016 1.016)
					(thickness 0.1524)
				)
			)
		)
		(property "Device Type" "C805H58"
			(at -0.0762 -8.1534 180)
			(unlocked yes)
			(layer "F.Fab")
			(hide yes)
			(effects
				(font
					(size 1.016 1.016)
					(thickness 0.1524)
				)
			)
		)
		(duplicate_pad_numbers_are_jumpers no)
		(fp_line
			(start 0.635 0)
			(end -0.635 0)
			(stroke
				(width 0.508)
				(type default)
			)
			(layer "F.SilkS")
		)
		(fp_rect
			(start -0.9652 1.778)
			(end 0.9652 -1.778)
			(stroke
				(width 0)
				(type default)
			)
			(fill no)
			(layer "F.CrtYd")
		)
		(fp_poly
			(pts
				(xy -0.9652 -1.778) (xy 0.9652 -1.778) (xy 0.9652 1.778) (xy -0.9652 1.778)
			)
			(stroke
				(width 0)
				(type default)
			)
			(fill no)
			(layer "F.Fab")
		)
		(pad "1" smd rect
			(at 0 -0.9652 180)
			(size 1.397 1.143)
			(layers "F.Cu" "F.Mask" "F.Paste")
			(net "P12V_STBY_VIN_PU2")
		)
		(pad "2" smd rect
			(at 0 0.9652 180)
			(size 1.397 1.143)
			(layers "F.Cu" "F.Mask" "F.Paste")
			(net "GND")
		)
	)
	(footprint ""
		(layer "F.Cu")
		(at 82.441796 -173.57598 90)
		(property "Reference" "C194"
			(at 0 0 90)
			(layer "F.SilkS")
			(hide yes)
			(effects
				(font
					(size 1.27 1.27)
				)
			)
		)
		(property "Value" "SC10U6D3V5KX-4GP"
			(at -0.0762 -6.1214 90)
			(unlocked yes)
			(layer "F.Fab")
			(hide yes)
			(effects
				(font
					(size 1.016 1.016)
					(thickness 0.1524)
				)
			)
		)
		(property "Device Type" "C805H58"
			(at -0.0762 -8.1534 90)
			(unlocked yes)
			(layer "F.Fab")
			(hide yes)
			(effects
				(font
					(size 1.016 1.016)
					(thickness 0.1524)
				)
			)
		)
		(duplicate_pad_numbers_are_jumpers no)
		(fp_line
			(start 0.635 0)
			(end -0.635 0)
			(stroke
				(width 0.508)
				(type default)
			)
			(layer "F.SilkS")
		)
		(fp_rect
			(start -0.9652 1.778)
			(end 0.9652 -1.778)
			(stroke
				(width 0)
				(type default)
			)
			(fill no)
			(layer "F.CrtYd")
		)
		(fp_poly
			(pts
				(xy -0.9652 -1.778) (xy 0.9652 -1.778) (xy 0.9652 1.778) (xy -0.9652 1.778)
			)
			(stroke
				(width 0)
				(type default)
			)
			(fill no)
			(layer "F.Fab")
		)
		(pad "1" smd rect
			(at 0 -0.9652 90)
			(size 1.397 1.143)
			(layers "F.Cu" "F.Mask" "F.Paste")
			(net "TPS74801_P2V5_STBY_OUT")
		)
		(pad "2" smd rect
			(at 0 0.9652 90)
			(size 1.397 1.143)
			(layers "F.Cu" "F.Mask" "F.Paste")
			(net "GND")
		)
	)
	(footprint ""
		(layer "F.Cu")
		(at 180.594 -157.226 90)
		(property "Reference" "C160"
			(at 0 0 90)
			(layer "F.SilkS")
			(hide yes)
			(effects
				(font
					(size 1.27 1.27)
				)
			)
		)
		(property "Value" "SCD1U50V3KX-GP"
			(at 0 -2.8194 90)
			(unlocked yes)
			(layer "F.Fab")
			(hide yes)
			(effects
				(font
					(size 1.016 1.016)
					(thickness 0.1524)
				)
			)
		)
		(property "Device Type" "C603H36"
			(at 0 -4.3434 90)
			(unlocked yes)
			(layer "F.Fab")
			(hide yes)
			(effects
				(font
					(size 1.016 1.016)
					(thickness 0.1524)
				)
			)
		)
		(duplicate_pad_numbers_are_jumpers no)
		(fp_line
			(start 0.508 0)
			(end -0.508 0)
			(stroke
				(width 0.2032)
				(type default)
			)
			(layer "F.SilkS")
		)
		(fp_rect
			(start -0.5842 1.3335)
			(end 0.5842 -1.3335)
			(stroke
				(width 0)
				(type default)
			)
			(fill no)
			(layer "F.CrtYd")
		)
		(fp_rect
			(start -0.5842 1.3335)
			(end 0.5842 -1.3335)
			(stroke
				(width 0)
				(type default)
			)
			(fill no)
			(layer "F.Fab")
		)
		(pad "1" smd custom
			(at 0 -0.762 90)
			(size 0.2159 0.2159)
			(layers "F.Cu" "F.Mask" "F.Paste")
			(net "P5V_STBY")
			(options
				(clearance outline)
				(anchor circle)
			)
			(primitives
				(gr_poly
					(pts
						(arc
							(start -0.3302 -0.4318)
							(mid -0.402042 -0.402042)
							(end -0.4318 -0.3302)
						)
						(arc
							(start -0.4318 0.3302)
							(mid -0.402042 0.402042)
							(end -0.3302 0.4318)
						)
						(arc
							(start 0.3302 0.4318)
							(mid 0.402042 0.402042)
							(end 0.4318 0.3302)
						)
						(arc
							(start 0.4318 -0.3302)
							(mid 0.402042 -0.402042)
							(end 0.3302 -0.4318)
						)
					)
					(width 0)
					(fill yes)
				)
			)
		)
		(pad "2" smd custom
			(at 0 0.762 90)
			(size 0.2159 0.2159)
			(layers "F.Cu" "F.Mask" "F.Paste")
			(net "P5V_LL_R")
			(options
				(clearance outline)
				(anchor circle)
			)
			(primitives
				(gr_poly
					(pts
						(arc
							(start -0.3302 -0.4318)
							(mid -0.402042 -0.402042)
							(end -0.4318 -0.3302)
						)
						(arc
							(start -0.4318 0.3302)
							(mid -0.402042 0.402042)
							(end -0.3302 0.4318)
						)
						(arc
							(start 0.3302 0.4318)
							(mid 0.402042 0.402042)
							(end 0.4318 0.3302)
						)
						(arc
							(start 0.4318 -0.3302)
							(mid 0.402042 -0.402042)
							(end 0.3302 -0.4318)
						)
					)
					(width 0)
					(fill yes)
				)
			)
		)
	)
	(footprint ""
		(layer "F.Cu")
		(at 75.091036 -180.35778 -90)
		(property "Reference" "PU9"
			(at 0 0 270)
			(layer "F.SilkS")
			(hide yes)
			(effects
				(font
					(size 1.27 1.27)
				)
			)
		)
		(property "Value" "TPS74801RGW-GP"
			(at -4.7244 -6.223 270)
			(unlocked yes)
			(layer "F.Fab")
			(hide yes)
			(effects
				(font
					(size 1.016 1.016)
					(thickness 0.1524)
				)
			)
		)
		(property "Device Type" "QFN20-1G3D15H40"
			(at -4.7244 -7.747 270)
			(unlocked yes)
			(layer "F.Fab")
			(hide yes)
			(effects
				(font
					(size 1.016 1.016)
					(thickness 0.1524)
				)
			)
		)
		(duplicate_pad_numbers_are_jumpers no)
		(fp_line
			(start -3.5179 3.5179)
			(end -2.2479 3.5179)
			(stroke
				(width 0.1524)
				(type default)
			)
			(layer "F.SilkS")
		)
		(fp_line
			(start 2.2479 3.5179)
			(end 3.5179 3.5179)
			(stroke
				(width 0.1524)
				(type default)
			)
			(layer "F.SilkS")
		)
		(fp_line
			(start 3.5179 3.5179)
			(end 3.5179 2.2479)
			(stroke
				(width 0.1524)
				(type default)
			)
			(layer "F.SilkS")
		)
		(fp_line
			(start 1.299972 3.160522)
			(end 1.299972 3.668522)
			(stroke
				(width 0.1524)
				(type default)
			)
			(layer "F.SilkS")
		)
		(fp_line
			(start -3.5179 2.2479)
			(end -3.5179 3.5179)
			(stroke
				(width 0.1524)
				(type default)
			)
			(layer "F.SilkS")
		)
		(fp_line
			(start -3.160522 1.299972)
			(end -3.922522 1.299972)
			(stroke
				(width 0.1524)
				(type default)
			)
			(layer "F.SilkS")
		)
		(fp_line
			(start 3.160522 -1.299972)
			(end 3.922522 -1.299972)
			(stroke
				(width 0.1524)
				(type default)
			)
			(layer "F.SilkS")
		)
		(fp_line
			(start -1.299972 -3.160522)
			(end -1.299972 -3.668522)
			(stroke
				(width 0.1524)
				(type default)
			)
			(layer "F.SilkS")
		)
		(fp_line
			(start -3.5179 -3.5179)
			(end -3.5179 -2.2479)
			(stroke
				(width 0.1524)
				(type default)
			)
			(layer "F.SilkS")
		)
		(fp_line
			(start -2.2479 -3.5179)
			(end -3.5179 -3.5179)
			(stroke
				(width 0.1524)
				(type default)
			)
			(layer "F.SilkS")
		)
		(fp_poly
			(pts
				(xy 3.5179 -3.5179) (xy 2.2479 -3.5179) (xy 3.5179 -2.2479)
			)
			(stroke
				(width 0)
				(type default)
			)
			(fill yes)
			(layer "F.SilkS")
		)
		(fp_rect
			(start -2.5019 2.5019)
			(end 2.5019 -2.5019)
			(stroke
				(width 0)
				(type default)
			)
			(fill no)
			(layer "F.CrtYd")
		)
		(fp_poly
			(pts
				(xy -3.5179 3.5179) (xy -3.5179 -3.5179) (xy 3.5179 -3.5179) (xy 3.5179 -2.5019) (xy -2.5019 -2.5019)
				(xy -2.5019 2.5019) (xy 2.5019 2.5019) (xy 2.5019 -2.49682) (xy 3.5179 -2.49682) (xy 3.5179 3.5179)
			)
			(stroke
				(width 0)
				(type default)
			)
			(fill no)
			(layer "F.CrtYd")
		)
		(fp_rect
			(start -3.5179 3.5179)
			(end 3.5179 -3.5179)
			(stroke
				(width 0)
				(type default)
			)
			(fill no)
			(layer "F.Fab")
		)
		(pad "1" smd rect
			(at 1.299972 -2.474722 270)
			(size 0.3556 1.0668)
			(layers "F.Cu" "F.Mask" "F.Paste")
			(net "TPS74801_P2V5_STBY_OUT")
		)
		(pad "2" smd rect
			(at 0.649986 -2.474722 270)
			(size 0.3556 1.0668)
			(layers "F.Cu" "F.Mask" "F.Paste")
			(net "GND")
		)
		(pad "3" smd rect
			(at 0 -2.474722 270)
			(size 0.3556 1.0668)
			(layers "F.Cu" "F.Mask" "F.Paste")
			(net "GND")
		)
		(pad "4" smd rect
			(at -0.649986 -2.474722 270)
			(size 0.3556 1.0668)
			(layers "F.Cu" "F.Mask" "F.Paste")
			(net "GND")
		)
		(pad "5" smd rect
			(at -1.299972 -2.474722 270)
			(size 0.3556 1.0668)
			(layers "F.Cu" "F.Mask" "F.Paste")
			(net "P3V3_STBY")
		)
		(pad "6" smd rect
			(at -2.474722 -1.299972 270)
			(size 1.0668 0.3556)
			(layers "F.Cu" "F.Mask" "F.Paste")
			(net "P3V3_STBY")
		)
		(pad "7" smd rect
			(at -2.474722 -0.649986 270)
			(size 1.0668 0.3556)
			(layers "F.Cu" "F.Mask" "F.Paste")
			(net "P3V3_STBY")
		)
		(pad "8" smd rect
			(at -2.474722 0 270)
			(size 1.0668 0.3556)
			(layers "F.Cu" "F.Mask" "F.Paste")
			(net "P3V3_STBY")
		)
		(pad "9" smd rect
			(at -2.474722 0.649986 270)
			(size 1.0668 0.3556)
			(layers "F.Cu" "F.Mask" "F.Paste")
			(net "PWRGD_P2V5_STBY")
		)
		(pad "10" smd rect
			(at -2.474722 1.299972 270)
			(size 1.0668 0.3556)
			(layers "F.Cu" "F.Mask" "F.Paste")
			(net "TPS74801_P2V5_STBY_BIAS")
		)
		(pad "11" smd rect
			(at -1.299972 2.474722 270)
			(size 0.3556 1.0668)
			(layers "F.Cu" "F.Mask" "F.Paste")
			(net "TPS74801_P2V5_STBY_EN")
		)
		(pad "12" smd rect
			(at -0.649986 2.474722 270)
			(size 0.3556 1.0668)
			(layers "F.Cu" "F.Mask" "F.Paste")
			(net "GND")
		)
		(pad "13" smd rect
			(at 0 2.474722 270)
			(size 0.3556 1.0668)
			(layers "F.Cu" "F.Mask" "F.Paste")
			(net "GND")
		)
		(pad "14" smd rect
			(at 0.649986 2.474722 270)
			(size 0.3556 1.0668)
			(layers "F.Cu" "F.Mask" "F.Paste")
			(net "GND")
		)
		(pad "15" smd rect
			(at 1.299972 2.474722 270)
			(size 0.3556 1.0668)
			(layers "F.Cu" "F.Mask" "F.Paste")
			(net "TPS74801_P2V5_STBY_SS")
		)
		(pad "16" smd rect
			(at 2.474722 1.299972 270)
			(size 1.0668 0.3556)
			(layers "F.Cu" "F.Mask" "F.Paste")
			(net "TPS74801_P2V5_STBY_FB")
		)
		(pad "17" smd rect
			(at 2.474722 0.649986 270)
			(size 1.0668 0.3556)
			(layers "F.Cu" "F.Mask" "F.Paste")
			(net "GND")
		)
		(pad "18" smd rect
			(at 2.474722 0 270)
			(size 1.0668 0.3556)
			(layers "F.Cu" "F.Mask" "F.Paste")
			(net "TPS74801_P2V5_STBY_OUT")
		)
		(pad "19" smd rect
			(at 2.474722 -0.649986 270)
			(size 1.0668 0.3556)
			(layers "F.Cu" "F.Mask" "F.Paste")
			(net "TPS74801_P2V5_STBY_OUT")
		)
		(pad "20" smd rect
			(at 2.474722 -1.299972 270)
			(size 1.0668 0.3556)
			(layers "F.Cu" "F.Mask" "F.Paste")
			(net "TPS74801_P2V5_STBY_OUT")
		)
		(pad "21" smd rect
			(at 0 0 270)
			(size 3.2512 3.2512)
			(layers "F.Cu" "F.Mask" "F.Paste")
			(net "GND")
		)
	)
	(footprint ""
		(layer "F.Cu")
		(at 66.675 -137.033 90)
		(property "Reference" "R49"
			(at 0 0 90)
			(layer "F.SilkS")
			(hide yes)
			(effects
				(font
					(size 1.27 1.27)
				)
			)
		)
		(property "Value" "10KR2F-2-GP"
			(at 0.064008 -3.993896 90)
			(unlocked yes)
			(layer "F.Fab")
			(hide yes)
			(effects
				(font
					(size 1.016 1.016)
					(thickness 0.1524)
				)
			)
		)
		(property "Device Type" "R402H16"
			(at 0.064008 -5.517896 90)
			(unlocked yes)
			(layer "F.Fab")
			(hide yes)
			(effects
				(font
					(size 1.016 1.016)
					(thickness 0.1524)
				)
			)
		)
		(duplicate_pad_numbers_are_jumpers no)
		(fp_line
			(start 0.508 -0.9398)
			(end -0.508 -0.9398)
			(stroke
				(width 0.1524)
				(type default)
			)
			(layer "F.SilkS")
		)
		(fp_line
			(start -0.508 -0.9398)
			(end -0.508 0.9398)
			(stroke
				(width 0.1524)
				(type default)
			)
			(layer "F.SilkS")
		)
		(fp_rect
			(start -0.508 0.9398)
			(end 0.508 -0.9398)
			(stroke
				(width 0)
				(type default)
			)
			(fill no)
			(layer "F.CrtYd")
		)
		(fp_rect
			(start -0.508 0.9398)
			(end 0.508 -0.9398)
			(stroke
				(width 0)
				(type default)
			)
			(fill no)
			(layer "F.Fab")
		)
		(pad "1" smd custom
			(at 0 -0.4445 90)
			(size 0.1397 0.1397)
			(layers "F.Cu" "F.Mask" "F.Paste")
			(net "P3V3_STBY")
			(options
				(clearance outline)
				(anchor circle)
			)
			(primitives
				(gr_poly
					(pts
						(arc
							(start -0.1778 -0.2794)
							(mid -0.249642 -0.249642)
							(end -0.2794 -0.1778)
						)
						(arc
							(start -0.2794 0.1778)
							(mid -0.249642 0.249642)
							(end -0.1778 0.2794)
						)
						(arc
							(start 0.1778 0.2794)
							(mid 0.249642 0.249642)
							(end 0.2794 0.1778)
						)
						(arc
							(start 0.2794 -0.1778)
							(mid 0.249642 -0.249642)
							(end 0.1778 -0.2794)
						)
					)
					(width 0)
					(fill yes)
				)
			)
		)
		(pad "2" smd custom
			(at 0 0.4445 90)
			(size 0.1397 0.1397)
			(layers "F.Cu" "F.Mask" "F.Paste")
			(net "FP_PWRBTN")
			(options
				(clearance outline)
				(anchor circle)
			)
			(primitives
				(gr_poly
					(pts
						(arc
							(start -0.1778 -0.2794)
							(mid -0.249642 -0.249642)
							(end -0.2794 -0.1778)
						)
						(arc
							(start -0.2794 0.1778)
							(mid -0.249642 0.249642)
							(end -0.1778 0.2794)
						)
						(arc
							(start 0.1778 0.2794)
							(mid 0.249642 0.249642)
							(end 0.2794 0.1778)
						)
						(arc
							(start 0.2794 -0.1778)
							(mid 0.249642 -0.249642)
							(end 0.1778 -0.2794)
						)
					)
					(width 0)
					(fill yes)
				)
			)
		)
	)
	(footprint ""
		(layer "F.Cu")
		(at 88.9 -12.649962)
		(property "Reference" "USB1"
			(at 0 0 0)
			(layer "F.SilkS")
			(hide yes)
			(effects
				(font
					(size 1.27 1.27)
				)
			)
		)
		(property "Value" "SKT-USB13-246-GP"
			(at 4.9149 11.7348 0)
			(unlocked yes)
			(layer "F.Fab")
			(hide yes)
			(effects
				(font
					(size 1.016 1.016)
					(thickness 0.1524)
				)
			)
		)
		(property "Device Type" "SKT-USB13-064258"
			(at 4.9149 10.2108 0)
			(unlocked yes)
			(layer "F.Fab")
			(hide yes)
			(effects
				(font
					(size 1.016 1.016)
					(thickness 0.1524)
				)
			)
		)
		(duplicate_pad_numbers_are_jumpers no)
		(fp_line
			(start -3.827526 -10.395204)
			(end -3.827526 -11.004804)
			(stroke
				(width 0.3048)
				(type default)
			)
			(layer "F.SilkS")
		)
		(fp_line
			(start -3.827526 0.6477)
			(end -3.827526 -0.6477)
			(stroke
				(width 0.3048)
				(type default)
			)
			(layer "F.SilkS")
		)
		(fp_line
			(start -3.7211 -12.8016)
			(end 3.7211 -12.8016)
			(stroke
				(width 0.1524)
				(type default)
			)
			(layer "F.SilkS")
		)
		(fp_line
			(start -3.7211 -9.5758)
			(end -3.7211 -12.8016)
			(stroke
				(width 0.1524)
				(type default)
			)
			(layer "F.SilkS")
		)
		(fp_line
			(start -3.7211 -1.4732)
			(end -3.4671 -1.4732)
			(stroke
				(width 0.1524)
				(type default)
			)
			(layer "F.SilkS")
		)
		(fp_line
			(start -3.7211 1.4732)
			(end -3.7211 -1.4732)
			(stroke
				(width 0.1524)
				(type default)
			)
			(layer "F.SilkS")
		)
		(fp_line
			(start -3.4671 -9.5758)
			(end -3.7211 -9.5758)
			(stroke
				(width 0.1524)
				(type default)
			)
			(layer "F.SilkS")
		)
		(fp_line
			(start -3.4671 -1.4732)
			(end -3.4671 -9.5758)
			(stroke
				(width 0.1524)
				(type default)
			)
			(layer "F.SilkS")
		)
		(fp_line
			(start -3.4671 1.4732)
			(end -3.7211 1.4732)
			(stroke
				(width 0.1524)
				(type default)
			)
			(layer "F.SilkS")
		)
		(fp_line
			(start -3.4671 12.649962)
			(end -3.4671 1.4732)
			(stroke
				(width 0.1524)
				(type default)
			)
			(layer "F.SilkS")
		)
		(fp_line
			(start -3.4671 13.462)
			(end -3.4671 12.649962)
			(stroke
				(width 0.1524)
				(type default)
			)
			(layer "F.SilkS")
		)
		(fp_line
			(start -1.592326 -11.004804)
			(end -1.592326 -10.395204)
			(stroke
				(width 0.3048)
				(type default)
			)
			(layer "F.SilkS")
		)
		(fp_line
			(start -1.592326 -0.6477)
			(end -1.592326 0.6477)
			(stroke
				(width 0.3048)
				(type default)
			)
			(layer "F.SilkS")
		)
		(fp_line
			(start 1.592326 -10.052304)
			(end 1.592326 -11.347704)
			(stroke
				(width 0.3048)
				(type default)
			)
			(layer "F.SilkS")
		)
		(fp_line
			(start 1.592326 0.3048)
			(end 1.592326 -0.3048)
			(stroke
				(width 0.3048)
				(type default)
			)
			(layer "F.SilkS")
		)
		(fp_line
			(start 3.4671 -9.2202)
			(end 3.4671 -1.1303)
			(stroke
				(width 0.1524)
				(type default)
			)
			(layer "F.SilkS")
		)
		(fp_line
			(start 3.4671 -1.1303)
			(end 3.7211 -1.1303)
			(stroke
				(width 0.1524)
				(type default)
			)
			(layer "F.SilkS")
		)
		(fp_line
			(start 3.4671 1.1303)
			(end 3.4671 12.649962)
			(stroke
				(width 0.1524)
				(type default)
			)
			(layer "F.SilkS")
		)
		(fp_line
			(start 3.4671 12.649962)
			(end -3.4671 12.649962)
			(stroke
				(width 0.1524)
				(type default)
			)
			(layer "F.SilkS")
		)
		(fp_line
			(start 3.4671 12.649962)
			(end 3.4671 13.462)
			(stroke
				(width 0.1524)
				(type default)
			)
			(layer "F.SilkS")
		)
		(fp_line
			(start 3.4671 13.462)
			(end -3.4671 13.462)
			(stroke
				(width 0.1524)
				(type default)
			)
			(layer "F.SilkS")
		)
		(fp_line
			(start 3.7211 -12.8016)
			(end 3.7211 -9.2202)
			(stroke
				(width 0.1524)
				(type default)
			)
			(layer "F.SilkS")
		)
		(fp_line
			(start 3.7211 -9.2202)
			(end 3.4671 -9.2202)
			(stroke
				(width 0.1524)
				(type default)
			)
			(layer "F.SilkS")
		)
		(fp_line
			(start 3.7211 -1.1303)
			(end 3.7211 1.1303)
			(stroke
				(width 0.1524)
				(type default)
			)
			(layer "F.SilkS")
		)
		(fp_line
			(start 3.7211 1.1303)
			(end 3.4671 1.1303)
			(stroke
				(width 0.1524)
				(type default)
			)
			(layer "F.SilkS")
		)
		(fp_line
			(start 3.827526 -11.347704)
			(end 3.827526 -10.052304)
			(stroke
				(width 0.3048)
				(type default)
			)
			(layer "F.SilkS")
		)
		(fp_line
			(start 3.827526 -0.3048)
			(end 3.827526 0.3048)
			(stroke
				(width 0.3048)
				(type default)
			)
			(layer "F.SilkS")
		)
		(fp_arc
			(start -3.827526 -11.004804)
			(mid -2.709926 -12.122404)
			(end -1.592326 -11.004804)
			(stroke
				(width 0.3048)
				(type default)
			)
			(layer "F.SilkS")
		)
		(fp_arc
			(start -3.827526 -0.6477)
			(mid -2.709926 -1.7653)
			(end -1.592326 -0.6477)
			(stroke
				(width 0.3048)
				(type default)
			)
			(layer "F.SilkS")
		)
		(fp_arc
			(start -1.592326 -10.395204)
			(mid -2.709926 -9.277604)
			(end -3.827526 -10.395204)
			(stroke
				(width 0.3048)
				(type default)
			)
			(layer "F.SilkS")
		)
		(fp_arc
			(start -1.592326 0.6477)
			(mid -2.709926 1.7653)
			(end -3.827526 0.6477)
			(stroke
				(width 0.3048)
				(type default)
			)
			(layer "F.SilkS")
		)
		(fp_arc
			(start 1.592326 -11.347704)
			(mid 2.709926 -12.465304)
			(end 3.827526 -11.347704)
			(stroke
				(width 0.3048)
				(type default)
			)
			(layer "F.SilkS")
		)
		(fp_arc
			(start 1.592326 -0.3048)
			(mid 2.709926 -1.4224)
			(end 3.827526 -0.3048)
			(stroke
				(width 0.3048)
				(type default)
			)
			(layer "F.SilkS")
		)
		(fp_arc
			(start 1.607566 -9.8679)
			(mid 1.596126 -9.959786)
			(end 1.592326 -10.052304)
			(stroke
				(width 0.3048)
				(type default)
			)
			(layer "F.SilkS")
		)
		(fp_arc
			(start 1.783588 -9.426956)
			(mid 0.074258 -9.000444)
			(end 1.607566 -9.8679)
			(stroke
				(width 0.3048)
				(type default)
			)
			(layer "F.SilkS")
		)
		(fp_arc
			(start 3.827526 -10.052304)
			(mid 3.036889 -8.983601)
			(end 1.783588 -9.426956)
			(stroke
				(width 0.3048)
				(type default)
			)
			(layer "F.SilkS")
		)
		(fp_arc
			(start 3.827526 0.3048)
			(mid 2.709926 1.4224)
			(end 1.592326 0.3048)
			(stroke
				(width 0.3048)
				(type default)
			)
			(layer "F.SilkS")
		)
		(fp_circle
			(center -0.899922 -8.830056)
			(end -0.010922 -8.830056)
			(stroke
				(width 0.3048)
				(type default)
			)
			(fill no)
			(layer "F.SilkS")
		)
		(fp_circle
			(center -0.899922 -6.329934)
			(end -0.010922 -6.329934)
			(stroke
				(width 0.3048)
				(type default)
			)
			(fill no)
			(layer "F.SilkS")
		)
		(fp_circle
			(center -0.899922 -4.329938)
			(end -0.010922 -4.329938)
			(stroke
				(width 0.3048)
				(type default)
			)
			(fill no)
			(layer "F.SilkS")
		)
		(fp_circle
			(center -0.899922 -1.829816)
			(end -0.010922 -1.829816)
			(stroke
				(width 0.3048)
				(type default)
			)
			(fill no)
			(layer "F.SilkS")
		)
		(fp_circle
			(center -0.899922 -1.829816)
			(end -0.010922 -1.829816)
			(stroke
				(width 0.3048)
				(type default)
			)
			(fill no)
			(layer "F.SilkS")
		)
		(fp_circle
			(center 0.899922 -7.329932)
			(end 1.788922 -7.329932)
			(stroke
				(width 0.3048)
				(type default)
			)
			(fill no)
			(layer "F.SilkS")
		)
		(fp_circle
			(center 0.899922 -5.329936)
			(end 1.788922 -5.329936)
			(stroke
				(width 0.3048)
				(type default)
			)
			(fill no)
			(layer "F.SilkS")
		)
		(fp_circle
			(center 0.899922 -3.32994)
			(end 1.788922 -3.32994)
			(stroke
				(width 0.3048)
				(type default)
			)
			(fill no)
			(layer "F.SilkS")
		)
		(fp_circle
			(center 0.899922 -1.329944)
			(end 1.788922 -1.329944)
			(stroke
				(width 0.3048)
				(type default)
			)
			(fill no)
			(layer "F.SilkS")
		)
		(fp_circle
			(center 0.899922 -1.329944)
			(end 1.788922 -1.329944)
			(stroke
				(width 0.3048)
				(type default)
			)
			(fill no)
			(layer "F.SilkS")
		)
		(fp_rect
			(start -3.2131 13.208)
			(end 3.2131 -12.5476)
			(stroke
				(width 0)
				(type default)
			)
			(fill no)
			(layer "F.CrtYd")
		)
		(fp_poly
			(pts
				(xy -3.7211 13.716) (xy -3.7211 1.7272) (xy -3.9751 1.7272) (xy -3.9751 -1.7272) (xy -3.7211 -1.7272)
				(xy -3.7211 -9.3218) (xy -3.9751 -9.3218) (xy -3.9751 -13.0556) (xy 3.9751 -13.0556) (xy 3.9751 -8.9662)
				(xy 3.7211 -8.9662) (xy 3.7211 -1.3843) (xy 3.9751 -1.3843) (xy 3.9751 -0.00635) (xy 3.2131 -0.00635)
				(xy 3.2131 -12.5476) (xy -3.2131 -12.5476) (xy -3.2131 13.208) (xy 3.2131 13.208) (xy 3.2131 0.00635)
				(xy 3.9751 0.00635) (xy 3.9751 1.3843) (xy 3.7211 1.3843) (xy 3.7211 13.716)
			)
			(stroke
				(width 0)
				(type default)
			)
			(fill no)
			(layer "F.CrtYd")
		)
		(fp_poly
			(pts
				(xy -3.7211 13.716) (xy -3.7211 1.7272) (xy -3.9751 1.7272) (xy -3.9751 -1.7272) (xy -3.7211 -1.7272)
				(xy -3.7211 -9.3218) (xy -3.9751 -9.3218) (xy -3.9751 -13.0556) (xy 3.9751 -13.0556) (xy 3.9751 -8.9662)
				(xy 3.7211 -8.9662) (xy 3.7211 -1.3843) (xy 3.9751 -1.3843) (xy 3.9751 1.3843) (xy 3.7211 1.3843)
				(xy 3.7211 13.716)
			)
			(stroke
				(width 0)
				(type default)
			)
			(fill no)
			(layer "F.Fab")
		)
		(pad "1" thru_hole circle
			(at -0.899922 -8.830056)
			(size 1.0668 1.0668)
			(drill 0.7112)
			(layers "*.Cu" "*.Mask")
			(remove_unused_layers no)
			(net "P5V_VBUS_CONN")
			(clearance 0.1778)
			(thermal_gap 0.1778)
		)
		(pad "2" thru_hole circle
			(at -0.899922 -6.329934)
			(size 1.0668 1.0668)
			(drill 0.7112)
			(layers "*.Cu" "*.Mask")
			(remove_unused_layers no)
			(net "USB_P1_F_DN1")
			(clearance 0.1778)
			(thermal_gap 0.1778)
		)
		(pad "3" thru_hole circle
			(at -0.899922 -4.329938)
			(size 1.0668 1.0668)
			(drill 0.7112)
			(layers "*.Cu" "*.Mask")
			(remove_unused_layers no)
			(net "USB_P1_F_DP1")
			(clearance 0.1778)
			(thermal_gap 0.1778)
		)
		(pad "4" thru_hole circle
			(at -0.899922 -1.829816)
			(size 1.0668 1.0668)
			(drill 0.7112)
			(layers "*.Cu" "*.Mask")
			(remove_unused_layers no)
			(net "GND")
			(clearance 0.1778)
			(thermal_gap 0.1778)
		)
		(pad "5" thru_hole circle
			(at 0.899922 -1.329944)
			(size 1.0668 1.0668)
			(drill 0.7112)
			(layers "*.Cu" "*.Mask")
			(remove_unused_layers no)
			(net "I2C_DEBUG_SCL")
			(clearance 0.1778)
			(thermal_gap 0.1778)
		)
		(pad "6" thru_hole circle
			(at 0.899922 -3.32994)
			(size 1.0668 1.0668)
			(drill 0.7112)
			(layers "*.Cu" "*.Mask")
			(remove_unused_layers no)
			(net "I2C_DEBUG_SDA")
			(clearance 0.1778)
			(thermal_gap 0.1778)
		)
		(pad "7" thru_hole circle
			(at 0.899922 -5.329936)
			(size 1.0668 1.0668)
			(drill 0.7112)
			(layers "*.Cu" "*.Mask")
			(remove_unused_layers no)
			(net "DEBUG_CARD_PRSNT")
			(clearance 0.1778)
			(thermal_gap 0.1778)
		)
		(pad "8" thru_hole circle
			(at 0.899922 -7.329932)
			(size 1.0668 1.0668)
			(drill 0.7112)
			(layers "*.Cu" "*.Mask")
			(remove_unused_layers no)
			(net "UART_IOM_TX")
			(clearance 0.1778)
			(thermal_gap 0.1778)
		)
		(pad "9" thru_hole circle
			(at 0.899922 -9.329928)
			(size 1.0668 1.0668)
			(drill 0.7112)
			(layers "*.Cu" "*.Mask")
			(remove_unused_layers no)
			(net "UART_IOM_RX")
			(clearance 0.1778)
			(thermal_gap 0.1778)
		)
		(pad "10" thru_hole oval
			(at -2.709926 -10.700004)
			(size 1.524 2.1336)
			(drill oval 0.8128 1.4224)
			(layers "*.Cu" "*.Mask")
			(remove_unused_layers no)
			(net "USB_CONN_GND")
			(clearance 0.1524)
			(thermal_gap 0.1524)
		)
		(pad "11" thru_hole oval
			(at -2.709926 0)
			(size 1.524 2.8194)
			(drill oval 0.8128 2.1082)
			(layers "*.Cu" "*.Mask")
			(remove_unused_layers no)
			(net "USB_CONN_GND")
			(clearance 0.1524)
			(thermal_gap 0.1524)
		)
		(pad "12" thru_hole oval
			(at 2.709926 0)
			(size 1.524 2.1336)
			(drill oval 0.8128 1.4224)
			(layers "*.Cu" "*.Mask")
			(remove_unused_layers no)
			(net "USB_CONN_GND")
			(clearance 0.1524)
			(thermal_gap 0.1524)
		)
		(pad "13" thru_hole oval
			(at 2.709926 -10.700004)
			(size 1.524 2.8194)
			(drill oval 0.8128 2.1082)
			(layers "*.Cu" "*.Mask")
			(remove_unused_layers no)
			(net "USB_CONN_GND")
			(clearance 0.1524)
			(thermal_gap 0.1524)
		)
	)
	(footprint ""
		(layer "F.Cu")
		(at 208.055972 -68.326 90)
		(property "Reference" "C317"
			(at 0 0 90)
			(layer "F.SilkS")
			(hide yes)
			(effects
				(font
					(size 1.27 1.27)
				)
			)
		)
		(property "Value" "SCD01U16V1KX-GP"
			(at -2.8321 -1.7399 90)
			(unlocked yes)
			(layer "F.Fab")
			(hide yes)
			(effects
				(font
					(size 1.016 1.016)
					(thickness 0.1524)
				)
			)
		)
		(property "Device Type" "C0201H13"
			(at -2.8321 -3.2639 90)
			(unlocked yes)
			(layer "F.Fab")
			(hide yes)
			(effects
				(font
					(size 1.016 1.016)
					(thickness 0.1524)
				)
			)
		)
		(duplicate_pad_numbers_are_jumpers no)
		(fp_rect
			(start -0.2794 0.6477)
			(end 0.2794 -0.6477)
			(stroke
				(width 0)
				(type default)
			)
			(fill no)
			(layer "F.CrtYd")
		)
		(fp_rect
			(start -0.2794 0.6477)
			(end 0.2794 -0.6477)
			(stroke
				(width 0)
				(type default)
			)
			(fill no)
			(layer "F.Fab")
		)
		(pad "1" smd custom
			(at 0 -0.2794 90)
			(size 0.0762 0.0762)
			(layers "F.Cu" "F.Mask" "F.Paste")
			(net "PHY_IOC_TO_CON_B_1_DP_C")
			(options
				(clearance outline)
				(anchor circle)
			)
			(primitives
				(gr_poly
					(pts
						(arc
							(start 0.1524 -0.127)
							(mid 0.137521 -0.162921)
							(end 0.1016 -0.1778)
						)
						(arc
							(start -0.1016 -0.1778)
							(mid -0.137521 -0.162921)
							(end -0.1524 -0.127)
						)
						(arc
							(start -0.1524 0.127)
							(mid -0.137521 0.162921)
							(end -0.1016 0.1778)
						)
						(arc
							(start 0.1016 0.1778)
							(mid 0.137521 0.162921)
							(end 0.1524 0.127)
						)
					)
					(width 0)
					(fill yes)
				)
			)
		)
		(pad "2" smd custom
			(at 0 0.2794 90)
			(size 0.0762 0.0762)
			(layers "F.Cu" "F.Mask" "F.Paste")
			(net "PHY_IOC_TO_CON_B_1_DP")
			(options
				(clearance outline)
				(anchor circle)
			)
			(primitives
				(gr_poly
					(pts
						(arc
							(start 0.1524 -0.127)
							(mid 0.137521 -0.162921)
							(end 0.1016 -0.1778)
						)
						(arc
							(start -0.1016 -0.1778)
							(mid -0.137521 -0.162921)
							(end -0.1524 -0.127)
						)
						(arc
							(start -0.1524 0.127)
							(mid -0.137521 0.162921)
							(end -0.1016 0.1778)
						)
						(arc
							(start 0.1016 0.1778)
							(mid 0.137521 0.162921)
							(end 0.1524 0.127)
						)
					)
					(width 0)
					(fill yes)
				)
			)
		)
	)
	(footprint ""
		(layer "F.Cu")
		(at 57.446672 -157.213808 90)
		(property "Reference" "TP53"
			(at 0 0 90)
			(layer "F.SilkS")
			(hide yes)
			(effects
				(font
					(size 1.27 1.27)
				)
			)
		)
		(property "Value" "TPAD28-2-GP"
			(at -0.0127 -1.6637 90)
			(unlocked yes)
			(layer "F.Fab")
			(hide yes)
			(effects
				(font
					(size 1.016 1.016)
					(thickness 0.1524)
				)
			)
		)
		(property "Device Type" "TPAD28"
			(at -0.0127 -3.1877 90)
			(unlocked yes)
			(layer "F.Fab")
			(hide yes)
			(effects
				(font
					(size 1.016 1.016)
					(thickness 0.1524)
				)
			)
		)
		(duplicate_pad_numbers_are_jumpers no)
		(fp_poly
			(pts
				(arc
					(start 0 0.3556)
					(mid 0 -0.3556)
					(end 0 0.3556)
				)
			)
			(stroke
				(width 0)
				(type default)
			)
			(fill no)
			(layer "F.CrtYd")
		)
		(fp_poly
			(pts
				(arc
					(start 0 0.6096)
					(mid 0 -0.6096)
					(end 0 0.6096)
				)
			)
			(stroke
				(width 0)
				(type default)
			)
			(fill no)
			(layer "F.Fab")
		)
		(pad "1" smd circle
			(at 0 0 90)
			(size 0.7112 0.7112)
			(layers "F.Cu" "F.Mask" "F.Paste")
			(net "TP_BMC_GPIOT6")
		)
	)
	(footprint ""
		(layer "F.Cu")
		(at 35.687 -157.5562)
		(property "Reference" "TP57"
			(at 0 0 0)
			(layer "F.SilkS")
			(hide yes)
			(effects
				(font
					(size 1.27 1.27)
				)
			)
		)
		(property "Value" "TPAD28-2-GP"
			(at -0.0127 -1.6637 0)
			(unlocked yes)
			(layer "F.Fab")
			(hide yes)
			(effects
				(font
					(size 1.016 1.016)
					(thickness 0.1524)
				)
			)
		)
		(property "Device Type" "TPAD28"
			(at -0.0127 -3.1877 0)
			(unlocked yes)
			(layer "F.Fab")
			(hide yes)
			(effects
				(font
					(size 1.016 1.016)
					(thickness 0.1524)
				)
			)
		)
		(duplicate_pad_numbers_are_jumpers no)
		(fp_poly
			(pts
				(arc
					(start 0.3556 0)
					(mid -0.3556 0)
					(end 0.3556 0)
				)
			)
			(stroke
				(width 0)
				(type default)
			)
			(fill no)
			(layer "F.CrtYd")
		)
		(fp_poly
			(pts
				(arc
					(start 0.6096 0)
					(mid -0.6096 0)
					(end 0.6096 0)
				)
			)
			(stroke
				(width 0)
				(type default)
			)
			(fill no)
			(layer "F.Fab")
		)
		(pad "1" smd circle
			(at 0 0)
			(size 0.7112 0.7112)
			(layers "F.Cu" "F.Mask" "F.Paste")
			(net "TP_BMC_GPION5")
		)
	)
	(footprint ""
		(layer "F.Cu")
		(at 47.060104 -161.180272 180)
		(property "Reference" "R179"
			(at 0 0 180)
			(layer "F.SilkS")
			(hide yes)
			(effects
				(font
					(size 1.27 1.27)
				)
			)
		)
		(property "Value" "2K2R2F-GP"
			(at 0.064008 -3.993896 180)
			(unlocked yes)
			(layer "F.Fab")
			(hide yes)
			(effects
				(font
					(size 1.016 1.016)
					(thickness 0.1524)
				)
			)
		)
		(property "Device Type" "R402H16"
			(at 0.064008 -5.517896 180)
			(unlocked yes)
			(layer "F.Fab")
			(hide yes)
			(effects
				(font
					(size 1.016 1.016)
					(thickness 0.1524)
				)
			)
		)
		(duplicate_pad_numbers_are_jumpers no)
		(fp_line
			(start 0.508 -0.9398)
			(end -0.508 -0.9398)
			(stroke
				(width 0.1524)
				(type default)
			)
			(layer "F.SilkS")
		)
		(fp_line
			(start -0.508 -0.9398)
			(end -0.508 0.9398)
			(stroke
				(width 0.1524)
				(type default)
			)
			(layer "F.SilkS")
		)
		(fp_rect
			(start -0.508 0.9398)
			(end 0.508 -0.9398)
			(stroke
				(width 0)
				(type default)
			)
			(fill no)
			(layer "F.CrtYd")
		)
		(fp_rect
			(start -0.508 0.9398)
			(end 0.508 -0.9398)
			(stroke
				(width 0)
				(type default)
			)
			(fill no)
			(layer "F.Fab")
		)
		(pad "1" smd custom
			(at 0 -0.4445 180)
			(size 0.1397 0.1397)
			(layers "F.Cu" "F.Mask" "F.Paste")
			(net "I2C_DPB_SCL_OUT")
			(options
				(clearance outline)
				(anchor circle)
			)
			(primitives
				(gr_poly
					(pts
						(arc
							(start -0.1778 -0.2794)
							(mid -0.249642 -0.249642)
							(end -0.2794 -0.1778)
						)
						(arc
							(start -0.2794 0.1778)
							(mid -0.249642 0.249642)
							(end -0.1778 0.2794)
						)
						(arc
							(start 0.1778 0.2794)
							(mid 0.249642 0.249642)
							(end 0.2794 0.1778)
						)
						(arc
							(start 0.2794 -0.1778)
							(mid 0.249642 -0.249642)
							(end 0.1778 -0.2794)
						)
					)
					(width 0)
					(fill yes)
				)
			)
		)
		(pad "2" smd custom
			(at 0 0.4445 180)
			(size 0.1397 0.1397)
			(layers "F.Cu" "F.Mask" "F.Paste")
			(net "P3V3_STBY")
			(options
				(clearance outline)
				(anchor circle)
			)
			(primitives
				(gr_poly
					(pts
						(arc
							(start -0.1778 -0.2794)
							(mid -0.249642 -0.249642)
							(end -0.2794 -0.1778)
						)
						(arc
							(start -0.2794 0.1778)
							(mid -0.249642 0.249642)
							(end -0.1778 0.2794)
						)
						(arc
							(start 0.1778 0.2794)
							(mid 0.249642 0.249642)
							(end 0.2794 0.1778)
						)
						(arc
							(start 0.2794 -0.1778)
							(mid 0.249642 -0.249642)
							(end 0.1778 -0.2794)
						)
					)
					(width 0)
					(fill yes)
				)
			)
		)
	)
	(footprint ""
		(layer "F.Cu")
		(at 73.05548 -185.90768)
		(property "Reference" "R508"
			(at 0 0 0)
			(layer "F.SilkS")
			(hide yes)
			(effects
				(font
					(size 1.27 1.27)
				)
			)
		)
		(property "Value" "0R2J-2-GP"
			(at 0.064008 -3.993896 0)
			(unlocked yes)
			(layer "F.Fab")
			(hide yes)
			(effects
				(font
					(size 1.016 1.016)
					(thickness 0.1524)
				)
			)
		)
		(property "Device Type" "R402H16"
			(at 0.064008 -5.517896 0)
			(unlocked yes)
			(layer "F.Fab")
			(hide yes)
			(effects
				(font
					(size 1.016 1.016)
					(thickness 0.1524)
				)
			)
		)
		(duplicate_pad_numbers_are_jumpers no)
		(fp_line
			(start -0.508 -0.9398)
			(end -0.508 0.9398)
			(stroke
				(width 0.1524)
				(type default)
			)
			(layer "F.SilkS")
		)
		(fp_line
			(start 0.508 -0.9398)
			(end -0.508 -0.9398)
			(stroke
				(width 0.1524)
				(type default)
			)
			(layer "F.SilkS")
		)
		(fp_rect
			(start -0.508 0.9398)
			(end 0.508 -0.9398)
			(stroke
				(width 0)
				(type default)
			)
			(fill no)
			(layer "F.CrtYd")
		)
		(fp_rect
			(start -0.508 0.9398)
			(end 0.508 -0.9398)
			(stroke
				(width 0)
				(type default)
			)
			(fill no)
			(layer "F.Fab")
		)
		(pad "1" smd custom
			(at 0 -0.4445)
			(size 0.1397 0.1397)
			(layers "F.Cu" "F.Mask" "F.Paste")
			(net "P5V_STBY")
			(options
				(clearance outline)
				(anchor circle)
			)
			(primitives
				(gr_poly
					(pts
						(arc
							(start -0.1778 -0.2794)
							(mid -0.249642 -0.249642)
							(end -0.2794 -0.1778)
						)
						(arc
							(start -0.2794 0.1778)
							(mid -0.249642 0.249642)
							(end -0.1778 0.2794)
						)
						(arc
							(start 0.1778 0.2794)
							(mid 0.249642 0.249642)
							(end 0.2794 0.1778)
						)
						(arc
							(start 0.2794 -0.1778)
							(mid 0.249642 -0.249642)
							(end 0.1778 -0.2794)
						)
					)
					(width 0)
					(fill yes)
				)
			)
		)
		(pad "2" smd custom
			(at 0 0.4445)
			(size 0.1397 0.1397)
			(layers "F.Cu" "F.Mask" "F.Paste")
			(net "TPS74801_P2V5_STBY_BIAS")
			(options
				(clearance outline)
				(anchor circle)
			)
			(primitives
				(gr_poly
					(pts
						(arc
							(start -0.1778 -0.2794)
							(mid -0.249642 -0.249642)
							(end -0.2794 -0.1778)
						)
						(arc
							(start -0.2794 0.1778)
							(mid -0.249642 0.249642)
							(end -0.1778 0.2794)
						)
						(arc
							(start 0.1778 0.2794)
							(mid 0.249642 0.249642)
							(end 0.2794 0.1778)
						)
						(arc
							(start 0.2794 -0.1778)
							(mid 0.249642 -0.249642)
							(end 0.1778 -0.2794)
						)
					)
					(width 0)
					(fill yes)
				)
			)
		)
	)
	(footprint ""
		(layer "F.Cu")
		(at 208.661 -81.915 90)
		(property "Reference" "R569"
			(at 0 0 90)
			(layer "F.SilkS")
			(hide yes)
			(effects
				(font
					(size 1.27 1.27)
				)
			)
		)
		(property "Value" "51R2F-2-GP"
			(at 0.064008 -3.993896 90)
			(unlocked yes)
			(layer "F.Fab")
			(hide yes)
			(effects
				(font
					(size 1.016 1.016)
					(thickness 0.1524)
				)
			)
		)
		(property "Device Type" "R402H16"
			(at 0.064008 -5.517896 90)
			(unlocked yes)
			(layer "F.Fab")
			(hide yes)
			(effects
				(font
					(size 1.016 1.016)
					(thickness 0.1524)
				)
			)
		)
		(duplicate_pad_numbers_are_jumpers no)
		(fp_line
			(start 0.508 -0.9398)
			(end -0.508 -0.9398)
			(stroke
				(width 0.1524)
				(type default)
			)
			(layer "F.SilkS")
		)
		(fp_line
			(start -0.508 -0.9398)
			(end -0.508 0.9398)
			(stroke
				(width 0.1524)
				(type default)
			)
			(layer "F.SilkS")
		)
		(fp_rect
			(start -0.508 0.9398)
			(end 0.508 -0.9398)
			(stroke
				(width 0)
				(type default)
			)
			(fill no)
			(layer "F.CrtYd")
		)
		(fp_rect
			(start -0.508 0.9398)
			(end 0.508 -0.9398)
			(stroke
				(width 0)
				(type default)
			)
			(fill no)
			(layer "F.Fab")
		)
		(pad "1" smd custom
			(at 0 -0.4445 90)
			(size 0.1397 0.1397)
			(layers "F.Cu" "F.Mask" "F.Paste")
			(net "PCIE_COMP_TO_IOM_CLK_2_DP")
			(options
				(clearance outline)
				(anchor circle)
			)
			(primitives
				(gr_poly
					(pts
						(arc
							(start -0.1778 -0.2794)
							(mid -0.249642 -0.249642)
							(end -0.2794 -0.1778)
						)
						(arc
							(start -0.2794 0.1778)
							(mid -0.249642 0.249642)
							(end -0.1778 0.2794)
						)
						(arc
							(start 0.1778 0.2794)
							(mid 0.249642 0.249642)
							(end 0.2794 0.1778)
						)
						(arc
							(start 0.2794 -0.1778)
							(mid 0.249642 -0.249642)
							(end 0.1778 -0.2794)
						)
					)
					(width 0)
					(fill yes)
				)
			)
		)
		(pad "2" smd custom
			(at 0 0.4445 90)
			(size 0.1397 0.1397)
			(layers "F.Cu" "F.Mask" "F.Paste")
			(net "GND")
			(options
				(clearance outline)
				(anchor circle)
			)
			(primitives
				(gr_poly
					(pts
						(arc
							(start -0.1778 -0.2794)
							(mid -0.249642 -0.249642)
							(end -0.2794 -0.1778)
						)
						(arc
							(start -0.2794 0.1778)
							(mid -0.249642 0.249642)
							(end -0.1778 0.2794)
						)
						(arc
							(start 0.1778 0.2794)
							(mid 0.249642 0.249642)
							(end 0.2794 0.1778)
						)
						(arc
							(start 0.2794 -0.1778)
							(mid 0.249642 -0.249642)
							(end 0.1778 -0.2794)
						)
					)
					(width 0)
					(fill yes)
				)
			)
		)
	)
	(footprint ""
		(layer "F.Cu")
		(at 30.912562 -154.893772 90)
		(property "Reference" "R331"
			(at 0 0 90)
			(layer "F.SilkS")
			(hide yes)
			(effects
				(font
					(size 1.27 1.27)
				)
			)
		)
		(property "Value" "4K7R2F-GP"
			(at 0.064008 -3.993896 90)
			(unlocked yes)
			(layer "F.Fab")
			(hide yes)
			(effects
				(font
					(size 1.016 1.016)
					(thickness 0.1524)
				)
			)
		)
		(property "Device Type" "R402H16"
			(at 0.064008 -5.517896 90)
			(unlocked yes)
			(layer "F.Fab")
			(hide yes)
			(effects
				(font
					(size 1.016 1.016)
					(thickness 0.1524)
				)
			)
		)
		(duplicate_pad_numbers_are_jumpers no)
		(fp_line
			(start 0.508 -0.9398)
			(end -0.508 -0.9398)
			(stroke
				(width 0.1524)
				(type default)
			)
			(layer "F.SilkS")
		)
		(fp_line
			(start -0.508 -0.9398)
			(end -0.508 0.9398)
			(stroke
				(width 0.1524)
				(type default)
			)
			(layer "F.SilkS")
		)
		(fp_rect
			(start -0.508 0.9398)
			(end 0.508 -0.9398)
			(stroke
				(width 0)
				(type default)
			)
			(fill no)
			(layer "F.CrtYd")
		)
		(fp_rect
			(start -0.508 0.9398)
			(end 0.508 -0.9398)
			(stroke
				(width 0)
				(type default)
			)
			(fill no)
			(layer "F.Fab")
		)
		(pad "1" smd custom
			(at 0 -0.4445 90)
			(size 0.1397 0.1397)
			(layers "F.Cu" "F.Mask" "F.Paste")
			(net "P3V3_STBY")
			(options
				(clearance outline)
				(anchor circle)
			)
			(primitives
				(gr_poly
					(pts
						(arc
							(start -0.1778 -0.2794)
							(mid -0.249642 -0.249642)
							(end -0.2794 -0.1778)
						)
						(arc
							(start -0.2794 0.1778)
							(mid -0.249642 0.249642)
							(end -0.1778 0.2794)
						)
						(arc
							(start 0.1778 0.2794)
							(mid 0.249642 0.249642)
							(end 0.2794 0.1778)
						)
						(arc
							(start 0.2794 -0.1778)
							(mid 0.249642 -0.249642)
							(end 0.1778 -0.2794)
						)
					)
					(width 0)
					(fill yes)
				)
			)
		)
		(pad "2" smd custom
			(at 0 0.4445 90)
			(size 0.1397 0.1397)
			(layers "F.Cu" "F.Mask" "F.Paste")
			(net "COMP_POWER_FAIL_N")
			(options
				(clearance outline)
				(anchor circle)
			)
			(primitives
				(gr_poly
					(pts
						(arc
							(start -0.1778 -0.2794)
							(mid -0.249642 -0.249642)
							(end -0.2794 -0.1778)
						)
						(arc
							(start -0.2794 0.1778)
							(mid -0.249642 0.249642)
							(end -0.1778 0.2794)
						)
						(arc
							(start 0.1778 0.2794)
							(mid 0.249642 0.249642)
							(end 0.2794 0.1778)
						)
						(arc
							(start 0.2794 -0.1778)
							(mid 0.249642 -0.249642)
							(end 0.1778 -0.2794)
						)
					)
					(width 0)
					(fill yes)
				)
			)
		)
	)
	(footprint ""
		(layer "F.Cu")
		(at 32.6898 -135.7884 90)
		(property "Reference" "R283"
			(at 0 0 90)
			(layer "F.SilkS")
			(hide yes)
			(effects
				(font
					(size 1.27 1.27)
				)
			)
		)
		(property "Value" "33R2F-3-GP"
			(at 0.064008 -3.993896 90)
			(unlocked yes)
			(layer "F.Fab")
			(hide yes)
			(effects
				(font
					(size 1.016 1.016)
					(thickness 0.1524)
				)
			)
		)
		(property "Device Type" "R402H16"
			(at 0.064008 -5.517896 90)
			(unlocked yes)
			(layer "F.Fab")
			(hide yes)
			(effects
				(font
					(size 1.016 1.016)
					(thickness 0.1524)
				)
			)
		)
		(duplicate_pad_numbers_are_jumpers no)
		(fp_line
			(start 0.508 -0.9398)
			(end -0.508 -0.9398)
			(stroke
				(width 0.1524)
				(type default)
			)
			(layer "F.SilkS")
		)
		(fp_line
			(start -0.508 -0.9398)
			(end -0.508 0.9398)
			(stroke
				(width 0.1524)
				(type default)
			)
			(layer "F.SilkS")
		)
		(fp_rect
			(start -0.508 0.9398)
			(end 0.508 -0.9398)
			(stroke
				(width 0)
				(type default)
			)
			(fill no)
			(layer "F.CrtYd")
		)
		(fp_rect
			(start -0.508 0.9398)
			(end 0.508 -0.9398)
			(stroke
				(width 0)
				(type default)
			)
			(fill no)
			(layer "F.Fab")
		)
		(pad "1" smd custom
			(at 0 -0.4445 90)
			(size 0.1397 0.1397)
			(layers "F.Cu" "F.Mask" "F.Paste")
			(net "BMC_SPI_CLK_R")
			(options
				(clearance outline)
				(anchor circle)
			)
			(primitives
				(gr_poly
					(pts
						(arc
							(start -0.1778 -0.2794)
							(mid -0.249642 -0.249642)
							(end -0.2794 -0.1778)
						)
						(arc
							(start -0.2794 0.1778)
							(mid -0.249642 0.249642)
							(end -0.1778 0.2794)
						)
						(arc
							(start 0.1778 0.2794)
							(mid 0.249642 0.249642)
							(end 0.2794 0.1778)
						)
						(arc
							(start 0.2794 -0.1778)
							(mid 0.249642 -0.249642)
							(end 0.1778 -0.2794)
						)
					)
					(width 0)
					(fill yes)
				)
			)
		)
		(pad "2" smd custom
			(at 0 0.4445 90)
			(size 0.1397 0.1397)
			(layers "F.Cu" "F.Mask" "F.Paste")
			(net "BMC_SPI_CLK")
			(options
				(clearance outline)
				(anchor circle)
			)
			(primitives
				(gr_poly
					(pts
						(arc
							(start -0.1778 -0.2794)
							(mid -0.249642 -0.249642)
							(end -0.2794 -0.1778)
						)
						(arc
							(start -0.2794 0.1778)
							(mid -0.249642 0.249642)
							(end -0.1778 0.2794)
						)
						(arc
							(start 0.1778 0.2794)
							(mid 0.249642 0.249642)
							(end 0.2794 0.1778)
						)
						(arc
							(start 0.2794 -0.1778)
							(mid 0.249642 -0.249642)
							(end 0.1778 -0.2794)
						)
					)
					(width 0)
					(fill yes)
				)
			)
		)
	)
	(footprint ""
		(layer "F.Cu")
		(at 10.7442 -139.573 90)
		(property "Reference" "R218"
			(at 0 0 90)
			(layer "F.SilkS")
			(hide yes)
			(effects
				(font
					(size 1.27 1.27)
				)
			)
		)
		(property "Value" "120R2F-GP"
			(at 0.064008 -3.993896 90)
			(unlocked yes)
			(layer "F.Fab")
			(hide yes)
			(effects
				(font
					(size 1.016 1.016)
					(thickness 0.1524)
				)
			)
		)
		(property "Device Type" "R402H16"
			(at 0.064008 -5.517896 90)
			(unlocked yes)
			(layer "F.Fab")
			(hide yes)
			(effects
				(font
					(size 1.016 1.016)
					(thickness 0.1524)
				)
			)
		)
		(duplicate_pad_numbers_are_jumpers no)
		(fp_line
			(start 0.508 -0.9398)
			(end -0.508 -0.9398)
			(stroke
				(width 0.1524)
				(type default)
			)
			(layer "F.SilkS")
		)
		(fp_line
			(start -0.508 -0.9398)
			(end -0.508 0.9398)
			(stroke
				(width 0.1524)
				(type default)
			)
			(layer "F.SilkS")
		)
		(fp_rect
			(start -0.508 0.9398)
			(end 0.508 -0.9398)
			(stroke
				(width 0)
				(type default)
			)
			(fill no)
			(layer "F.CrtYd")
		)
		(fp_rect
			(start -0.508 0.9398)
			(end 0.508 -0.9398)
			(stroke
				(width 0)
				(type default)
			)
			(fill no)
			(layer "F.Fab")
		)
		(pad "1" smd custom
			(at 0 -0.4445 90)
			(size 0.1397 0.1397)
			(layers "F.Cu" "F.Mask" "F.Paste")
			(net "MEMBG_0")
			(options
				(clearance outline)
				(anchor circle)
			)
			(primitives
				(gr_poly
					(pts
						(arc
							(start -0.1778 -0.2794)
							(mid -0.249642 -0.249642)
							(end -0.2794 -0.1778)
						)
						(arc
							(start -0.2794 0.1778)
							(mid -0.249642 0.249642)
							(end -0.1778 0.2794)
						)
						(arc
							(start 0.1778 0.2794)
							(mid 0.249642 0.249642)
							(end 0.2794 0.1778)
						)
						(arc
							(start 0.2794 -0.1778)
							(mid 0.249642 -0.249642)
							(end 0.1778 -0.2794)
						)
					)
					(width 0)
					(fill yes)
				)
			)
		)
		(pad "2" smd custom
			(at 0 0.4445 90)
			(size 0.1397 0.1397)
			(layers "F.Cu" "F.Mask" "F.Paste")
			(net "P1V2_STBY")
			(options
				(clearance outline)
				(anchor circle)
			)
			(primitives
				(gr_poly
					(pts
						(arc
							(start -0.1778 -0.2794)
							(mid -0.249642 -0.249642)
							(end -0.2794 -0.1778)
						)
						(arc
							(start -0.2794 0.1778)
							(mid -0.249642 0.249642)
							(end -0.1778 0.2794)
						)
						(arc
							(start 0.1778 0.2794)
							(mid 0.249642 0.249642)
							(end 0.2794 0.1778)
						)
						(arc
							(start 0.2794 -0.1778)
							(mid 0.249642 -0.249642)
							(end 0.1778 -0.2794)
						)
					)
					(width 0)
					(fill yes)
				)
			)
		)
	)
	(footprint ""
		(layer "F.Cu")
		(at 68.4784 -120.523 90)
		(property "Reference" "R764"
			(at 0 0 90)
			(layer "F.SilkS")
			(hide yes)
			(effects
				(font
					(size 1.27 1.27)
				)
			)
		)
		(property "Value" "0R2J-2-GP"
			(at 0.064008 -3.993896 90)
			(unlocked yes)
			(layer "F.Fab")
			(hide yes)
			(effects
				(font
					(size 1.016 1.016)
					(thickness 0.1524)
				)
			)
		)
		(property "Device Type" "R402H16"
			(at 0.064008 -5.517896 90)
			(unlocked yes)
			(layer "F.Fab")
			(hide yes)
			(effects
				(font
					(size 1.016 1.016)
					(thickness 0.1524)
				)
			)
		)
		(duplicate_pad_numbers_are_jumpers no)
		(fp_line
			(start 0.508 -0.9398)
			(end -0.508 -0.9398)
			(stroke
				(width 0.1524)
				(type default)
			)
			(layer "F.SilkS")
		)
		(fp_line
			(start -0.508 -0.9398)
			(end -0.508 0.9398)
			(stroke
				(width 0.1524)
				(type default)
			)
			(layer "F.SilkS")
		)
		(fp_rect
			(start -0.508 0.9398)
			(end 0.508 -0.9398)
			(stroke
				(width 0)
				(type default)
			)
			(fill no)
			(layer "F.CrtYd")
		)
		(fp_rect
			(start -0.508 0.9398)
			(end 0.508 -0.9398)
			(stroke
				(width 0)
				(type default)
			)
			(fill no)
			(layer "F.Fab")
		)
		(pad "1" smd custom
			(at 0 -0.4445 90)
			(size 0.1397 0.1397)
			(layers "F.Cu" "F.Mask" "F.Paste")
			(net "FLA1_SPI_RST")
			(options
				(clearance outline)
				(anchor circle)
			)
			(primitives
				(gr_poly
					(pts
						(arc
							(start -0.1778 -0.2794)
							(mid -0.249642 -0.249642)
							(end -0.2794 -0.1778)
						)
						(arc
							(start -0.2794 0.1778)
							(mid -0.249642 0.249642)
							(end -0.1778 0.2794)
						)
						(arc
							(start 0.1778 0.2794)
							(mid 0.249642 0.249642)
							(end 0.2794 0.1778)
						)
						(arc
							(start 0.2794 -0.1778)
							(mid 0.249642 -0.249642)
							(end 0.1778 -0.2794)
						)
					)
					(width 0)
					(fill yes)
				)
			)
		)
		(pad "2" smd custom
			(at 0 0.4445 90)
			(size 0.1397 0.1397)
			(layers "F.Cu" "F.Mask" "F.Paste")
			(net "RST_BMC_EXTRST_N")
			(options
				(clearance outline)
				(anchor circle)
			)
			(primitives
				(gr_poly
					(pts
						(arc
							(start -0.1778 -0.2794)
							(mid -0.249642 -0.249642)
							(end -0.2794 -0.1778)
						)
						(arc
							(start -0.2794 0.1778)
							(mid -0.249642 0.249642)
							(end -0.1778 0.2794)
						)
						(arc
							(start 0.1778 0.2794)
							(mid 0.249642 0.249642)
							(end 0.2794 0.1778)
						)
						(arc
							(start 0.2794 -0.1778)
							(mid 0.249642 -0.249642)
							(end 0.1778 -0.2794)
						)
					)
					(width 0)
					(fill yes)
				)
			)
		)
	)
	(footprint ""
		(layer "F.Cu")
		(at 180.35524 -82.94624 180)
		(property "Reference" "R656"
			(at 0 0 180)
			(layer "F.SilkS")
			(hide yes)
			(effects
				(font
					(size 1.27 1.27)
				)
			)
		)
		(property "Value" "10KR2F-2-GP"
			(at 0.064008 -3.993896 180)
			(unlocked yes)
			(layer "F.Fab")
			(hide yes)
			(effects
				(font
					(size 1.016 1.016)
					(thickness 0.1524)
				)
			)
		)
		(property "Device Type" "R402H16"
			(at 0.064008 -5.517896 180)
			(unlocked yes)
			(layer "F.Fab")
			(hide yes)
			(effects
				(font
					(size 1.016 1.016)
					(thickness 0.1524)
				)
			)
		)
		(duplicate_pad_numbers_are_jumpers no)
		(fp_line
			(start 0.508 -0.9398)
			(end -0.508 -0.9398)
			(stroke
				(width 0.1524)
				(type default)
			)
			(layer "F.SilkS")
		)
		(fp_line
			(start -0.508 -0.9398)
			(end -0.508 0.9398)
			(stroke
				(width 0.1524)
				(type default)
			)
			(layer "F.SilkS")
		)
		(fp_rect
			(start -0.508 0.9398)
			(end 0.508 -0.9398)
			(stroke
				(width 0)
				(type default)
			)
			(fill no)
			(layer "F.CrtYd")
		)
		(fp_rect
			(start -0.508 0.9398)
			(end 0.508 -0.9398)
			(stroke
				(width 0)
				(type default)
			)
			(fill no)
			(layer "F.Fab")
		)
		(pad "1" smd custom
			(at 0 -0.4445 180)
			(size 0.1397 0.1397)
			(layers "F.Cu" "F.Mask" "F.Paste")
			(net "SYS_DBMODE0")
			(options
				(clearance outline)
				(anchor circle)
			)
			(primitives
				(gr_poly
					(pts
						(arc
							(start -0.1778 -0.2794)
							(mid -0.249642 -0.249642)
							(end -0.2794 -0.1778)
						)
						(arc
							(start -0.2794 0.1778)
							(mid -0.249642 0.249642)
							(end -0.1778 0.2794)
						)
						(arc
							(start 0.1778 0.2794)
							(mid 0.249642 0.249642)
							(end 0.2794 0.1778)
						)
						(arc
							(start 0.2794 -0.1778)
							(mid 0.249642 -0.249642)
							(end 0.1778 -0.2794)
						)
					)
					(width 0)
					(fill yes)
				)
			)
		)
		(pad "2" smd custom
			(at 0 0.4445 180)
			(size 0.1397 0.1397)
			(layers "F.Cu" "F.Mask" "F.Paste")
			(net "GND")
			(options
				(clearance outline)
				(anchor circle)
			)
			(primitives
				(gr_poly
					(pts
						(arc
							(start -0.1778 -0.2794)
							(mid -0.249642 -0.249642)
							(end -0.2794 -0.1778)
						)
						(arc
							(start -0.2794 0.1778)
							(mid -0.249642 0.249642)
							(end -0.1778 0.2794)
						)
						(arc
							(start 0.1778 0.2794)
							(mid 0.249642 0.249642)
							(end 0.2794 0.1778)
						)
						(arc
							(start 0.2794 -0.1778)
							(mid 0.249642 -0.249642)
							(end 0.1778 -0.2794)
						)
					)
					(width 0)
					(fill yes)
				)
			)
		)
	)
	(footprint ""
		(layer "F.Cu")
		(at 98.484182 -151.45766 180)
		(property "Reference" "R43"
			(at 0 0 180)
			(layer "F.SilkS")
			(hide yes)
			(effects
				(font
					(size 1.27 1.27)
				)
			)
		)
		(property "Value" "4K7R2F-GP"
			(at 0.064008 -3.993896 180)
			(unlocked yes)
			(layer "F.Fab")
			(hide yes)
			(effects
				(font
					(size 1.016 1.016)
					(thickness 0.1524)
				)
			)
		)
		(property "Device Type" "R402H16"
			(at 0.064008 -5.517896 180)
			(unlocked yes)
			(layer "F.Fab")
			(hide yes)
			(effects
				(font
					(size 1.016 1.016)
					(thickness 0.1524)
				)
			)
		)
		(duplicate_pad_numbers_are_jumpers no)
		(fp_line
			(start 0.508 -0.9398)
			(end -0.508 -0.9398)
			(stroke
				(width 0.1524)
				(type default)
			)
			(layer "F.SilkS")
		)
		(fp_line
			(start -0.508 -0.9398)
			(end -0.508 0.9398)
			(stroke
				(width 0.1524)
				(type default)
			)
			(layer "F.SilkS")
		)
		(fp_rect
			(start -0.508 0.9398)
			(end 0.508 -0.9398)
			(stroke
				(width 0)
				(type default)
			)
			(fill no)
			(layer "F.CrtYd")
		)
		(fp_rect
			(start -0.508 0.9398)
			(end 0.508 -0.9398)
			(stroke
				(width 0)
				(type default)
			)
			(fill no)
			(layer "F.Fab")
		)
		(pad "1" smd custom
			(at 0 -0.4445 180)
			(size 0.1397 0.1397)
			(layers "F.Cu" "F.Mask" "F.Paste")
			(net "USB_EN_4")
			(options
				(clearance outline)
				(anchor circle)
			)
			(primitives
				(gr_poly
					(pts
						(arc
							(start -0.1778 -0.2794)
							(mid -0.249642 -0.249642)
							(end -0.2794 -0.1778)
						)
						(arc
							(start -0.2794 0.1778)
							(mid -0.249642 0.249642)
							(end -0.1778 0.2794)
						)
						(arc
							(start 0.1778 0.2794)
							(mid 0.249642 0.249642)
							(end 0.2794 0.1778)
						)
						(arc
							(start 0.2794 -0.1778)
							(mid 0.249642 -0.249642)
							(end 0.1778 -0.2794)
						)
					)
					(width 0)
					(fill yes)
				)
			)
		)
		(pad "2" smd custom
			(at 0 0.4445 180)
			(size 0.1397 0.1397)
			(layers "F.Cu" "F.Mask" "F.Paste")
			(net "GND")
			(options
				(clearance outline)
				(anchor circle)
			)
			(primitives
				(gr_poly
					(pts
						(arc
							(start -0.1778 -0.2794)
							(mid -0.249642 -0.249642)
							(end -0.2794 -0.1778)
						)
						(arc
							(start -0.2794 0.1778)
							(mid -0.249642 0.249642)
							(end -0.1778 0.2794)
						)
						(arc
							(start 0.1778 0.2794)
							(mid 0.249642 0.249642)
							(end 0.2794 0.1778)
						)
						(arc
							(start 0.2794 -0.1778)
							(mid 0.249642 -0.249642)
							(end 0.1778 -0.2794)
						)
					)
					(width 0)
					(fill yes)
				)
			)
		)
	)
	(footprint ""
		(layer "F.Cu")
		(at 152.4 -38.481)
		(property "Reference" "TP185"
			(at 0 0 0)
			(layer "F.SilkS")
			(hide yes)
			(effects
				(font
					(size 1.27 1.27)
				)
			)
		)
		(property "Value" "TPAD28-2-GP"
			(at -0.0127 -1.6637 0)
			(unlocked yes)
			(layer "F.Fab")
			(hide yes)
			(effects
				(font
					(size 1.016 1.016)
					(thickness 0.1524)
				)
			)
		)
		(property "Device Type" "TPAD28"
			(at -0.0127 -3.1877 0)
			(unlocked yes)
			(layer "F.Fab")
			(hide yes)
			(effects
				(font
					(size 1.016 1.016)
					(thickness 0.1524)
				)
			)
		)
		(duplicate_pad_numbers_are_jumpers no)
		(fp_poly
			(pts
				(arc
					(start 0.3556 0)
					(mid -0.3556 0)
					(end 0.3556 0)
				)
			)
			(stroke
				(width 0)
				(type default)
			)
			(fill no)
			(layer "F.CrtYd")
		)
		(fp_poly
			(pts
				(arc
					(start 0.6096 0)
					(mid -0.6096 0)
					(end 0.6096 0)
				)
			)
			(stroke
				(width 0)
				(type default)
			)
			(fill no)
			(layer "F.Fab")
		)
		(pad "1" smd circle
			(at 0 0)
			(size 0.7112 0.7112)
			(layers "F.Cu" "F.Mask" "F.Paste")
			(net "ZDEF_EXTB_TP_B2")
		)
	)
	(footprint ""
		(layer "F.Cu")
		(at 155.575 -136.6012 180)
		(property "Reference" "C213"
			(at 0 0 180)
			(layer "F.SilkS")
			(hide yes)
			(effects
				(font
					(size 1.27 1.27)
				)
			)
		)
		(property "Value" "SC1U16V3KX-5GP"
			(at 0 -2.8194 180)
			(unlocked yes)
			(layer "F.Fab")
			(hide yes)
			(effects
				(font
					(size 1.016 1.016)
					(thickness 0.1524)
				)
			)
		)
		(property "Device Type" "C603H36"
			(at 0 -4.3434 180)
			(unlocked yes)
			(layer "F.Fab")
			(hide yes)
			(effects
				(font
					(size 1.016 1.016)
					(thickness 0.1524)
				)
			)
		)
		(duplicate_pad_numbers_are_jumpers no)
		(fp_line
			(start 0.508 0)
			(end -0.508 0)
			(stroke
				(width 0.2032)
				(type default)
			)
			(layer "F.SilkS")
		)
		(fp_rect
			(start -0.5842 1.3335)
			(end 0.5842 -1.3335)
			(stroke
				(width 0)
				(type default)
			)
			(fill no)
			(layer "F.CrtYd")
		)
		(fp_rect
			(start -0.5842 1.3335)
			(end 0.5842 -1.3335)
			(stroke
				(width 0)
				(type default)
			)
			(fill no)
			(layer "F.Fab")
		)
		(pad "1" smd custom
			(at 0 -0.762 180)
			(size 0.2159 0.2159)
			(layers "F.Cu" "F.Mask" "F.Paste")
			(net "GND")
			(options
				(clearance outline)
				(anchor circle)
			)
			(primitives
				(gr_poly
					(pts
						(arc
							(start -0.3302 -0.4318)
							(mid -0.402042 -0.402042)
							(end -0.4318 -0.3302)
						)
						(arc
							(start -0.4318 0.3302)
							(mid -0.402042 0.402042)
							(end -0.3302 0.4318)
						)
						(arc
							(start 0.3302 0.4318)
							(mid 0.402042 0.402042)
							(end 0.4318 0.3302)
						)
						(arc
							(start 0.4318 -0.3302)
							(mid 0.402042 -0.402042)
							(end 0.3302 -0.4318)
						)
					)
					(width 0)
					(fill yes)
				)
			)
		)
		(pad "2" smd custom
			(at 0 0.762 180)
			(size 0.2159 0.2159)
			(layers "F.Cu" "F.Mask" "F.Paste")
			(net "P1V8_STBY_EN_R")
			(options
				(clearance outline)
				(anchor circle)
			)
			(primitives
				(gr_poly
					(pts
						(arc
							(start -0.3302 -0.4318)
							(mid -0.402042 -0.402042)
							(end -0.4318 -0.3302)
						)
						(arc
							(start -0.4318 0.3302)
							(mid -0.402042 0.402042)
							(end -0.3302 0.4318)
						)
						(arc
							(start 0.3302 0.4318)
							(mid 0.402042 0.402042)
							(end 0.4318 0.3302)
						)
						(arc
							(start 0.4318 -0.3302)
							(mid 0.402042 -0.402042)
							(end 0.3302 -0.4318)
						)
					)
					(width 0)
					(fill yes)
				)
			)
		)
	)
	(footprint ""
		(layer "F.Cu")
		(at 112.87379 -6.643878 -90)
		(property "Reference" "R460"
			(at 0 0 270)
			(layer "F.SilkS")
			(hide yes)
			(effects
				(font
					(size 1.27 1.27)
				)
			)
		)
		(property "Value" "0R2J-2-GP"
			(at 0.064008 -3.993896 270)
			(unlocked yes)
			(layer "F.Fab")
			(hide yes)
			(effects
				(font
					(size 1.016 1.016)
					(thickness 0.1524)
				)
			)
		)
		(property "Device Type" "R402H16"
			(at 0.064008 -5.517896 270)
			(unlocked yes)
			(layer "F.Fab")
			(hide yes)
			(effects
				(font
					(size 1.016 1.016)
					(thickness 0.1524)
				)
			)
		)
		(duplicate_pad_numbers_are_jumpers no)
		(fp_line
			(start -0.508 -0.9398)
			(end -0.508 0.9398)
			(stroke
				(width 0.1524)
				(type default)
			)
			(layer "F.SilkS")
		)
		(fp_line
			(start 0.508 -0.9398)
			(end -0.508 -0.9398)
			(stroke
				(width 0.1524)
				(type default)
			)
			(layer "F.SilkS")
		)
		(fp_rect
			(start -0.508 0.9398)
			(end 0.508 -0.9398)
			(stroke
				(width 0)
				(type default)
			)
			(fill no)
			(layer "F.CrtYd")
		)
		(fp_rect
			(start -0.508 0.9398)
			(end 0.508 -0.9398)
			(stroke
				(width 0)
				(type default)
			)
			(fill no)
			(layer "F.Fab")
		)
		(pad "1" smd custom
			(at 0 -0.4445 270)
			(size 0.1397 0.1397)
			(layers "F.Cu" "F.Mask" "F.Paste")
			(net "MB0_CM_ADR2_R")
			(options
				(clearance outline)
				(anchor circle)
			)
			(primitives
				(gr_poly
					(pts
						(arc
							(start -0.1778 -0.2794)
							(mid -0.249642 -0.249642)
							(end -0.2794 -0.1778)
						)
						(arc
							(start -0.2794 0.1778)
							(mid -0.249642 0.249642)
							(end -0.1778 0.2794)
						)
						(arc
							(start 0.1778 0.2794)
							(mid 0.249642 0.249642)
							(end 0.2794 0.1778)
						)
						(arc
							(start 0.2794 -0.1778)
							(mid 0.249642 -0.249642)
							(end 0.1778 -0.2794)
						)
					)
					(width 0)
					(fill yes)
				)
			)
		)
		(pad "2" smd custom
			(at 0 0.4445 270)
			(size 0.1397 0.1397)
			(layers "F.Cu" "F.Mask" "F.Paste")
			(net "AGND_CURRENT_MON")
			(options
				(clearance outline)
				(anchor circle)
			)
			(primitives
				(gr_poly
					(pts
						(arc
							(start -0.1778 -0.2794)
							(mid -0.249642 -0.249642)
							(end -0.2794 -0.1778)
						)
						(arc
							(start -0.2794 0.1778)
							(mid -0.249642 0.249642)
							(end -0.1778 0.2794)
						)
						(arc
							(start 0.1778 0.2794)
							(mid 0.249642 0.249642)
							(end 0.2794 0.1778)
						)
						(arc
							(start 0.2794 -0.1778)
							(mid 0.249642 -0.249642)
							(end 0.1778 -0.2794)
						)
					)
					(width 0)
					(fill yes)
				)
			)
		)
	)
	(footprint ""
		(layer "F.Cu")
		(at 83.029044 -132.72135 90)
		(property "Reference" "C485"
			(at 0 0 90)
			(layer "F.SilkS")
			(hide yes)
			(effects
				(font
					(size 1.27 1.27)
				)
			)
		)
		(property "Value" "SCD1U16V2KX-3GP"
			(at 1.1811 -2.7051 90)
			(unlocked yes)
			(layer "F.Fab")
			(hide yes)
			(effects
				(font
					(size 1.016 1.016)
					(thickness 0.1524)
				)
			)
		)
		(property "Device Type" "C402H22"
			(at 1.1811 -4.2291 90)
			(unlocked yes)
			(layer "F.Fab")
			(hide yes)
			(effects
				(font
					(size 1.016 1.016)
					(thickness 0.1524)
				)
			)
		)
		(duplicate_pad_numbers_are_jumpers no)
		(fp_rect
			(start -0.4318 0.9525)
			(end 0.4318 -0.9525)
			(stroke
				(width 0)
				(type default)
			)
			(fill no)
			(layer "F.CrtYd")
		)
		(fp_rect
			(start -0.4318 0.9525)
			(end 0.4318 -0.9525)
			(stroke
				(width 0)
				(type default)
			)
			(fill no)
			(layer "F.Fab")
		)
		(pad "1" smd custom
			(at 0 -0.4445 90)
			(size 0.1524 0.1524)
			(layers "F.Cu" "F.Mask" "F.Paste")
			(net "P3V3_STBY")
			(options
				(clearance outline)
				(anchor circle)
			)
			(primitives
				(gr_poly
					(pts
						(arc
							(start 0.3048 -0.2032)
							(mid 0.275042 -0.275042)
							(end 0.2032 -0.3048)
						)
						(arc
							(start -0.2032 -0.3048)
							(mid -0.275042 -0.275042)
							(end -0.3048 -0.2032)
						)
						(arc
							(start -0.3048 0.2032)
							(mid -0.275042 0.275042)
							(end -0.2032 0.3048)
						)
						(arc
							(start 0.2032 0.3048)
							(mid 0.275042 0.275042)
							(end 0.3048 0.2032)
						)
					)
					(width 0)
					(fill yes)
				)
			)
		)
		(pad "2" smd custom
			(at 0 0.4445 90)
			(size 0.1524 0.1524)
			(layers "F.Cu" "F.Mask" "F.Paste")
			(net "GND")
			(options
				(clearance outline)
				(anchor circle)
			)
			(primitives
				(gr_poly
					(pts
						(arc
							(start 0.3048 -0.2032)
							(mid 0.275042 -0.275042)
							(end 0.2032 -0.3048)
						)
						(arc
							(start -0.2032 -0.3048)
							(mid -0.275042 -0.275042)
							(end -0.3048 -0.2032)
						)
						(arc
							(start -0.3048 0.2032)
							(mid -0.275042 0.275042)
							(end -0.2032 0.3048)
						)
						(arc
							(start 0.2032 0.3048)
							(mid 0.275042 0.275042)
							(end 0.3048 0.2032)
						)
					)
					(width 0)
					(fill yes)
				)
			)
		)
	)
	(footprint ""
		(layer "F.Cu")
		(at 186.443112 -45.884084 180)
		(property "Reference" "R660"
			(at 0 0 180)
			(layer "F.SilkS")
			(hide yes)
			(effects
				(font
					(size 1.27 1.27)
				)
			)
		)
		(property "Value" "10KR2F-2-GP"
			(at 0.064008 -3.993896 180)
			(unlocked yes)
			(layer "F.Fab")
			(hide yes)
			(effects
				(font
					(size 1.016 1.016)
					(thickness 0.1524)
				)
			)
		)
		(property "Device Type" "R402H16"
			(at 0.064008 -5.517896 180)
			(unlocked yes)
			(layer "F.Fab")
			(hide yes)
			(effects
				(font
					(size 1.016 1.016)
					(thickness 0.1524)
				)
			)
		)
		(duplicate_pad_numbers_are_jumpers no)
		(fp_line
			(start 0.508 -0.9398)
			(end -0.508 -0.9398)
			(stroke
				(width 0.1524)
				(type default)
			)
			(layer "F.SilkS")
		)
		(fp_line
			(start -0.508 -0.9398)
			(end -0.508 0.9398)
			(stroke
				(width 0.1524)
				(type default)
			)
			(layer "F.SilkS")
		)
		(fp_rect
			(start -0.508 0.9398)
			(end 0.508 -0.9398)
			(stroke
				(width 0)
				(type default)
			)
			(fill no)
			(layer "F.CrtYd")
		)
		(fp_rect
			(start -0.508 0.9398)
			(end 0.508 -0.9398)
			(stroke
				(width 0)
				(type default)
			)
			(fill no)
			(layer "F.Fab")
		)
		(pad "1" smd custom
			(at 0 -0.4445 180)
			(size 0.1397 0.1397)
			(layers "F.Cu" "F.Mask" "F.Paste")
			(net "P1V8")
			(options
				(clearance outline)
				(anchor circle)
			)
			(primitives
				(gr_poly
					(pts
						(arc
							(start -0.1778 -0.2794)
							(mid -0.249642 -0.249642)
							(end -0.2794 -0.1778)
						)
						(arc
							(start -0.2794 0.1778)
							(mid -0.249642 0.249642)
							(end -0.1778 0.2794)
						)
						(arc
							(start 0.1778 0.2794)
							(mid 0.249642 0.249642)
							(end 0.2794 0.1778)
						)
						(arc
							(start 0.2794 -0.1778)
							(mid 0.249642 -0.249642)
							(end 0.1778 -0.2794)
						)
					)
					(width 0)
					(fill yes)
				)
			)
		)
		(pad "2" smd custom
			(at 0 0.4445 180)
			(size 0.1397 0.1397)
			(layers "F.Cu" "F.Mask" "F.Paste")
			(net "XM_ADDR_0")
			(options
				(clearance outline)
				(anchor circle)
			)
			(primitives
				(gr_poly
					(pts
						(arc
							(start -0.1778 -0.2794)
							(mid -0.249642 -0.249642)
							(end -0.2794 -0.1778)
						)
						(arc
							(start -0.2794 0.1778)
							(mid -0.249642 0.249642)
							(end -0.1778 0.2794)
						)
						(arc
							(start 0.1778 0.2794)
							(mid 0.249642 0.249642)
							(end 0.2794 0.1778)
						)
						(arc
							(start 0.2794 -0.1778)
							(mid 0.249642 -0.249642)
							(end 0.1778 -0.2794)
						)
					)
					(width 0)
					(fill yes)
				)
			)
		)
	)
	(footprint ""
		(layer "F.Cu")
		(at 39.712646 -174.67961 -90)
		(property "Reference" "R489"
			(at 0 0 270)
			(layer "F.SilkS")
			(hide yes)
			(effects
				(font
					(size 1.27 1.27)
				)
			)
		)
		(property "Value" "10R3F-GP"
			(at -0.0254 -2.5146 270)
			(unlocked yes)
			(layer "F.Fab")
			(hide yes)
			(effects
				(font
					(size 1.016 1.016)
					(thickness 0.1524)
				)
			)
		)
		(property "Device Type" "R603H22"
			(at -0.0254 -4.0386 270)
			(unlocked yes)
			(layer "F.Fab")
			(hide yes)
			(effects
				(font
					(size 1.016 1.016)
					(thickness 0.1524)
				)
			)
		)
		(duplicate_pad_numbers_are_jumpers no)
		(fp_line
			(start -0.4826 0)
			(end -0.2032 0)
			(stroke
				(width 0.2032)
				(type default)
			)
			(layer "F.SilkS")
		)
		(fp_line
			(start 0.2032 0)
			(end 0.4826 0)
			(stroke
				(width 0.2032)
				(type default)
			)
			(layer "F.SilkS")
		)
		(fp_rect
			(start -0.5842 1.3335)
			(end 0.5842 -1.3335)
			(stroke
				(width 0)
				(type default)
			)
			(fill no)
			(layer "F.CrtYd")
		)
		(fp_rect
			(start -0.5842 1.3335)
			(end 0.5842 -1.3335)
			(stroke
				(width 0)
				(type default)
			)
			(fill no)
			(layer "F.Fab")
		)
		(pad "1" smd custom
			(at 0 -0.762 270)
			(size 0.2159 0.2159)
			(layers "F.Cu" "F.Mask" "F.Paste")
			(net "P3V3_STBY_OUT")
			(options
				(clearance outline)
				(anchor circle)
			)
			(primitives
				(gr_poly
					(pts
						(arc
							(start -0.3302 -0.4318)
							(mid -0.402042 -0.402042)
							(end -0.4318 -0.3302)
						)
						(arc
							(start -0.4318 0.3302)
							(mid -0.402042 0.402042)
							(end -0.3302 0.4318)
						)
						(arc
							(start 0.3302 0.4318)
							(mid 0.402042 0.402042)
							(end 0.4318 0.3302)
						)
						(arc
							(start 0.4318 -0.3302)
							(mid 0.402042 -0.402042)
							(end 0.3302 -0.4318)
						)
					)
					(width 0)
					(fill yes)
				)
			)
		)
		(pad "2" smd custom
			(at 0 0.762 270)
			(size 0.2159 0.2159)
			(layers "F.Cu" "F.Mask" "F.Paste")
			(net "P3V3_STBY_VFB_R")
			(options
				(clearance outline)
				(anchor circle)
			)
			(primitives
				(gr_poly
					(pts
						(arc
							(start -0.3302 -0.4318)
							(mid -0.402042 -0.402042)
							(end -0.4318 -0.3302)
						)
						(arc
							(start -0.4318 0.3302)
							(mid -0.402042 0.402042)
							(end -0.3302 0.4318)
						)
						(arc
							(start 0.3302 0.4318)
							(mid 0.402042 0.402042)
							(end 0.4318 0.3302)
						)
						(arc
							(start 0.4318 -0.3302)
							(mid 0.402042 -0.402042)
							(end 0.3302 -0.4318)
						)
					)
					(width 0)
					(fill yes)
				)
			)
		)
	)
	(footprint ""
		(layer "F.Cu")
		(at 211.6836 -111.5568 180)
		(property "Reference" "C324"
			(at 0 0 180)
			(layer "F.SilkS")
			(hide yes)
			(effects
				(font
					(size 1.27 1.27)
				)
			)
		)
		(property "Value" "SE470UF2VDM-GP"
			(at 0 -9.6012 180)
			(unlocked yes)
			(layer "F.Fab")
			(hide yes)
			(effects
				(font
					(size 1.016 1.016)
					(thickness 0.1524)
				)
			)
		)
		(property "Device Type" "CT7343H83"
			(at 0 -11.1252 180)
			(unlocked yes)
			(layer "F.Fab")
			(hide yes)
			(effects
				(font
					(size 1.016 1.016)
					(thickness 0.1524)
				)
			)
		)
		(duplicate_pad_numbers_are_jumpers no)
		(fp_line
			(start 2.286 4.8768)
			(end -2.286 4.8768)
			(stroke
				(width 0.1524)
				(type default)
			)
			(layer "F.SilkS")
		)
		(fp_line
			(start 2.286 2.032)
			(end 2.286 4.8768)
			(stroke
				(width 0.1524)
				(type default)
			)
			(layer "F.SilkS")
		)
		(fp_line
			(start 2.286 -2.032)
			(end 2.286 -4.8768)
			(stroke
				(width 0.1524)
				(type default)
			)
			(layer "F.SilkS")
		)
		(fp_line
			(start 2.286 -4.8768)
			(end -2.286 -4.8768)
			(stroke
				(width 0.1524)
				(type default)
			)
			(layer "F.SilkS")
		)
		(fp_line
			(start 2.1082 -4.699)
			(end -2.1082 -4.699)
			(stroke
				(width 0.508)
				(type default)
			)
			(layer "F.SilkS")
		)
		(fp_line
			(start -2.286 4.8768)
			(end -2.286 2.032)
			(stroke
				(width 0.1524)
				(type default)
			)
			(layer "F.SilkS")
		)
		(fp_line
			(start -2.286 -4.8768)
			(end -2.286 -2.032)
			(stroke
				(width 0.1524)
				(type default)
			)
			(layer "F.SilkS")
		)
		(fp_rect
			(start -2.1463 3.6449)
			(end 2.1463 -3.6449)
			(stroke
				(width 0)
				(type default)
			)
			(fill no)
			(layer "F.CrtYd")
		)
		(fp_poly
			(pts
				(xy -2.54 4.953) (xy -2.54 4.2926) (xy -3.81 4.2926) (xy -3.81 -4.2926) (xy -2.54 -4.2926) (xy -2.54 -4.953)
				(xy 2.54 -4.953) (xy 2.54 -4.2926) (xy 3.81 -4.2926) (xy 3.81 -1.6256) (xy 2.1463 -1.6256) (xy 2.1463 -3.6449)
				(xy -2.1463 -3.6449) (xy -2.1463 3.6449) (xy 2.1463 3.6449) (xy 2.1463 -1.6129) (xy 3.81 -1.6129)
				(xy 3.81 4.2926) (xy 2.54 4.2926) (xy 2.54 4.953)
			)
			(stroke
				(width 0)
				(type default)
			)
			(fill no)
			(layer "F.CrtYd")
		)
		(fp_rect
			(start 2.54 4.2926)
			(end 3.81 -4.2926)
			(stroke
				(width 0)
				(type default)
			)
			(fill no)
			(layer "F.Fab")
		)
		(fp_rect
			(start -2.54 4.953)
			(end 2.54 -4.953)
			(stroke
				(width 0)
				(type default)
			)
			(fill no)
			(layer "F.Fab")
		)
		(fp_rect
			(start -3.81 4.2926)
			(end -2.54 -4.2926)
			(stroke
				(width 0)
				(type default)
			)
			(fill no)
			(layer "F.Fab")
		)
		(pad "1" smd rect
			(at 0 -3.1496 180)
			(size 2.413 2.286)
			(layers "F.Cu" "F.Mask" "F.Paste")
			(net "P0V975")
		)
		(pad "2" smd rect
			(at 0 3.1496 180)
			(size 2.413 2.286)
			(layers "F.Cu" "F.Mask" "F.Paste")
			(net "GND")
		)
		(zone
			(layer "F.Cu")
			(hatch none 0.5)
			(connect_pads
				(clearance 0)
			)
			(min_thickness 0.25)
			(keepout
				(tracks allowed)
				(vias not_allowed)
				(pads allowed)
				(copperpour not_allowed)
				(footprints allowed)
			)
			(placement
				(enabled no)
				(sheetname "")
			)
			(fill
				(thermal_gap 0.5)
				(thermal_bridge_width 0.5)
				(island_removal_mode 0)
			)
			(polygon
				(pts
					(xy 210.1723 -109.8677) (xy 210.1723 -106.9594) (xy 213.1949 -106.9594) (xy 213.1949 -109.855)
					(xy 213.1949 -110.1852) (xy 210.1723 -110.1852)
				)
			)
		)
		(zone
			(layer "F.Cu")
			(hatch none 0.5)
			(connect_pads
				(clearance 0)
			)
			(min_thickness 0.25)
			(keepout
				(tracks allowed)
				(vias not_allowed)
				(pads allowed)
				(copperpour not_allowed)
				(footprints allowed)
			)
			(placement
				(enabled no)
				(sheetname "")
			)
			(fill
				(thermal_gap 0.5)
				(thermal_bridge_width 0.5)
				(island_removal_mode 0)
			)
			(polygon
				(pts
					(xy 213.1949 -116.1542) (xy 210.1723 -116.1542) (xy 210.1723 -113.2586) (xy 210.1723 -112.9284)
					(xy 213.1949 -112.9284) (xy 213.1949 -113.2586)
				)
			)
		)
	)
	(footprint ""
		(layer "F.Cu")
		(at 70.744842 -186.28487 180)
		(property "Reference" "C197"
			(at 0 0 180)
			(layer "F.SilkS")
			(hide yes)
			(effects
				(font
					(size 1.27 1.27)
				)
			)
		)
		(property "Value" "SC1U16V3KX-5GP"
			(at 0 -2.8194 180)
			(unlocked yes)
			(layer "F.Fab")
			(hide yes)
			(effects
				(font
					(size 1.016 1.016)
					(thickness 0.1524)
				)
			)
		)
		(property "Device Type" "C603H36"
			(at 0 -4.3434 180)
			(unlocked yes)
			(layer "F.Fab")
			(hide yes)
			(effects
				(font
					(size 1.016 1.016)
					(thickness 0.1524)
				)
			)
		)
		(duplicate_pad_numbers_are_jumpers no)
		(fp_line
			(start 0.508 0)
			(end -0.508 0)
			(stroke
				(width 0.2032)
				(type default)
			)
			(layer "F.SilkS")
		)
		(fp_rect
			(start -0.5842 1.3335)
			(end 0.5842 -1.3335)
			(stroke
				(width 0)
				(type default)
			)
			(fill no)
			(layer "F.CrtYd")
		)
		(fp_rect
			(start -0.5842 1.3335)
			(end 0.5842 -1.3335)
			(stroke
				(width 0)
				(type default)
			)
			(fill no)
			(layer "F.Fab")
		)
		(pad "1" smd custom
			(at 0 -0.762 180)
			(size 0.2159 0.2159)
			(layers "F.Cu" "F.Mask" "F.Paste")
			(net "TPS74801_P2V5_STBY_BIAS")
			(options
				(clearance outline)
				(anchor circle)
			)
			(primitives
				(gr_poly
					(pts
						(arc
							(start -0.3302 -0.4318)
							(mid -0.402042 -0.402042)
							(end -0.4318 -0.3302)
						)
						(arc
							(start -0.4318 0.3302)
							(mid -0.402042 0.402042)
							(end -0.3302 0.4318)
						)
						(arc
							(start 0.3302 0.4318)
							(mid 0.402042 0.402042)
							(end 0.4318 0.3302)
						)
						(arc
							(start 0.4318 -0.3302)
							(mid 0.402042 -0.402042)
							(end 0.3302 -0.4318)
						)
					)
					(width 0)
					(fill yes)
				)
			)
		)
		(pad "2" smd custom
			(at 0 0.762 180)
			(size 0.2159 0.2159)
			(layers "F.Cu" "F.Mask" "F.Paste")
			(net "GND")
			(options
				(clearance outline)
				(anchor circle)
			)
			(primitives
				(gr_poly
					(pts
						(arc
							(start -0.3302 -0.4318)
							(mid -0.402042 -0.402042)
							(end -0.4318 -0.3302)
						)
						(arc
							(start -0.4318 0.3302)
							(mid -0.402042 0.402042)
							(end -0.3302 0.4318)
						)
						(arc
							(start 0.3302 0.4318)
							(mid 0.402042 0.402042)
							(end 0.4318 0.3302)
						)
						(arc
							(start 0.4318 -0.3302)
							(mid 0.402042 -0.402042)
							(end 0.3302 -0.4318)
						)
					)
					(width 0)
					(fill yes)
				)
			)
		)
	)
	(footprint ""
		(layer "F.Cu")
		(at 35.235896 -136.73709 90)
		(property "Reference" "R351"
			(at 0 0 90)
			(layer "F.SilkS")
			(hide yes)
			(effects
				(font
					(size 1.27 1.27)
				)
			)
		)
		(property "Value" "10KR2F-2-GP"
			(at 0.064008 -3.993896 90)
			(unlocked yes)
			(layer "F.Fab")
			(hide yes)
			(effects
				(font
					(size 1.016 1.016)
					(thickness 0.1524)
				)
			)
		)
		(property "Device Type" "R402H16"
			(at 0.064008 -5.517896 90)
			(unlocked yes)
			(layer "F.Fab")
			(hide yes)
			(effects
				(font
					(size 1.016 1.016)
					(thickness 0.1524)
				)
			)
		)
		(duplicate_pad_numbers_are_jumpers no)
		(fp_line
			(start 0.508 -0.9398)
			(end -0.508 -0.9398)
			(stroke
				(width 0.1524)
				(type default)
			)
			(layer "F.SilkS")
		)
		(fp_line
			(start -0.508 -0.9398)
			(end -0.508 0.9398)
			(stroke
				(width 0.1524)
				(type default)
			)
			(layer "F.SilkS")
		)
		(fp_rect
			(start -0.508 0.9398)
			(end 0.508 -0.9398)
			(stroke
				(width 0)
				(type default)
			)
			(fill no)
			(layer "F.CrtYd")
		)
		(fp_rect
			(start -0.508 0.9398)
			(end 0.508 -0.9398)
			(stroke
				(width 0)
				(type default)
			)
			(fill no)
			(layer "F.Fab")
		)
		(pad "1" smd custom
			(at 0 -0.4445 90)
			(size 0.1397 0.1397)
			(layers "F.Cu" "F.Mask" "F.Paste")
			(net "GND")
			(options
				(clearance outline)
				(anchor circle)
			)
			(primitives
				(gr_poly
					(pts
						(arc
							(start -0.1778 -0.2794)
							(mid -0.249642 -0.249642)
							(end -0.2794 -0.1778)
						)
						(arc
							(start -0.2794 0.1778)
							(mid -0.249642 0.249642)
							(end -0.1778 0.2794)
						)
						(arc
							(start 0.1778 0.2794)
							(mid 0.249642 0.249642)
							(end 0.2794 0.1778)
						)
						(arc
							(start 0.2794 -0.1778)
							(mid 0.249642 -0.249642)
							(end 0.1778 -0.2794)
						)
					)
					(width 0)
					(fill yes)
				)
			)
		)
		(pad "2" smd custom
			(at 0 0.4445 90)
			(size 0.1397 0.1397)
			(layers "F.Cu" "F.Mask" "F.Paste")
			(net "PECI")
			(options
				(clearance outline)
				(anchor circle)
			)
			(primitives
				(gr_poly
					(pts
						(arc
							(start -0.1778 -0.2794)
							(mid -0.249642 -0.249642)
							(end -0.2794 -0.1778)
						)
						(arc
							(start -0.2794 0.1778)
							(mid -0.249642 0.249642)
							(end -0.1778 0.2794)
						)
						(arc
							(start 0.1778 0.2794)
							(mid 0.249642 0.249642)
							(end 0.2794 0.1778)
						)
						(arc
							(start 0.2794 -0.1778)
							(mid 0.249642 -0.249642)
							(end 0.1778 -0.2794)
						)
					)
					(width 0)
					(fill yes)
				)
			)
		)
	)
	(footprint ""
		(layer "F.Cu")
		(at 156.723842 -95.03791 180)
		(property "Reference" "C484"
			(at 0 0 180)
			(layer "F.SilkS")
			(hide yes)
			(effects
				(font
					(size 1.27 1.27)
				)
			)
		)
		(property "Value" "SCD1U16V2KX-3GP"
			(at 1.1811 -2.7051 180)
			(unlocked yes)
			(layer "F.Fab")
			(hide yes)
			(effects
				(font
					(size 1.016 1.016)
					(thickness 0.1524)
				)
			)
		)
		(property "Device Type" "C402H22"
			(at 1.1811 -4.2291 180)
			(unlocked yes)
			(layer "F.Fab")
			(hide yes)
			(effects
				(font
					(size 1.016 1.016)
					(thickness 0.1524)
				)
			)
		)
		(duplicate_pad_numbers_are_jumpers no)
		(fp_rect
			(start -0.4318 0.9525)
			(end 0.4318 -0.9525)
			(stroke
				(width 0)
				(type default)
			)
			(fill no)
			(layer "F.CrtYd")
		)
		(fp_rect
			(start -0.4318 0.9525)
			(end 0.4318 -0.9525)
			(stroke
				(width 0)
				(type default)
			)
			(fill no)
			(layer "F.Fab")
		)
		(pad "1" smd custom
			(at 0 -0.4445 180)
			(size 0.1524 0.1524)
			(layers "F.Cu" "F.Mask" "F.Paste")
			(net "P3V3")
			(options
				(clearance outline)
				(anchor circle)
			)
			(primitives
				(gr_poly
					(pts
						(arc
							(start 0.3048 -0.2032)
							(mid 0.275042 -0.275042)
							(end 0.2032 -0.3048)
						)
						(arc
							(start -0.2032 -0.3048)
							(mid -0.275042 -0.275042)
							(end -0.3048 -0.2032)
						)
						(arc
							(start -0.3048 0.2032)
							(mid -0.275042 0.275042)
							(end -0.2032 0.3048)
						)
						(arc
							(start 0.2032 0.3048)
							(mid 0.275042 0.275042)
							(end 0.3048 0.2032)
						)
					)
					(width 0)
					(fill yes)
				)
			)
		)
		(pad "2" smd custom
			(at 0 0.4445 180)
			(size 0.1524 0.1524)
			(layers "F.Cu" "F.Mask" "F.Paste")
			(net "GND")
			(options
				(clearance outline)
				(anchor circle)
			)
			(primitives
				(gr_poly
					(pts
						(arc
							(start 0.3048 -0.2032)
							(mid 0.275042 -0.275042)
							(end 0.2032 -0.3048)
						)
						(arc
							(start -0.2032 -0.3048)
							(mid -0.275042 -0.275042)
							(end -0.3048 -0.2032)
						)
						(arc
							(start -0.3048 0.2032)
							(mid -0.275042 0.275042)
							(end -0.2032 0.3048)
						)
						(arc
							(start 0.2032 0.3048)
							(mid 0.275042 0.275042)
							(end 0.3048 0.2032)
						)
					)
					(width 0)
					(fill yes)
				)
			)
		)
	)
	(footprint ""
		(layer "F.Cu")
		(at 79.172816 -181.33568)
		(property "Reference" "C198"
			(at 0 0 0)
			(layer "F.SilkS")
			(hide yes)
			(effects
				(font
					(size 1.27 1.27)
				)
			)
		)
		(property "Value" "SCD1U16V2KX-3GP"
			(at 1.1811 -2.7051 0)
			(unlocked yes)
			(layer "F.Fab")
			(hide yes)
			(effects
				(font
					(size 1.016 1.016)
					(thickness 0.1524)
				)
			)
		)
		(property "Device Type" "C402H22"
			(at 1.1811 -4.2291 0)
			(unlocked yes)
			(layer "F.Fab")
			(hide yes)
			(effects
				(font
					(size 1.016 1.016)
					(thickness 0.1524)
				)
			)
		)
		(duplicate_pad_numbers_are_jumpers no)
		(fp_rect
			(start -0.4318 0.9525)
			(end 0.4318 -0.9525)
			(stroke
				(width 0)
				(type default)
			)
			(fill no)
			(layer "F.CrtYd")
		)
		(fp_rect
			(start -0.4318 0.9525)
			(end 0.4318 -0.9525)
			(stroke
				(width 0)
				(type default)
			)
			(fill no)
			(layer "F.Fab")
		)
		(pad "1" smd custom
			(at 0 -0.4445)
			(size 0.1524 0.1524)
			(layers "F.Cu" "F.Mask" "F.Paste")
			(net "P3V3_STBY")
			(options
				(clearance outline)
				(anchor circle)
			)
			(primitives
				(gr_poly
					(pts
						(arc
							(start 0.3048 -0.2032)
							(mid 0.275042 -0.275042)
							(end 0.2032 -0.3048)
						)
						(arc
							(start -0.2032 -0.3048)
							(mid -0.275042 -0.275042)
							(end -0.3048 -0.2032)
						)
						(arc
							(start -0.3048 0.2032)
							(mid -0.275042 0.275042)
							(end -0.2032 0.3048)
						)
						(arc
							(start 0.2032 0.3048)
							(mid 0.275042 0.275042)
							(end 0.3048 0.2032)
						)
					)
					(width 0)
					(fill yes)
				)
			)
		)
		(pad "2" smd custom
			(at 0 0.4445)
			(size 0.1524 0.1524)
			(layers "F.Cu" "F.Mask" "F.Paste")
			(net "GND")
			(options
				(clearance outline)
				(anchor circle)
			)
			(primitives
				(gr_poly
					(pts
						(arc
							(start 0.3048 -0.2032)
							(mid 0.275042 -0.275042)
							(end 0.2032 -0.3048)
						)
						(arc
							(start -0.2032 -0.3048)
							(mid -0.275042 -0.275042)
							(end -0.3048 -0.2032)
						)
						(arc
							(start -0.3048 0.2032)
							(mid -0.275042 0.275042)
							(end -0.2032 0.3048)
						)
						(arc
							(start 0.2032 0.3048)
							(mid 0.275042 0.275042)
							(end 0.3048 0.2032)
						)
					)
					(width 0)
					(fill yes)
				)
			)
		)
	)
	(footprint ""
		(layer "F.Cu")
		(at 91.818968 -59.111896 90)
		(property "Reference" "D4"
			(at 0 0 90)
			(layer "F.SilkS")
			(hide yes)
			(effects
				(font
					(size 1.27 1.27)
				)
			)
		)
		(property "Value" "SMF15A-GP"
			(at -2.0955 1.2192 90)
			(unlocked yes)
			(layer "F.Fab")
			(hide yes)
			(effects
				(font
					(size 1.016 1.016)
					(thickness 0.1524)
				)
			)
		)
		(property "Device Type" "SOD123AK-2H43"
			(at -2.0955 -0.3048 90)
			(unlocked yes)
			(layer "F.Fab")
			(hide yes)
			(effects
				(font
					(size 1.016 1.016)
					(thickness 0.1524)
				)
			)
		)
		(duplicate_pad_numbers_are_jumpers no)
		(fp_line
			(start 1.1557 -2.7686)
			(end -1.1557 -2.7686)
			(stroke
				(width 0.1524)
				(type default)
			)
			(layer "F.SilkS")
		)
		(fp_line
			(start -1.1557 -2.7686)
			(end -1.1557 2.7686)
			(stroke
				(width 0.1524)
				(type default)
			)
			(layer "F.SilkS")
		)
		(fp_line
			(start 1.1557 2.7686)
			(end 1.1557 -2.7686)
			(stroke
				(width 0.1524)
				(type default)
			)
			(layer "F.SilkS")
		)
		(fp_line
			(start -1.1557 2.7686)
			(end 1.1557 2.7686)
			(stroke
				(width 0.1524)
				(type default)
			)
			(layer "F.SilkS")
		)
		(fp_line
			(start 1.1557 2.921)
			(end -1.1557 2.921)
			(stroke
				(width 0.508)
				(type default)
			)
			(layer "F.SilkS")
		)
		(fp_poly
			(pts
				(xy -0.4572 1.8669) (xy -0.4572 1.397) (xy -0.9017 1.397) (xy -0.9017 -1.397) (xy -0.4572 -1.397)
				(xy -0.4572 -1.8669) (xy 0.4572 -1.8669) (xy 0.4572 -1.397) (xy 0.9017 -1.397) (xy 0.9017 1.397)
				(xy 0.4572 1.397) (xy 0.4572 1.8669)
			)
			(stroke
				(width 0)
				(type default)
			)
			(fill no)
			(layer "F.CrtYd")
		)
		(fp_poly
			(pts
				(xy -1.4097 2.8448) (xy -1.4097 -2.8448) (xy 1.4097 -2.8448) (xy 1.4097 1.3716) (xy 0.9017 1.3716)
				(xy 0.9017 -1.397) (xy 0.4572 -1.397) (xy 0.4572 -1.8669) (xy -0.4572 -1.8669) (xy -0.4572 -1.397)
				(xy -0.9017 -1.397) (xy -0.9017 1.397) (xy -0.4572 1.397) (xy -0.4572 1.8669) (xy 0.4572 1.8669)
				(xy 0.4572 1.397) (xy 0.9017 1.397) (xy 0.9017 1.3843) (xy 1.4097 1.3843) (xy 1.4097 2.8448)
			)
			(stroke
				(width 0)
				(type default)
			)
			(fill no)
			(layer "F.CrtYd")
		)
		(fp_rect
			(start -1.4097 2.8448)
			(end 1.4097 -2.8448)
			(stroke
				(width 0)
				(type default)
			)
			(fill no)
			(layer "F.Fab")
		)
		(pad "A" smd rect
			(at 0 -1.75768 90)
			(size 1.143 1.4986)
			(layers "F.Cu" "F.Mask" "F.Paste")
			(net "P3V3_EN_R")
		)
		(pad "K" smd rect
			(at 0 1.75768 90)
			(size 1.143 1.4986)
			(layers "F.Cu" "F.Mask" "F.Paste")
			(net "P3V3_EN")
		)
	)
	(footprint ""
		(layer "F.Cu")
		(at 61.8236 -162.8648 180)
		(property "Reference" "R72"
			(at 0 0 180)
			(layer "F.SilkS")
			(hide yes)
			(effects
				(font
					(size 1.27 1.27)
				)
			)
		)
		(property "Value" "10KR2F-2-GP"
			(at 0.064008 -3.993896 180)
			(unlocked yes)
			(layer "F.Fab")
			(hide yes)
			(effects
				(font
					(size 1.016 1.016)
					(thickness 0.1524)
				)
			)
		)
		(property "Device Type" "R402H16"
			(at 0.064008 -5.517896 180)
			(unlocked yes)
			(layer "F.Fab")
			(hide yes)
			(effects
				(font
					(size 1.016 1.016)
					(thickness 0.1524)
				)
			)
		)
		(duplicate_pad_numbers_are_jumpers no)
		(fp_line
			(start 0.508 -0.9398)
			(end -0.508 -0.9398)
			(stroke
				(width 0.1524)
				(type default)
			)
			(layer "F.SilkS")
		)
		(fp_line
			(start -0.508 -0.9398)
			(end -0.508 0.9398)
			(stroke
				(width 0.1524)
				(type default)
			)
			(layer "F.SilkS")
		)
		(fp_rect
			(start -0.508 0.9398)
			(end 0.508 -0.9398)
			(stroke
				(width 0)
				(type default)
			)
			(fill no)
			(layer "F.CrtYd")
		)
		(fp_rect
			(start -0.508 0.9398)
			(end 0.508 -0.9398)
			(stroke
				(width 0)
				(type default)
			)
			(fill no)
			(layer "F.Fab")
		)
		(pad "1" smd custom
			(at 0 -0.4445 180)
			(size 0.1397 0.1397)
			(layers "F.Cu" "F.Mask" "F.Paste")
			(net "P3V3_STBY")
			(options
				(clearance outline)
				(anchor circle)
			)
			(primitives
				(gr_poly
					(pts
						(arc
							(start -0.1778 -0.2794)
							(mid -0.249642 -0.249642)
							(end -0.2794 -0.1778)
						)
						(arc
							(start -0.2794 0.1778)
							(mid -0.249642 0.249642)
							(end -0.1778 0.2794)
						)
						(arc
							(start 0.1778 0.2794)
							(mid 0.249642 0.249642)
							(end 0.2794 0.1778)
						)
						(arc
							(start 0.2794 -0.1778)
							(mid 0.249642 -0.249642)
							(end 0.1778 -0.2794)
						)
					)
					(width 0)
					(fill yes)
				)
			)
		)
		(pad "2" smd custom
			(at 0 0.4445 180)
			(size 0.1397 0.1397)
			(layers "F.Cu" "F.Mask" "F.Paste")
			(net "FM_TPM_PRSNT_RST")
			(options
				(clearance outline)
				(anchor circle)
			)
			(primitives
				(gr_poly
					(pts
						(arc
							(start -0.1778 -0.2794)
							(mid -0.249642 -0.249642)
							(end -0.2794 -0.1778)
						)
						(arc
							(start -0.2794 0.1778)
							(mid -0.249642 0.249642)
							(end -0.1778 0.2794)
						)
						(arc
							(start 0.1778 0.2794)
							(mid 0.249642 0.249642)
							(end 0.2794 0.1778)
						)
						(arc
							(start 0.2794 -0.1778)
							(mid 0.249642 -0.249642)
							(end 0.1778 -0.2794)
						)
					)
					(width 0)
					(fill yes)
				)
			)
		)
	)
	(footprint ""
		(layer "F.Cu")
		(at 98.711258 -17.90446 90)
		(property "Reference" "L1"
			(at 0 0 90)
			(layer "F.SilkS")
			(hide yes)
			(effects
				(font
					(size 1.27 1.27)
				)
			)
		)
		(property "Value" "DLW21HN900SQ2LGP-U"
			(at -0.0889 -2.7813 90)
			(unlocked yes)
			(layer "F.Fab")
			(hide yes)
			(effects
				(font
					(size 1.016 1.016)
					(thickness 0.1524)
				)
			)
		)
		(property "Device Type" "L2012-4P-1MH40"
			(at -0.0889 -4.3053 90)
			(unlocked yes)
			(layer "F.Fab")
			(hide yes)
			(effects
				(font
					(size 1.016 1.016)
					(thickness 0.1524)
				)
			)
		)
		(duplicate_pad_numbers_are_jumpers no)
		(fp_line
			(start 1.5494 -1.0668)
			(end 1.5494 1.0668)
			(stroke
				(width 0.1524)
				(type default)
			)
			(layer "F.SilkS")
		)
		(fp_line
			(start -1.5494 -1.0668)
			(end 1.5494 -1.0668)
			(stroke
				(width 0.1524)
				(type default)
			)
			(layer "F.SilkS")
		)
		(fp_line
			(start 1.5494 1.0668)
			(end -1.5494 1.0668)
			(stroke
				(width 0.1524)
				(type default)
			)
			(layer "F.SilkS")
		)
		(fp_line
			(start -1.5494 1.0668)
			(end -1.5494 -1.0668)
			(stroke
				(width 0.1524)
				(type default)
			)
			(layer "F.SilkS")
		)
		(fp_line
			(start 1.0668 1.1811)
			(end 0.6858 1.1811)
			(stroke
				(width 0.3302)
				(type default)
			)
			(layer "F.SilkS")
		)
		(fp_poly
			(pts
				(xy 1.500124 1.768856) (xy 0.230124 1.768856) (xy 0.865124 1.133856)
			)
			(stroke
				(width 0)
				(type default)
			)
			(fill yes)
			(layer "F.SilkS")
		)
		(fp_rect
			(start -1.0033 0.5969)
			(end 1.0033 -0.5969)
			(stroke
				(width 0)
				(type default)
			)
			(fill no)
			(layer "F.CrtYd")
		)
		(fp_poly
			(pts
				(xy -1.8034 1.3208) (xy -1.8034 -1.3208) (xy 1.8034 -1.3208) (xy 1.8034 0.0508) (xy 1.0033 0.0508)
				(xy 1.0033 -0.5969) (xy -1.0033 -0.5969) (xy -1.0033 0.5969) (xy 1.0033 0.5969) (xy 1.0033 0.0762)
				(xy 1.8034 0.0762) (xy 1.8034 1.3208)
			)
			(stroke
				(width 0)
				(type default)
			)
			(fill no)
			(layer "F.CrtYd")
		)
		(fp_rect
			(start -1.8034 1.3208)
			(end 1.8034 -1.3208)
			(stroke
				(width 0)
				(type default)
			)
			(fill no)
			(layer "F.Fab")
		)
		(pad "1" smd rect
			(at 0.8382 0.4826 90)
			(size 0.9144 0.6604)
			(layers "F.Cu" "F.Mask" "F.Paste")
			(net "USB_P1_DP")
		)
		(pad "2" smd rect
			(at -0.8382 0.4826 90)
			(size 0.9144 0.6604)
			(layers "F.Cu" "F.Mask" "F.Paste")
			(net "USB_P1_F_DP1")
		)
		(pad "3" smd rect
			(at -0.8382 -0.4826 90)
			(size 0.9144 0.6604)
			(layers "F.Cu" "F.Mask" "F.Paste")
			(net "USB_P1_F_DN1")
		)
		(pad "4" smd rect
			(at 0.8382 -0.4826 90)
			(size 0.9144 0.6604)
			(layers "F.Cu" "F.Mask" "F.Paste")
			(net "USB_P1_DN")
		)
		(zone
			(layer "F.Cu")
			(hatch none 0.5)
			(connect_pads
				(clearance 0)
			)
			(min_thickness 0.25)
			(keepout
				(tracks allowed)
				(vias not_allowed)
				(pads allowed)
				(copperpour not_allowed)
				(footprints allowed)
			)
			(placement
				(enabled no)
				(sheetname "")
			)
			(fill
				(thermal_gap 0.5)
				(thermal_bridge_width 0.5)
				(island_removal_mode 0)
			)
			(polygon
				(pts
					(xy 99.524058 -17.52346) (xy 98.863658 -17.52346) (xy 98.863658 -16.60906) (xy 98.558858 -16.60906)
					(xy 98.558858 -17.52346) (xy 97.898458 -17.52346) (xy 97.898458 -18.28546) (xy 98.558858 -18.28546)
					(xy 98.558858 -19.19986) (xy 98.863658 -19.19986) (xy 98.863658 -18.28546) (xy 99.524058 -18.28546)
				)
			)
		)
		(zone
			(layer "F.Cu")
			(hatch none 0.5)
			(connect_pads
				(clearance 0)
			)
			(min_thickness 0.25)
			(keepout
				(tracks not_allowed)
				(vias allowed)
				(pads allowed)
				(copperpour not_allowed)
				(footprints allowed)
			)
			(placement
				(enabled no)
				(sheetname "")
			)
			(fill
				(thermal_gap 0.5)
				(thermal_bridge_width 0.5)
				(island_removal_mode 0)
			)
			(polygon
				(pts
					(xy 99.524058 -17.52346) (xy 98.863658 -17.52346) (xy 98.863658 -16.60906) (xy 98.558858 -16.60906)
					(xy 98.558858 -17.52346) (xy 97.898458 -17.52346) (xy 97.898458 -18.28546) (xy 98.558858 -18.28546)
					(xy 98.558858 -19.19986) (xy 98.863658 -19.19986) (xy 98.863658 -18.28546) (xy 99.524058 -18.28546)
				)
			)
		)
	)
	(footprint ""
		(layer "F.Cu")
		(at 184.7088 -90.8812)
		(property "Reference" "R641"
			(at 0 0 0)
			(layer "F.SilkS")
			(hide yes)
			(effects
				(font
					(size 1.27 1.27)
				)
			)
		)
		(property "Value" "4K7R2F-GP"
			(at 0.064008 -3.993896 0)
			(unlocked yes)
			(layer "F.Fab")
			(hide yes)
			(effects
				(font
					(size 1.016 1.016)
					(thickness 0.1524)
				)
			)
		)
		(property "Device Type" "R402H16"
			(at 0.064008 -5.517896 0)
			(unlocked yes)
			(layer "F.Fab")
			(hide yes)
			(effects
				(font
					(size 1.016 1.016)
					(thickness 0.1524)
				)
			)
		)
		(duplicate_pad_numbers_are_jumpers no)
		(fp_line
			(start -0.508 -0.9398)
			(end -0.508 0.9398)
			(stroke
				(width 0.1524)
				(type default)
			)
			(layer "F.SilkS")
		)
		(fp_line
			(start 0.508 -0.9398)
			(end -0.508 -0.9398)
			(stroke
				(width 0.1524)
				(type default)
			)
			(layer "F.SilkS")
		)
		(fp_rect
			(start -0.508 0.9398)
			(end 0.508 -0.9398)
			(stroke
				(width 0)
				(type default)
			)
			(fill no)
			(layer "F.CrtYd")
		)
		(fp_rect
			(start -0.508 0.9398)
			(end 0.508 -0.9398)
			(stroke
				(width 0)
				(type default)
			)
			(fill no)
			(layer "F.Fab")
		)
		(pad "1" smd custom
			(at 0 -0.4445)
			(size 0.1397 0.1397)
			(layers "F.Cu" "F.Mask" "F.Paste")
			(net "P1V8")
			(options
				(clearance outline)
				(anchor circle)
			)
			(primitives
				(gr_poly
					(pts
						(arc
							(start -0.1778 -0.2794)
							(mid -0.249642 -0.249642)
							(end -0.2794 -0.1778)
						)
						(arc
							(start -0.2794 0.1778)
							(mid -0.249642 0.249642)
							(end -0.1778 0.2794)
						)
						(arc
							(start 0.1778 0.2794)
							(mid 0.249642 0.249642)
							(end 0.2794 0.1778)
						)
						(arc
							(start 0.2794 -0.1778)
							(mid 0.249642 -0.249642)
							(end 0.1778 -0.2794)
						)
					)
					(width 0)
					(fill yes)
				)
			)
		)
		(pad "2" smd custom
			(at 0 0.4445)
			(size 0.1397 0.1397)
			(layers "F.Cu" "F.Mask" "F.Paste")
			(net "SYS_DBMODE3")
			(options
				(clearance outline)
				(anchor circle)
			)
			(primitives
				(gr_poly
					(pts
						(arc
							(start -0.1778 -0.2794)
							(mid -0.249642 -0.249642)
							(end -0.2794 -0.1778)
						)
						(arc
							(start -0.2794 0.1778)
							(mid -0.249642 0.249642)
							(end -0.1778 0.2794)
						)
						(arc
							(start 0.1778 0.2794)
							(mid 0.249642 0.249642)
							(end 0.2794 0.1778)
						)
						(arc
							(start 0.2794 -0.1778)
							(mid 0.249642 -0.249642)
							(end 0.1778 -0.2794)
						)
					)
					(width 0)
					(fill yes)
				)
			)
		)
	)
	(footprint ""
		(layer "F.Cu")
		(at 226.187 -59.436 90)
		(property "Reference" "SX1"
			(at 0 0 90)
			(layer "F.SilkS")
			(hide yes)
			(effects
				(font
					(size 1.27 1.27)
				)
			)
		)
		(property "Value" "XTAL-25MHZ-295-GP"
			(at -4.4958 -3.3782 90)
			(unlocked yes)
			(layer "F.Fab")
			(hide yes)
			(effects
				(font
					(size 1.016 1.016)
					(thickness 0.1524)
				)
			)
		)
		(property "Device Type" "SMD-OSC38H20"
			(at -4.4958 -4.9022 90)
			(unlocked yes)
			(layer "F.Fab")
			(hide yes)
			(effects
				(font
					(size 1.016 1.016)
					(thickness 0.1524)
				)
			)
		)
		(duplicate_pad_numbers_are_jumpers no)
		(fp_line
			(start 1.5748 -1.1176)
			(end 1.5748 1.1176)
			(stroke
				(width 0.1524)
				(type default)
			)
			(layer "F.SilkS")
		)
		(fp_line
			(start -1.5748 -1.1176)
			(end 1.5748 -1.1176)
			(stroke
				(width 0.1524)
				(type default)
			)
			(layer "F.SilkS")
		)
		(fp_line
			(start 1.5748 1.1176)
			(end -1.5748 1.1176)
			(stroke
				(width 0.1524)
				(type default)
			)
			(layer "F.SilkS")
		)
		(fp_line
			(start -0.659384 1.2065)
			(end -1.668272 1.2065)
			(stroke
				(width 0.3302)
				(type default)
			)
			(layer "F.SilkS")
		)
		(fp_line
			(start -1.668272 1.2065)
			(end -1.668272 0.462788)
			(stroke
				(width 0.3302)
				(type default)
			)
			(layer "F.SilkS")
		)
		(fp_poly
			(pts
				(xy -2.286 1.1557) (xy -2.286 -0.1143) (xy -1.651 0.5207)
			)
			(stroke
				(width 0)
				(type default)
			)
			(fill yes)
			(layer "F.SilkS")
		)
		(fp_rect
			(start -1.0033 0.8001)
			(end 1.0033 -0.8001)
			(stroke
				(width 0)
				(type default)
			)
			(fill no)
			(layer "F.CrtYd")
		)
		(fp_poly
			(pts
				(xy -1.8288 1.3716) (xy -1.8288 -1.3716) (xy 1.8288 -1.3716) (xy 1.8288 -0.0127) (xy 1.0033 -0.0127)
				(xy 1.0033 -0.8001) (xy -1.0033 -0.8001) (xy -1.0033 0.8001) (xy 1.0033 0.8001) (xy 1.0033 0) (xy 1.8288 0)
				(xy 1.8288 1.3716)
			)
			(stroke
				(width 0)
				(type default)
			)
			(fill no)
			(layer "F.CrtYd")
		)
		(fp_rect
			(start -1.8288 1.3716)
			(end 1.8288 -1.3716)
			(stroke
				(width 0)
				(type default)
			)
			(fill no)
			(layer "F.Fab")
		)
		(pad "1" smd rect
			(at -0.769112 0.495046 90)
			(size 1.0922 0.7366)
			(layers "F.Cu" "F.Mask" "F.Paste")
			(net "REF_CLK")
		)
		(pad "2" smd rect
			(at 0.769112 0.495046 90)
			(size 1.0922 0.7366)
			(layers "F.Cu" "F.Mask" "F.Paste")
			(net "GND")
		)
		(pad "3" smd rect
			(at 0.769112 -0.495046 90)
			(size 1.0922 0.7366)
			(layers "F.Cu" "F.Mask" "F.Paste")
			(net "IOC_REF_CLK_P")
		)
		(pad "4" smd rect
			(at -0.769112 -0.495046 90)
			(size 1.0922 0.7366)
			(layers "F.Cu" "F.Mask" "F.Paste")
			(net "GND")
		)
		(zone
			(layer "F.Cu")
			(hatch none 0.5)
			(connect_pads
				(clearance 0)
			)
			(min_thickness 0.25)
			(keepout
				(tracks allowed)
				(vias not_allowed)
				(pads allowed)
				(copperpour not_allowed)
				(footprints allowed)
			)
			(placement
				(enabled no)
				(sheetname "")
			)
			(fill
				(thermal_gap 0.5)
				(thermal_bridge_width 0.5)
				(island_removal_mode 0)
			)
			(polygon
				(pts
					(xy 227.050346 -59.212988) (xy 226.313746 -59.212988) (xy 226.313746 -58.120788) (xy 226.060254 -58.120788)
					(xy 226.060254 -59.212988) (xy 225.323654 -59.212988) (xy 225.323654 -59.659012) (xy 226.060254 -59.659012)
					(xy 226.060254 -60.751212) (xy 226.313746 -60.751212) (xy 226.313746 -59.659012) (xy 227.050346 -59.659012)
				)
			)
		)
		(zone
			(layer "F.Cu")
			(hatch none 0.5)
			(connect_pads
				(clearance 0)
			)
			(min_thickness 0.25)
			(keepout
				(tracks not_allowed)
				(vias allowed)
				(pads allowed)
				(copperpour not_allowed)
				(footprints allowed)
			)
			(placement
				(enabled no)
				(sheetname "")
			)
			(fill
				(thermal_gap 0.5)
				(thermal_bridge_width 0.5)
				(island_removal_mode 0)
			)
			(polygon
				(pts
					(xy 227.050346 -59.212988) (xy 226.313746 -59.212988) (xy 226.313746 -58.120788) (xy 226.060254 -58.120788)
					(xy 226.060254 -59.212988) (xy 225.323654 -59.212988) (xy 225.323654 -59.659012) (xy 226.060254 -59.659012)
					(xy 226.060254 -60.751212) (xy 226.313746 -60.751212) (xy 226.313746 -59.659012) (xy 227.050346 -59.659012)
				)
			)
		)
	)
	(footprint ""
		(layer "F.Cu")
		(at 51.431444 -177.38217 -90)
		(property "Reference" "C49"
			(at 0 0 270)
			(layer "F.SilkS")
			(hide yes)
			(effects
				(font
					(size 1.27 1.27)
				)
			)
		)
		(property "Value" "SCD1U16V2KX-3GP"
			(at 1.1811 -2.7051 270)
			(unlocked yes)
			(layer "F.Fab")
			(hide yes)
			(effects
				(font
					(size 1.016 1.016)
					(thickness 0.1524)
				)
			)
		)
		(property "Device Type" "C402H22"
			(at 1.1811 -4.2291 270)
			(unlocked yes)
			(layer "F.Fab")
			(hide yes)
			(effects
				(font
					(size 1.016 1.016)
					(thickness 0.1524)
				)
			)
		)
		(duplicate_pad_numbers_are_jumpers no)
		(fp_rect
			(start -0.4318 0.9525)
			(end 0.4318 -0.9525)
			(stroke
				(width 0)
				(type default)
			)
			(fill no)
			(layer "F.CrtYd")
		)
		(fp_rect
			(start -0.4318 0.9525)
			(end 0.4318 -0.9525)
			(stroke
				(width 0)
				(type default)
			)
			(fill no)
			(layer "F.Fab")
		)
		(pad "1" smd custom
			(at 0 -0.4445 270)
			(size 0.1524 0.1524)
			(layers "F.Cu" "F.Mask" "F.Paste")
			(net "P3V3_STBY")
			(options
				(clearance outline)
				(anchor circle)
			)
			(primitives
				(gr_poly
					(pts
						(arc
							(start 0.3048 -0.2032)
							(mid 0.275042 -0.275042)
							(end 0.2032 -0.3048)
						)
						(arc
							(start -0.2032 -0.3048)
							(mid -0.275042 -0.275042)
							(end -0.3048 -0.2032)
						)
						(arc
							(start -0.3048 0.2032)
							(mid -0.275042 0.275042)
							(end -0.2032 0.3048)
						)
						(arc
							(start 0.2032 0.3048)
							(mid 0.275042 0.275042)
							(end 0.3048 0.2032)
						)
					)
					(width 0)
					(fill yes)
				)
			)
		)
		(pad "2" smd custom
			(at 0 0.4445 270)
			(size 0.1524 0.1524)
			(layers "F.Cu" "F.Mask" "F.Paste")
			(net "GND")
			(options
				(clearance outline)
				(anchor circle)
			)
			(primitives
				(gr_poly
					(pts
						(arc
							(start 0.3048 -0.2032)
							(mid 0.275042 -0.275042)
							(end 0.2032 -0.3048)
						)
						(arc
							(start -0.2032 -0.3048)
							(mid -0.275042 -0.275042)
							(end -0.3048 -0.2032)
						)
						(arc
							(start -0.3048 0.2032)
							(mid -0.275042 0.275042)
							(end -0.2032 0.3048)
						)
						(arc
							(start 0.2032 0.3048)
							(mid 0.275042 0.275042)
							(end 0.3048 0.2032)
						)
					)
					(width 0)
					(fill yes)
				)
			)
		)
	)
	(footprint ""
		(layer "F.Cu")
		(at 155.1686 -38.481)
		(property "Reference" "TP181"
			(at 0 0 0)
			(layer "F.SilkS")
			(hide yes)
			(effects
				(font
					(size 1.27 1.27)
				)
			)
		)
		(property "Value" "TPAD28-2-GP"
			(at -0.0127 -1.6637 0)
			(unlocked yes)
			(layer "F.Fab")
			(hide yes)
			(effects
				(font
					(size 1.016 1.016)
					(thickness 0.1524)
				)
			)
		)
		(property "Device Type" "TPAD28"
			(at -0.0127 -3.1877 0)
			(unlocked yes)
			(layer "F.Fab")
			(hide yes)
			(effects
				(font
					(size 1.016 1.016)
					(thickness 0.1524)
				)
			)
		)
		(duplicate_pad_numbers_are_jumpers no)
		(fp_poly
			(pts
				(arc
					(start 0.3556 0)
					(mid -0.3556 0)
					(end 0.3556 0)
				)
			)
			(stroke
				(width 0)
				(type default)
			)
			(fill no)
			(layer "F.CrtYd")
		)
		(fp_poly
			(pts
				(arc
					(start 0.6096 0)
					(mid -0.6096 0)
					(end 0.6096 0)
				)
			)
			(stroke
				(width 0)
				(type default)
			)
			(fill no)
			(layer "F.Fab")
		)
		(pad "1" smd circle
			(at 0 0)
			(size 0.7112 0.7112)
			(layers "F.Cu" "F.Mask" "F.Paste")
			(net "ZDEF_EXTB_TP_C2")
		)
	)
	(footprint ""
		(layer "F.Cu")
		(at 44.37761 -131.75488 180)
		(property "Reference" "R158"
			(at 0 0 180)
			(layer "F.SilkS")
			(hide yes)
			(effects
				(font
					(size 1.27 1.27)
				)
			)
		)
		(property "Value" "0R2J-2-GP"
			(at 0.064008 -3.993896 180)
			(unlocked yes)
			(layer "F.Fab")
			(hide yes)
			(effects
				(font
					(size 1.016 1.016)
					(thickness 0.1524)
				)
			)
		)
		(property "Device Type" "R402H16"
			(at 0.064008 -5.517896 180)
			(unlocked yes)
			(layer "F.Fab")
			(hide yes)
			(effects
				(font
					(size 1.016 1.016)
					(thickness 0.1524)
				)
			)
		)
		(duplicate_pad_numbers_are_jumpers no)
		(fp_line
			(start 0.508 -0.9398)
			(end -0.508 -0.9398)
			(stroke
				(width 0.1524)
				(type default)
			)
			(layer "F.SilkS")
		)
		(fp_line
			(start -0.508 -0.9398)
			(end -0.508 0.9398)
			(stroke
				(width 0.1524)
				(type default)
			)
			(layer "F.SilkS")
		)
		(fp_rect
			(start -0.508 0.9398)
			(end 0.508 -0.9398)
			(stroke
				(width 0)
				(type default)
			)
			(fill no)
			(layer "F.CrtYd")
		)
		(fp_rect
			(start -0.508 0.9398)
			(end 0.508 -0.9398)
			(stroke
				(width 0)
				(type default)
			)
			(fill no)
			(layer "F.Fab")
		)
		(pad "1" smd custom
			(at 0 -0.4445 180)
			(size 0.1397 0.1397)
			(layers "F.Cu" "F.Mask" "F.Paste")
			(net "I2C_IOC_SDA")
			(options
				(clearance outline)
				(anchor circle)
			)
			(primitives
				(gr_poly
					(pts
						(arc
							(start -0.1778 -0.2794)
							(mid -0.249642 -0.249642)
							(end -0.2794 -0.1778)
						)
						(arc
							(start -0.2794 0.1778)
							(mid -0.249642 0.249642)
							(end -0.1778 0.2794)
						)
						(arc
							(start 0.1778 0.2794)
							(mid 0.249642 0.249642)
							(end 0.2794 0.1778)
						)
						(arc
							(start 0.2794 -0.1778)
							(mid 0.249642 -0.249642)
							(end 0.1778 -0.2794)
						)
					)
					(width 0)
					(fill yes)
				)
			)
		)
		(pad "2" smd custom
			(at 0 0.4445 180)
			(size 0.1397 0.1397)
			(layers "F.Cu" "F.Mask" "F.Paste")
			(net "BMC_SMB2_DAT")
			(options
				(clearance outline)
				(anchor circle)
			)
			(primitives
				(gr_poly
					(pts
						(arc
							(start -0.1778 -0.2794)
							(mid -0.249642 -0.249642)
							(end -0.2794 -0.1778)
						)
						(arc
							(start -0.2794 0.1778)
							(mid -0.249642 0.249642)
							(end -0.1778 0.2794)
						)
						(arc
							(start 0.1778 0.2794)
							(mid 0.249642 0.249642)
							(end 0.2794 0.1778)
						)
						(arc
							(start 0.2794 -0.1778)
							(mid 0.249642 -0.249642)
							(end 0.1778 -0.2794)
						)
					)
					(width 0)
					(fill yes)
				)
			)
		)
	)
	(footprint ""
		(layer "F.Cu")
		(at 206.004414 -13.526008 90)
		(property "Reference" "Q28"
			(at 0 0 90)
			(layer "F.SilkS")
			(hide yes)
			(effects
				(font
					(size 1.27 1.27)
				)
			)
		)
		(property "Value" "SSM6P39TU-GP"
			(at 0.0508 -11.5824 90)
			(unlocked yes)
			(layer "F.Fab")
			(hide yes)
			(effects
				(font
					(size 1.016 1.016)
					(thickness 0.1524)
				)
			)
		)
		(property "Device Type" "UMT6H30"
			(at 0.0508 -13.1572 90)
			(unlocked yes)
			(layer "F.Fab")
			(hide yes)
			(effects
				(font
					(size 1.016 1.016)
					(thickness 0.1524)
				)
			)
		)
		(duplicate_pad_numbers_are_jumpers no)
		(fp_line
			(start 1.524 -0.36449)
			(end 1.524 -1.82245)
			(stroke
				(width 0.508)
				(type default)
			)
			(layer "F.SilkS")
		)
		(fp_line
			(start 1.524 -0.36449)
			(end 1.45796 -0.36449)
			(stroke
				(width 0.1524)
				(type default)
			)
			(layer "F.SilkS")
		)
		(fp_line
			(start 1.524 -0.36449)
			(end 1.524 0.36449)
			(stroke
				(width 0.1524)
				(type default)
			)
			(layer "F.SilkS")
		)
		(fp_line
			(start 1.45796 -0.36449)
			(end 1.09347 0)
			(stroke
				(width 0.1524)
				(type default)
			)
			(layer "F.SilkS")
		)
		(fp_line
			(start -1.27 -0.36449)
			(end 1.524 -0.36449)
			(stroke
				(width 0.1524)
				(type default)
			)
			(layer "F.SilkS")
		)
		(fp_line
			(start -1.27 -0.36449)
			(end -1.27 0.36449)
			(stroke
				(width 0.1524)
				(type default)
			)
			(layer "F.SilkS")
		)
		(fp_line
			(start 1.09347 0)
			(end 1.45796 0.36449)
			(stroke
				(width 0.1524)
				(type default)
			)
			(layer "F.SilkS")
		)
		(fp_line
			(start 1.524 0.36449)
			(end -1.27 0.36449)
			(stroke
				(width 0.1524)
				(type default)
			)
			(layer "F.SilkS")
		)
		(fp_poly
			(pts
				(xy -0.65024 0.36449) (xy -0.65024 -0.36449) (xy 0.65024 -0.36449) (xy 0.65024 0.36449)
			)
			(stroke
				(width 0)
				(type default)
			)
			(fill yes)
			(layer "F.SilkS")
		)
		(fp_poly
			(pts
				(xy 1.016 -1.0668) (xy 1.016 1.0668) (xy -1.016 1.0668) (xy -1.016 -1.0668)
			)
			(stroke
				(width 0)
				(type default)
			)
			(fill no)
			(layer "F.CrtYd")
		)
		(fp_poly
			(pts
				(xy -1.524 1.905) (xy 1.524 1.905) (xy 1.524 -1.06426) (xy 1.016 -1.06426) (xy 1.016 1.0668) (xy -1.016 1.0668)
				(xy -1.016 -1.0668) (xy 1.524 -1.0668) (xy 1.524 -1.905) (xy -1.524 -1.905)
			)
			(stroke
				(width 0)
				(type default)
			)
			(fill no)
			(layer "F.CrtYd")
		)
		(fp_poly
			(pts
				(xy -1.524 -1.905) (xy -1.524 1.905) (xy 1.524 1.905) (xy 1.524 -1.905)
			)
			(stroke
				(width 0)
				(type default)
			)
			(fill no)
			(layer "F.Fab")
		)
		(pad "1" smd rect
			(at 0.65024 -1.02489 90)
			(size 0.4064 0.8128)
			(layers "F.Cu" "F.Mask" "F.Paste")
			(net "P3V3_STBY")
		)
		(pad "2" smd rect
			(at 0 -1.02489 90)
			(size 0.4064 0.8128)
			(layers "F.Cu" "F.Mask" "F.Paste")
			(net "BMC_ML_PWR_YELLOW_LED_R")
		)
		(pad "3" smd rect
			(at -0.65024 -1.02489 90)
			(size 0.4064 0.8128)
			(layers "F.Cu" "F.Mask" "F.Paste")
			(net "ML_PWR_BLUE_LED")
		)
		(pad "4" smd rect
			(at -0.65024 1.02489 90)
			(size 0.4064 0.8128)
			(layers "F.Cu" "F.Mask" "F.Paste")
			(net "P5V_STBY")
		)
		(pad "5" smd rect
			(at 0 1.02489 90)
			(size 0.4064 0.8128)
			(layers "F.Cu" "F.Mask" "F.Paste")
			(net "BMC_ML_PWR_BLUE_LED_L")
		)
		(pad "6" smd rect
			(at 0.65024 1.02489 90)
			(size 0.4064 0.8128)
			(layers "F.Cu" "F.Mask" "F.Paste")
			(net "ML_PWR_YELLOW_LED")
		)
	)
	(footprint ""
		(layer "F.Cu")
		(at 157.3276 -143.637 180)
		(property "Reference" "R521"
			(at 0 0 180)
			(layer "F.SilkS")
			(hide yes)
			(effects
				(font
					(size 1.27 1.27)
				)
			)
		)
		(property "Value" "15KR2F-GP"
			(at 0.064008 -3.993896 180)
			(unlocked yes)
			(layer "F.Fab")
			(hide yes)
			(effects
				(font
					(size 1.016 1.016)
					(thickness 0.1524)
				)
			)
		)
		(property "Device Type" "R402H16"
			(at 0.064008 -5.517896 180)
			(unlocked yes)
			(layer "F.Fab")
			(hide yes)
			(effects
				(font
					(size 1.016 1.016)
					(thickness 0.1524)
				)
			)
		)
		(duplicate_pad_numbers_are_jumpers no)
		(fp_line
			(start 0.508 -0.9398)
			(end -0.508 -0.9398)
			(stroke
				(width 0.1524)
				(type default)
			)
			(layer "F.SilkS")
		)
		(fp_line
			(start -0.508 -0.9398)
			(end -0.508 0.9398)
			(stroke
				(width 0.1524)
				(type default)
			)
			(layer "F.SilkS")
		)
		(fp_rect
			(start -0.508 0.9398)
			(end 0.508 -0.9398)
			(stroke
				(width 0)
				(type default)
			)
			(fill no)
			(layer "F.CrtYd")
		)
		(fp_rect
			(start -0.508 0.9398)
			(end 0.508 -0.9398)
			(stroke
				(width 0)
				(type default)
			)
			(fill no)
			(layer "F.Fab")
		)
		(pad "1" smd custom
			(at 0 -0.4445 180)
			(size 0.1397 0.1397)
			(layers "F.Cu" "F.Mask" "F.Paste")
			(net "PWRGD_P1V8_STBY")
			(options
				(clearance outline)
				(anchor circle)
			)
			(primitives
				(gr_poly
					(pts
						(arc
							(start -0.1778 -0.2794)
							(mid -0.249642 -0.249642)
							(end -0.2794 -0.1778)
						)
						(arc
							(start -0.2794 0.1778)
							(mid -0.249642 0.249642)
							(end -0.1778 0.2794)
						)
						(arc
							(start 0.1778 0.2794)
							(mid 0.249642 0.249642)
							(end 0.2794 0.1778)
						)
						(arc
							(start 0.2794 -0.1778)
							(mid 0.249642 -0.249642)
							(end 0.1778 -0.2794)
						)
					)
					(width 0)
					(fill yes)
				)
			)
		)
		(pad "2" smd custom
			(at 0 0.4445 180)
			(size 0.1397 0.1397)
			(layers "F.Cu" "F.Mask" "F.Paste")
			(net "GND")
			(options
				(clearance outline)
				(anchor circle)
			)
			(primitives
				(gr_poly
					(pts
						(arc
							(start -0.1778 -0.2794)
							(mid -0.249642 -0.249642)
							(end -0.2794 -0.1778)
						)
						(arc
							(start -0.2794 0.1778)
							(mid -0.249642 0.249642)
							(end -0.1778 0.2794)
						)
						(arc
							(start 0.1778 0.2794)
							(mid 0.249642 0.249642)
							(end 0.2794 0.1778)
						)
						(arc
							(start 0.2794 -0.1778)
							(mid 0.249642 -0.249642)
							(end 0.1778 -0.2794)
						)
					)
					(width 0)
					(fill yes)
				)
			)
		)
	)
	(footprint ""
		(layer "F.Cu")
		(at 98.29038 -177.08372 90)
		(property "Reference" "C141"
			(at 0 0 90)
			(layer "F.SilkS")
			(hide yes)
			(effects
				(font
					(size 1.27 1.27)
				)
			)
		)
		(property "Value" "SCD1U16V2KX-3GP"
			(at 1.1811 -2.7051 90)
			(unlocked yes)
			(layer "F.Fab")
			(hide yes)
			(effects
				(font
					(size 1.016 1.016)
					(thickness 0.1524)
				)
			)
		)
		(property "Device Type" "C402H22"
			(at 1.1811 -4.2291 90)
			(unlocked yes)
			(layer "F.Fab")
			(hide yes)
			(effects
				(font
					(size 1.016 1.016)
					(thickness 0.1524)
				)
			)
		)
		(duplicate_pad_numbers_are_jumpers no)
		(fp_rect
			(start -0.4318 0.9525)
			(end 0.4318 -0.9525)
			(stroke
				(width 0)
				(type default)
			)
			(fill no)
			(layer "F.CrtYd")
		)
		(fp_rect
			(start -0.4318 0.9525)
			(end 0.4318 -0.9525)
			(stroke
				(width 0)
				(type default)
			)
			(fill no)
			(layer "F.Fab")
		)
		(pad "1" smd custom
			(at 0 -0.4445 90)
			(size 0.1524 0.1524)
			(layers "F.Cu" "F.Mask" "F.Paste")
			(net "P3V3_STBY")
			(options
				(clearance outline)
				(anchor circle)
			)
			(primitives
				(gr_poly
					(pts
						(arc
							(start 0.3048 -0.2032)
							(mid 0.275042 -0.275042)
							(end 0.2032 -0.3048)
						)
						(arc
							(start -0.2032 -0.3048)
							(mid -0.275042 -0.275042)
							(end -0.3048 -0.2032)
						)
						(arc
							(start -0.3048 0.2032)
							(mid -0.275042 0.275042)
							(end -0.2032 0.3048)
						)
						(arc
							(start 0.2032 0.3048)
							(mid 0.275042 0.275042)
							(end 0.3048 0.2032)
						)
					)
					(width 0)
					(fill yes)
				)
			)
		)
		(pad "2" smd custom
			(at 0 0.4445 90)
			(size 0.1524 0.1524)
			(layers "F.Cu" "F.Mask" "F.Paste")
			(net "GND")
			(options
				(clearance outline)
				(anchor circle)
			)
			(primitives
				(gr_poly
					(pts
						(arc
							(start 0.3048 -0.2032)
							(mid 0.275042 -0.275042)
							(end 0.2032 -0.3048)
						)
						(arc
							(start -0.2032 -0.3048)
							(mid -0.275042 -0.275042)
							(end -0.3048 -0.2032)
						)
						(arc
							(start -0.3048 0.2032)
							(mid -0.275042 0.275042)
							(end -0.2032 0.3048)
						)
						(arc
							(start 0.2032 0.3048)
							(mid 0.275042 0.275042)
							(end 0.3048 0.2032)
						)
					)
					(width 0)
					(fill yes)
				)
			)
		)
	)
	(footprint ""
		(layer "F.Cu")
		(at 49.948592 -166.451534)
		(property "Reference" "R778"
			(at 0 0 0)
			(layer "F.SilkS")
			(hide yes)
			(effects
				(font
					(size 1.27 1.27)
				)
			)
		)
		(property "Value" "866R2F-GP"
			(at 0.064008 -3.993896 0)
			(unlocked yes)
			(layer "F.Fab")
			(hide yes)
			(effects
				(font
					(size 1.016 1.016)
					(thickness 0.1524)
				)
			)
		)
		(property "Device Type" "R402H16"
			(at 0.064008 -5.517896 0)
			(unlocked yes)
			(layer "F.Fab")
			(hide yes)
			(effects
				(font
					(size 1.016 1.016)
					(thickness 0.1524)
				)
			)
		)
		(duplicate_pad_numbers_are_jumpers no)
		(fp_line
			(start -0.508 -0.9398)
			(end -0.508 0.9398)
			(stroke
				(width 0.1524)
				(type default)
			)
			(layer "F.SilkS")
		)
		(fp_line
			(start 0.508 -0.9398)
			(end -0.508 -0.9398)
			(stroke
				(width 0.1524)
				(type default)
			)
			(layer "F.SilkS")
		)
		(fp_rect
			(start -0.508 0.9398)
			(end 0.508 -0.9398)
			(stroke
				(width 0)
				(type default)
			)
			(fill no)
			(layer "F.CrtYd")
		)
		(fp_rect
			(start -0.508 0.9398)
			(end 0.508 -0.9398)
			(stroke
				(width 0)
				(type default)
			)
			(fill no)
			(layer "F.Fab")
		)
		(pad "1" smd custom
			(at 0 -0.4445)
			(size 0.1397 0.1397)
			(layers "F.Cu" "F.Mask" "F.Paste")
			(net "P2V5_STBY")
			(options
				(clearance outline)
				(anchor circle)
			)
			(primitives
				(gr_poly
					(pts
						(arc
							(start -0.1778 -0.2794)
							(mid -0.249642 -0.249642)
							(end -0.2794 -0.1778)
						)
						(arc
							(start -0.2794 0.1778)
							(mid -0.249642 0.249642)
							(end -0.1778 0.2794)
						)
						(arc
							(start 0.1778 0.2794)
							(mid 0.249642 0.249642)
							(end 0.2794 0.1778)
						)
						(arc
							(start 0.2794 -0.1778)
							(mid 0.249642 -0.249642)
							(end 0.1778 -0.2794)
						)
					)
					(width 0)
					(fill yes)
				)
			)
		)
		(pad "2" smd custom
			(at 0 0.4445)
			(size 0.1397 0.1397)
			(layers "F.Cu" "F.Mask" "F.Paste")
			(net "ADC_P2V5_STBY")
			(options
				(clearance outline)
				(anchor circle)
			)
			(primitives
				(gr_poly
					(pts
						(arc
							(start -0.1778 -0.2794)
							(mid -0.249642 -0.249642)
							(end -0.2794 -0.1778)
						)
						(arc
							(start -0.2794 0.1778)
							(mid -0.249642 0.249642)
							(end -0.1778 0.2794)
						)
						(arc
							(start 0.1778 0.2794)
							(mid 0.249642 0.249642)
							(end 0.2794 0.1778)
						)
						(arc
							(start 0.2794 -0.1778)
							(mid 0.249642 -0.249642)
							(end 0.1778 -0.2794)
						)
					)
					(width 0)
					(fill yes)
				)
			)
		)
	)
	(footprint ""
		(layer "F.Cu")
		(at 199.75068 -12.779248 180)
		(property "Reference" "U47"
			(at 0 0 180)
			(layer "F.SilkS")
			(hide yes)
			(effects
				(font
					(size 1.27 1.27)
				)
			)
		)
		(property "Value" "74LVC1G86DCKR-GP"
			(at -2.3368 -8.6868 180)
			(unlocked yes)
			(layer "F.Fab")
			(hide yes)
			(effects
				(font
					(size 1.016 1.016)
					(thickness 0.1524)
				)
			)
		)
		(property "Device Type" "SC70-5H44"
			(at -2.3114 -10.414 180)
			(unlocked yes)
			(layer "F.Fab")
			(hide yes)
			(effects
				(font
					(size 1.016 1.016)
					(thickness 0.1524)
				)
			)
		)
		(duplicate_pad_numbers_are_jumpers no)
		(fp_line
			(start 1.3843 -1.8034)
			(end 1.3843 -1.1176)
			(stroke
				(width 0.3302)
				(type default)
			)
			(layer "F.SilkS")
		)
		(fp_line
			(start 1.27 1.7018)
			(end -1.27 1.7018)
			(stroke
				(width 0.1524)
				(type default)
			)
			(layer "F.SilkS")
		)
		(fp_line
			(start 1.27 -1.7018)
			(end 1.27 1.7018)
			(stroke
				(width 0.1524)
				(type default)
			)
			(layer "F.SilkS")
		)
		(fp_line
			(start 0.6604 -1.8034)
			(end 1.3843 -1.8034)
			(stroke
				(width 0.3302)
				(type default)
			)
			(layer "F.SilkS")
		)
		(fp_line
			(start -1.27 1.7018)
			(end -1.27 -1.7018)
			(stroke
				(width 0.1524)
				(type default)
			)
			(layer "F.SilkS")
		)
		(fp_line
			(start -1.27 -1.7018)
			(end 1.27 -1.7018)
			(stroke
				(width 0.1524)
				(type default)
			)
			(layer "F.SilkS")
		)
		(fp_rect
			(start -1.524 1.9558)
			(end 1.524 -1.9558)
			(stroke
				(width 0)
				(type default)
			)
			(fill no)
			(layer "F.CrtYd")
		)
		(fp_poly
			(pts
				(xy -1.524 -1.9558) (xy 1.524 -1.9558) (xy 1.524 1.9558) (xy -1.524 1.9558)
			)
			(stroke
				(width 0)
				(type default)
			)
			(fill no)
			(layer "F.Fab")
		)
		(pad "1" smd rect
			(at 0.65024 -0.8255 180)
			(size 0.4064 1.2192)
			(layers "F.Cu" "F.Mask" "F.Paste")
			(net "IOC_EXT1_LED_B")
		)
		(pad "2" smd rect
			(at 0 -0.8255 180)
			(size 0.4064 1.2192)
			(layers "F.Cu" "F.Mask" "F.Paste")
			(net "IOC_EXT1_LED_Y")
		)
		(pad "3" smd rect
			(at -0.65024 -0.8255 180)
			(size 0.4064 1.2192)
			(layers "F.Cu" "F.Mask" "F.Paste")
			(net "GND")
		)
		(pad "4" smd rect
			(at -0.65024 0.8255 180)
			(size 0.4064 1.2192)
			(layers "F.Cu" "F.Mask" "F.Paste")
			(net "IOC_EXT1_LED_Y_XOR")
		)
		(pad "5" smd rect
			(at 0.65024 0.8255 180)
			(size 0.4064 1.2192)
			(layers "F.Cu" "F.Mask" "F.Paste")
			(net "P1V8")
		)
	)
	(footprint ""
		(layer "F.Cu")
		(at 70.59803 -139.546076 90)
		(property "Reference" "U5"
			(at 0 0 90)
			(layer "F.SilkS")
			(hide yes)
			(effects
				(font
					(size 1.27 1.27)
				)
			)
		)
		(property "Value" "74LVC2G07GW-GP"
			(at -2.3622 -8.2042 90)
			(unlocked yes)
			(layer "F.Fab")
			(hide yes)
			(effects
				(font
					(size 1.016 1.016)
					(thickness 0.1524)
				)
			)
		)
		(property "Device Type" "SOT-363H44"
			(at -2.3622 -10.1092 90)
			(unlocked yes)
			(layer "F.Fab")
			(hide yes)
			(effects
				(font
					(size 1.016 1.016)
					(thickness 0.1524)
				)
			)
		)
		(duplicate_pad_numbers_are_jumpers no)
		(fp_line
			(start 1.4478 -1.7018)
			(end -1.4478 -1.7018)
			(stroke
				(width 0.1524)
				(type default)
			)
			(layer "F.SilkS")
		)
		(fp_line
			(start -1.4478 -1.7018)
			(end -1.4478 1.7018)
			(stroke
				(width 0.1524)
				(type default)
			)
			(layer "F.SilkS")
		)
		(fp_line
			(start -1.27 1.524)
			(end -1.27 0.6604)
			(stroke
				(width 0.4826)
				(type default)
			)
			(layer "F.SilkS")
		)
		(fp_line
			(start 1.4478 1.7018)
			(end 1.4478 -1.7018)
			(stroke
				(width 0.1524)
				(type default)
			)
			(layer "F.SilkS")
		)
		(fp_line
			(start -1.4478 1.7018)
			(end 1.4478 1.7018)
			(stroke
				(width 0.1524)
				(type default)
			)
			(layer "F.SilkS")
		)
		(fp_poly
			(pts
				(xy -1.524 -1.778) (xy 1.524 -1.778) (xy 1.524 1.778) (xy -1.524 1.778)
			)
			(stroke
				(width 0)
				(type default)
			)
			(fill no)
			(layer "F.CrtYd")
		)
		(fp_poly
			(pts
				(xy -1.524 -1.778) (xy 1.524 -1.778) (xy 1.524 1.778) (xy -1.524 1.778)
			)
			(stroke
				(width 0)
				(type default)
			)
			(fill no)
			(layer "F.Fab")
		)
		(pad "1" smd rect
			(at -0.65024 0.9398 90)
			(size 0.4064 1.016)
			(layers "F.Cu" "F.Mask" "F.Paste")
			(net "FP_PWR_BTN_N_R")
		)
		(pad "2" smd rect
			(at 0 0.9398 90)
			(size 0.4064 1.016)
			(layers "F.Cu" "F.Mask" "F.Paste")
			(net "GND")
		)
		(pad "3" smd rect
			(at 0.65024 0.9398 90)
			(size 0.4064 1.016)
			(layers "F.Cu" "F.Mask" "F.Paste")
			(net "FP_RESET_RC_N")
		)
		(pad "4" smd rect
			(at 0.65024 -0.9398 90)
			(size 0.4064 1.016)
			(layers "F.Cu" "F.Mask" "F.Paste")
			(net "FP_RETBTN")
		)
		(pad "5" smd rect
			(at 0 -0.9398 90)
			(size 0.4064 1.016)
			(layers "F.Cu" "F.Mask" "F.Paste")
			(net "P3V3_STBY")
		)
		(pad "6" smd rect
			(at -0.65024 -0.9398 90)
			(size 0.4064 1.016)
			(layers "F.Cu" "F.Mask" "F.Paste")
			(net "FP_PWRBTN")
		)
	)
	(footprint ""
		(layer "F.Cu")
		(at 55.7784 -181.3306)
		(property "Reference" "C172"
			(at 0 0 0)
			(layer "F.SilkS")
			(hide yes)
			(effects
				(font
					(size 1.27 1.27)
				)
			)
		)
		(property "Value" "SC10U6D3V5KX-4GP"
			(at -0.0762 -6.1214 0)
			(unlocked yes)
			(layer "F.Fab")
			(hide yes)
			(effects
				(font
					(size 1.016 1.016)
					(thickness 0.1524)
				)
			)
		)
		(property "Device Type" "C805H58"
			(at -0.0762 -8.1534 0)
			(unlocked yes)
			(layer "F.Fab")
			(hide yes)
			(effects
				(font
					(size 1.016 1.016)
					(thickness 0.1524)
				)
			)
		)
		(duplicate_pad_numbers_are_jumpers no)
		(fp_line
			(start 0.635 0)
			(end -0.635 0)
			(stroke
				(width 0.508)
				(type default)
			)
			(layer "F.SilkS")
		)
		(fp_rect
			(start -0.9652 1.778)
			(end 0.9652 -1.778)
			(stroke
				(width 0)
				(type default)
			)
			(fill no)
			(layer "F.CrtYd")
		)
		(fp_poly
			(pts
				(xy -0.9652 -1.778) (xy 0.9652 -1.778) (xy 0.9652 1.778) (xy -0.9652 1.778)
			)
			(stroke
				(width 0)
				(type default)
			)
			(fill no)
			(layer "F.Fab")
		)
		(pad "1" smd rect
			(at 0 -0.9652)
			(size 1.397 1.143)
			(layers "F.Cu" "F.Mask" "F.Paste")
			(net "P3V3_STBY_OUT")
		)
		(pad "2" smd rect
			(at 0 0.9652)
			(size 1.397 1.143)
			(layers "F.Cu" "F.Mask" "F.Paste")
			(net "GND")
		)
	)
	(footprint ""
		(layer "F.Cu")
		(at 20.773136 -170.1038)
		(property "Reference" "C230"
			(at 0 0 0)
			(layer "F.SilkS")
			(hide yes)
			(effects
				(font
					(size 1.27 1.27)
				)
			)
		)
		(property "Value" "SCD1U16V2KX-3GP"
			(at 1.1811 -2.7051 0)
			(unlocked yes)
			(layer "F.Fab")
			(hide yes)
			(effects
				(font
					(size 1.016 1.016)
					(thickness 0.1524)
				)
			)
		)
		(property "Device Type" "C402H22"
			(at 1.1811 -4.2291 0)
			(unlocked yes)
			(layer "F.Fab")
			(hide yes)
			(effects
				(font
					(size 1.016 1.016)
					(thickness 0.1524)
				)
			)
		)
		(duplicate_pad_numbers_are_jumpers no)
		(fp_rect
			(start -0.4318 0.9525)
			(end 0.4318 -0.9525)
			(stroke
				(width 0)
				(type default)
			)
			(fill no)
			(layer "F.CrtYd")
		)
		(fp_rect
			(start -0.4318 0.9525)
			(end 0.4318 -0.9525)
			(stroke
				(width 0)
				(type default)
			)
			(fill no)
			(layer "F.Fab")
		)
		(pad "1" smd custom
			(at 0 -0.4445)
			(size 0.1524 0.1524)
			(layers "F.Cu" "F.Mask" "F.Paste")
			(net "P1V8_STBY")
			(options
				(clearance outline)
				(anchor circle)
			)
			(primitives
				(gr_poly
					(pts
						(arc
							(start 0.3048 -0.2032)
							(mid 0.275042 -0.275042)
							(end 0.2032 -0.3048)
						)
						(arc
							(start -0.2032 -0.3048)
							(mid -0.275042 -0.275042)
							(end -0.3048 -0.2032)
						)
						(arc
							(start -0.3048 0.2032)
							(mid -0.275042 0.275042)
							(end -0.2032 0.3048)
						)
						(arc
							(start 0.2032 0.3048)
							(mid 0.275042 0.275042)
							(end 0.3048 0.2032)
						)
					)
					(width 0)
					(fill yes)
				)
			)
		)
		(pad "2" smd custom
			(at 0 0.4445)
			(size 0.1524 0.1524)
			(layers "F.Cu" "F.Mask" "F.Paste")
			(net "GND")
			(options
				(clearance outline)
				(anchor circle)
			)
			(primitives
				(gr_poly
					(pts
						(arc
							(start 0.3048 -0.2032)
							(mid 0.275042 -0.275042)
							(end 0.2032 -0.3048)
						)
						(arc
							(start -0.2032 -0.3048)
							(mid -0.275042 -0.275042)
							(end -0.3048 -0.2032)
						)
						(arc
							(start -0.3048 0.2032)
							(mid -0.275042 0.275042)
							(end -0.2032 0.3048)
						)
						(arc
							(start 0.2032 0.3048)
							(mid 0.275042 0.275042)
							(end 0.3048 0.2032)
						)
					)
					(width 0)
					(fill yes)
				)
			)
		)
	)
	(footprint ""
		(layer "F.Cu")
		(at 46.054772 -117.791992 90)
		(property "Reference" "C36"
			(at 0 0 90)
			(layer "F.SilkS")
			(hide yes)
			(effects
				(font
					(size 1.27 1.27)
				)
			)
		)
		(property "Value" "SCD1U16V2KX-3GP"
			(at 1.1811 -2.7051 90)
			(unlocked yes)
			(layer "F.Fab")
			(hide yes)
			(effects
				(font
					(size 1.016 1.016)
					(thickness 0.1524)
				)
			)
		)
		(property "Device Type" "C402H22"
			(at 1.1811 -4.2291 90)
			(unlocked yes)
			(layer "F.Fab")
			(hide yes)
			(effects
				(font
					(size 1.016 1.016)
					(thickness 0.1524)
				)
			)
		)
		(duplicate_pad_numbers_are_jumpers no)
		(fp_rect
			(start -0.4318 0.9525)
			(end 0.4318 -0.9525)
			(stroke
				(width 0)
				(type default)
			)
			(fill no)
			(layer "F.CrtYd")
		)
		(fp_rect
			(start -0.4318 0.9525)
			(end 0.4318 -0.9525)
			(stroke
				(width 0)
				(type default)
			)
			(fill no)
			(layer "F.Fab")
		)
		(pad "1" smd custom
			(at 0 -0.4445 90)
			(size 0.1524 0.1524)
			(layers "F.Cu" "F.Mask" "F.Paste")
			(net "P3V3_STBY")
			(options
				(clearance outline)
				(anchor circle)
			)
			(primitives
				(gr_poly
					(pts
						(arc
							(start 0.3048 -0.2032)
							(mid 0.275042 -0.275042)
							(end 0.2032 -0.3048)
						)
						(arc
							(start -0.2032 -0.3048)
							(mid -0.275042 -0.275042)
							(end -0.3048 -0.2032)
						)
						(arc
							(start -0.3048 0.2032)
							(mid -0.275042 0.275042)
							(end -0.2032 0.3048)
						)
						(arc
							(start 0.2032 0.3048)
							(mid 0.275042 0.275042)
							(end 0.3048 0.2032)
						)
					)
					(width 0)
					(fill yes)
				)
			)
		)
		(pad "2" smd custom
			(at 0 0.4445 90)
			(size 0.1524 0.1524)
			(layers "F.Cu" "F.Mask" "F.Paste")
			(net "GND")
			(options
				(clearance outline)
				(anchor circle)
			)
			(primitives
				(gr_poly
					(pts
						(arc
							(start 0.3048 -0.2032)
							(mid 0.275042 -0.275042)
							(end 0.2032 -0.3048)
						)
						(arc
							(start -0.2032 -0.3048)
							(mid -0.275042 -0.275042)
							(end -0.3048 -0.2032)
						)
						(arc
							(start -0.3048 0.2032)
							(mid -0.275042 0.275042)
							(end -0.2032 0.3048)
						)
						(arc
							(start 0.2032 0.3048)
							(mid 0.275042 0.275042)
							(end 0.3048 0.2032)
						)
					)
					(width 0)
					(fill yes)
				)
			)
		)
	)
	(footprint ""
		(layer "F.Cu")
		(at 193.6496 -120.8786)
		(property "Reference" "C267"
			(at 0 0 0)
			(layer "F.SilkS")
			(hide yes)
			(effects
				(font
					(size 1.27 1.27)
				)
			)
		)
		(property "Value" "SC1U25V3KX-GP"
			(at 0 -2.8194 0)
			(unlocked yes)
			(layer "F.Fab")
			(hide yes)
			(effects
				(font
					(size 1.016 1.016)
					(thickness 0.1524)
				)
			)
		)
		(property "Device Type" "C603H36"
			(at 0 -4.3434 0)
			(unlocked yes)
			(layer "F.Fab")
			(hide yes)
			(effects
				(font
					(size 1.016 1.016)
					(thickness 0.1524)
				)
			)
		)
		(duplicate_pad_numbers_are_jumpers no)
		(fp_line
			(start 0.508 0)
			(end -0.508 0)
			(stroke
				(width 0.2032)
				(type default)
			)
			(layer "F.SilkS")
		)
		(fp_rect
			(start -0.5842 1.3335)
			(end 0.5842 -1.3335)
			(stroke
				(width 0)
				(type default)
			)
			(fill no)
			(layer "F.CrtYd")
		)
		(fp_rect
			(start -0.5842 1.3335)
			(end 0.5842 -1.3335)
			(stroke
				(width 0)
				(type default)
			)
			(fill no)
			(layer "F.Fab")
		)
		(pad "1" smd custom
			(at 0 -0.762)
			(size 0.2159 0.2159)
			(layers "F.Cu" "F.Mask" "F.Paste")
			(net "VT235_BST")
			(options
				(clearance outline)
				(anchor circle)
			)
			(primitives
				(gr_poly
					(pts
						(arc
							(start -0.3302 -0.4318)
							(mid -0.402042 -0.402042)
							(end -0.4318 -0.3302)
						)
						(arc
							(start -0.4318 0.3302)
							(mid -0.402042 0.402042)
							(end -0.3302 0.4318)
						)
						(arc
							(start 0.3302 0.4318)
							(mid 0.402042 0.402042)
							(end 0.4318 0.3302)
						)
						(arc
							(start 0.4318 -0.3302)
							(mid 0.402042 -0.402042)
							(end 0.3302 -0.4318)
						)
					)
					(width 0)
					(fill yes)
				)
			)
		)
		(pad "2" smd custom
			(at 0 0.762)
			(size 0.2159 0.2159)
			(layers "F.Cu" "F.Mask" "F.Paste")
			(net "VT235_VX")
			(options
				(clearance outline)
				(anchor circle)
			)
			(primitives
				(gr_poly
					(pts
						(arc
							(start -0.3302 -0.4318)
							(mid -0.402042 -0.402042)
							(end -0.4318 -0.3302)
						)
						(arc
							(start -0.4318 0.3302)
							(mid -0.402042 0.402042)
							(end -0.3302 0.4318)
						)
						(arc
							(start 0.3302 0.4318)
							(mid 0.402042 0.402042)
							(end 0.4318 0.3302)
						)
						(arc
							(start 0.4318 -0.3302)
							(mid 0.402042 -0.402042)
							(end 0.3302 -0.4318)
						)
					)
					(width 0)
					(fill yes)
				)
			)
		)
	)
	(footprint ""
		(layer "F.Cu")
		(at 60.071 -160.8328 90)
		(property "Reference" "R392"
			(at 0 0 90)
			(layer "F.SilkS")
			(hide yes)
			(effects
				(font
					(size 1.27 1.27)
				)
			)
		)
		(property "Value" "4K7R2F-GP"
			(at 0.064008 -3.993896 90)
			(unlocked yes)
			(layer "F.Fab")
			(hide yes)
			(effects
				(font
					(size 1.016 1.016)
					(thickness 0.1524)
				)
			)
		)
		(property "Device Type" "R402H16"
			(at 0.064008 -5.517896 90)
			(unlocked yes)
			(layer "F.Fab")
			(hide yes)
			(effects
				(font
					(size 1.016 1.016)
					(thickness 0.1524)
				)
			)
		)
		(duplicate_pad_numbers_are_jumpers no)
		(fp_line
			(start 0.508 -0.9398)
			(end -0.508 -0.9398)
			(stroke
				(width 0.1524)
				(type default)
			)
			(layer "F.SilkS")
		)
		(fp_line
			(start -0.508 -0.9398)
			(end -0.508 0.9398)
			(stroke
				(width 0.1524)
				(type default)
			)
			(layer "F.SilkS")
		)
		(fp_rect
			(start -0.508 0.9398)
			(end 0.508 -0.9398)
			(stroke
				(width 0)
				(type default)
			)
			(fill no)
			(layer "F.CrtYd")
		)
		(fp_rect
			(start -0.508 0.9398)
			(end 0.508 -0.9398)
			(stroke
				(width 0)
				(type default)
			)
			(fill no)
			(layer "F.Fab")
		)
		(pad "1" smd custom
			(at 0 -0.4445 90)
			(size 0.1397 0.1397)
			(layers "F.Cu" "F.Mask" "F.Paste")
			(net "P3V3_STBY")
			(options
				(clearance outline)
				(anchor circle)
			)
			(primitives
				(gr_poly
					(pts
						(arc
							(start -0.1778 -0.2794)
							(mid -0.249642 -0.249642)
							(end -0.2794 -0.1778)
						)
						(arc
							(start -0.2794 0.1778)
							(mid -0.249642 0.249642)
							(end -0.1778 0.2794)
						)
						(arc
							(start 0.1778 0.2794)
							(mid 0.249642 0.249642)
							(end 0.2794 0.1778)
						)
						(arc
							(start 0.2794 -0.1778)
							(mid 0.249642 -0.249642)
							(end 0.1778 -0.2794)
						)
					)
					(width 0)
					(fill yes)
				)
			)
		)
		(pad "2" smd custom
			(at 0 0.4445 90)
			(size 0.1397 0.1397)
			(layers "F.Cu" "F.Mask" "F.Paste")
			(net "MAC2_TXD1")
			(options
				(clearance outline)
				(anchor circle)
			)
			(primitives
				(gr_poly
					(pts
						(arc
							(start -0.1778 -0.2794)
							(mid -0.249642 -0.249642)
							(end -0.2794 -0.1778)
						)
						(arc
							(start -0.2794 0.1778)
							(mid -0.249642 0.249642)
							(end -0.1778 0.2794)
						)
						(arc
							(start 0.1778 0.2794)
							(mid 0.249642 0.249642)
							(end 0.2794 0.1778)
						)
						(arc
							(start 0.2794 -0.1778)
							(mid 0.249642 -0.249642)
							(end 0.1778 -0.2794)
						)
					)
					(width 0)
					(fill yes)
				)
			)
		)
	)
	(footprint ""
		(layer "F.Cu")
		(at 66.2686 -169.1894 90)
		(property "Reference" "C38"
			(at 0 0 90)
			(layer "F.SilkS")
			(hide yes)
			(effects
				(font
					(size 1.27 1.27)
				)
			)
		)
		(property "Value" "SCD1U16V2KX-3GP"
			(at 1.1811 -2.7051 90)
			(unlocked yes)
			(layer "F.Fab")
			(hide yes)
			(effects
				(font
					(size 1.016 1.016)
					(thickness 0.1524)
				)
			)
		)
		(property "Device Type" "C402H22"
			(at 1.1811 -4.2291 90)
			(unlocked yes)
			(layer "F.Fab")
			(hide yes)
			(effects
				(font
					(size 1.016 1.016)
					(thickness 0.1524)
				)
			)
		)
		(duplicate_pad_numbers_are_jumpers no)
		(fp_rect
			(start -0.4318 0.9525)
			(end 0.4318 -0.9525)
			(stroke
				(width 0)
				(type default)
			)
			(fill no)
			(layer "F.CrtYd")
		)
		(fp_rect
			(start -0.4318 0.9525)
			(end 0.4318 -0.9525)
			(stroke
				(width 0)
				(type default)
			)
			(fill no)
			(layer "F.Fab")
		)
		(pad "1" smd custom
			(at 0 -0.4445 90)
			(size 0.1524 0.1524)
			(layers "F.Cu" "F.Mask" "F.Paste")
			(net "Q4_G")
			(options
				(clearance outline)
				(anchor circle)
			)
			(primitives
				(gr_poly
					(pts
						(arc
							(start 0.3048 -0.2032)
							(mid 0.275042 -0.275042)
							(end 0.2032 -0.3048)
						)
						(arc
							(start -0.2032 -0.3048)
							(mid -0.275042 -0.275042)
							(end -0.3048 -0.2032)
						)
						(arc
							(start -0.3048 0.2032)
							(mid -0.275042 0.275042)
							(end -0.2032 0.3048)
						)
						(arc
							(start 0.2032 0.3048)
							(mid 0.275042 0.275042)
							(end 0.3048 0.2032)
						)
					)
					(width 0)
					(fill yes)
				)
			)
		)
		(pad "2" smd custom
			(at 0 0.4445 90)
			(size 0.1524 0.1524)
			(layers "F.Cu" "F.Mask" "F.Paste")
			(net "GND")
			(options
				(clearance outline)
				(anchor circle)
			)
			(primitives
				(gr_poly
					(pts
						(arc
							(start 0.3048 -0.2032)
							(mid 0.275042 -0.275042)
							(end 0.2032 -0.3048)
						)
						(arc
							(start -0.2032 -0.3048)
							(mid -0.275042 -0.275042)
							(end -0.3048 -0.2032)
						)
						(arc
							(start -0.3048 0.2032)
							(mid -0.275042 0.275042)
							(end -0.2032 0.3048)
						)
						(arc
							(start 0.2032 0.3048)
							(mid 0.275042 0.275042)
							(end 0.3048 0.2032)
						)
					)
					(width 0)
					(fill yes)
				)
			)
		)
	)
	(footprint ""
		(layer "F.Cu")
		(at 204.533246 -132.480558)
		(property "Reference" "R546"
			(at 0 0 0)
			(layer "F.SilkS")
			(hide yes)
			(effects
				(font
					(size 1.27 1.27)
				)
			)
		)
		(property "Value" "10KR2F-2-GP"
			(at 0.064008 -3.993896 0)
			(unlocked yes)
			(layer "F.Fab")
			(hide yes)
			(effects
				(font
					(size 1.016 1.016)
					(thickness 0.1524)
				)
			)
		)
		(property "Device Type" "R402H16"
			(at 0.064008 -5.517896 0)
			(unlocked yes)
			(layer "F.Fab")
			(hide yes)
			(effects
				(font
					(size 1.016 1.016)
					(thickness 0.1524)
				)
			)
		)
		(duplicate_pad_numbers_are_jumpers no)
		(fp_line
			(start -0.508 -0.9398)
			(end -0.508 0.9398)
			(stroke
				(width 0.1524)
				(type default)
			)
			(layer "F.SilkS")
		)
		(fp_line
			(start 0.508 -0.9398)
			(end -0.508 -0.9398)
			(stroke
				(width 0.1524)
				(type default)
			)
			(layer "F.SilkS")
		)
		(fp_rect
			(start -0.508 0.9398)
			(end 0.508 -0.9398)
			(stroke
				(width 0)
				(type default)
			)
			(fill no)
			(layer "F.CrtYd")
		)
		(fp_rect
			(start -0.508 0.9398)
			(end 0.508 -0.9398)
			(stroke
				(width 0)
				(type default)
			)
			(fill no)
			(layer "F.Fab")
		)
		(pad "1" smd custom
			(at 0 -0.4445)
			(size 0.1397 0.1397)
			(layers "F.Cu" "F.Mask" "F.Paste")
			(net "P3V3_STBY")
			(options
				(clearance outline)
				(anchor circle)
			)
			(primitives
				(gr_poly
					(pts
						(arc
							(start -0.1778 -0.2794)
							(mid -0.249642 -0.249642)
							(end -0.2794 -0.1778)
						)
						(arc
							(start -0.2794 0.1778)
							(mid -0.249642 0.249642)
							(end -0.1778 0.2794)
						)
						(arc
							(start 0.1778 0.2794)
							(mid 0.249642 0.249642)
							(end 0.2794 0.1778)
						)
						(arc
							(start 0.2794 -0.1778)
							(mid 0.249642 -0.249642)
							(end 0.1778 -0.2794)
						)
					)
					(width 0)
					(fill yes)
				)
			)
		)
		(pad "2" smd custom
			(at 0 0.4445)
			(size 0.1397 0.1397)
			(layers "F.Cu" "F.Mask" "F.Paste")
			(net "PWRGD_P1V5")
			(options
				(clearance outline)
				(anchor circle)
			)
			(primitives
				(gr_poly
					(pts
						(arc
							(start -0.1778 -0.2794)
							(mid -0.249642 -0.249642)
							(end -0.2794 -0.1778)
						)
						(arc
							(start -0.2794 0.1778)
							(mid -0.249642 0.249642)
							(end -0.1778 0.2794)
						)
						(arc
							(start 0.1778 0.2794)
							(mid 0.249642 0.249642)
							(end 0.2794 0.1778)
						)
						(arc
							(start 0.2794 -0.1778)
							(mid 0.249642 -0.249642)
							(end 0.1778 -0.2794)
						)
					)
					(width 0)
					(fill yes)
				)
			)
		)
	)
	(footprint ""
		(layer "F.Cu")
		(at 167.270684 -116.032534 90)
		(property "Reference" "PQ5"
			(at 0 0 90)
			(layer "F.SilkS")
			(hide yes)
			(effects
				(font
					(size 1.27 1.27)
				)
			)
		)
		(property "Value" "FDS8878-G-GP"
			(at -3.707384 -1.5367 90)
			(unlocked yes)
			(layer "F.Fab")
			(hide yes)
			(effects
				(font
					(size 1.016 1.016)
					(thickness 0.1524)
				)
			)
		)
		(property "Device Type" "SOIC8H69"
			(at -3.707384 -3.0607 90)
			(unlocked yes)
			(layer "F.Fab")
			(hide yes)
			(effects
				(font
					(size 1.016 1.016)
					(thickness 0.1524)
				)
			)
		)
		(duplicate_pad_numbers_are_jumpers no)
		(fp_line
			(start 2.1336 -1.4224)
			(end -2.7432 -1.4224)
			(stroke
				(width 0.1524)
				(type default)
			)
			(layer "F.SilkS")
		)
		(fp_line
			(start -2.7432 -1.4224)
			(end -2.7432 1.4224)
			(stroke
				(width 0.1524)
				(type default)
			)
			(layer "F.SilkS")
		)
		(fp_line
			(start -2.7178 -0.508)
			(end -2.1844 -0.0508)
			(stroke
				(width 0.1524)
				(type default)
			)
			(layer "F.SilkS")
		)
		(fp_line
			(start -2.1844 -0.0508)
			(end -2.7178 0.508)
			(stroke
				(width 0.1524)
				(type default)
			)
			(layer "F.SilkS")
		)
		(fp_line
			(start 2.1336 1.4224)
			(end 2.1336 -1.4224)
			(stroke
				(width 0.1524)
				(type default)
			)
			(layer "F.SilkS")
		)
		(fp_line
			(start -2.7432 1.4224)
			(end 2.1336 1.4224)
			(stroke
				(width 0.1524)
				(type default)
			)
			(layer "F.SilkS")
		)
		(fp_line
			(start -2.7432 1.4224)
			(end -2.6416 1.4224)
			(stroke
				(width 0.1524)
				(type default)
			)
			(layer "F.SilkS")
		)
		(fp_line
			(start -2.6289 3.4417)
			(end -2.6289 1.4732)
			(stroke
				(width 0.381)
				(type default)
			)
			(layer "F.SilkS")
		)
		(fp_poly
			(pts
				(xy -2.2098 -1.4224) (xy -2.2098 1.4224) (xy 2.2098 1.4224) (xy 2.2098 -1.4224)
			)
			(stroke
				(width 0)
				(type default)
			)
			(fill yes)
			(layer "F.SilkS")
		)
		(fp_rect
			(start -2.450084 2.999994)
			(end 2.450084 -2.999994)
			(stroke
				(width 0)
				(type default)
			)
			(fill no)
			(layer "F.CrtYd")
		)
		(fp_poly
			(pts
				(xy -2.8194 3.6322) (xy -2.8194 -3.6322) (xy 2.8194 -3.6322) (xy 2.8194 1.18364) (xy 2.450084 1.18364)
				(xy 2.450084 -2.999994) (xy -2.450084 -2.999994) (xy -2.450084 2.999994) (xy 2.450084 2.999994)
				(xy 2.450084 1.18618) (xy 2.8194 1.18618) (xy 2.8194 3.6322)
			)
			(stroke
				(width 0)
				(type default)
			)
			(fill no)
			(layer "F.CrtYd")
		)
		(fp_rect
			(start -2.8194 3.6322)
			(end 2.8194 -3.6322)
			(stroke
				(width 0)
				(type default)
			)
			(fill no)
			(layer "F.Fab")
		)
		(pad "1" smd rect
			(at -1.905 2.54 90)
			(size 0.635 1.651)
			(layers "F.Cu" "F.Mask" "F.Paste")
			(net "P1V8")
		)
		(pad "2" smd rect
			(at -0.635 2.54 90)
			(size 0.635 1.651)
			(layers "F.Cu" "F.Mask" "F.Paste")
			(net "P1V8")
		)
		(pad "3" smd rect
			(at 0.635 2.54 90)
			(size 0.635 1.651)
			(layers "F.Cu" "F.Mask" "F.Paste")
			(net "P1V8")
		)
		(pad "4" smd rect
			(at 1.905 2.54 90)
			(size 0.635 1.651)
			(layers "F.Cu" "F.Mask" "F.Paste")
			(net "PQ4_D")
		)
		(pad "5" smd rect
			(at 1.905 -2.54 90)
			(size 0.635 1.651)
			(layers "F.Cu" "F.Mask" "F.Paste")
			(net "P1V8_STBY")
		)
		(pad "6" smd rect
			(at 0.635 -2.54 90)
			(size 0.635 1.651)
			(layers "F.Cu" "F.Mask" "F.Paste")
			(net "P1V8_STBY")
		)
		(pad "7" smd rect
			(at -0.635 -2.54 90)
			(size 0.635 1.651)
			(layers "F.Cu" "F.Mask" "F.Paste")
			(net "P1V8_STBY")
		)
		(pad "8" smd rect
			(at -1.905 -2.54 90)
			(size 0.635 1.651)
			(layers "F.Cu" "F.Mask" "F.Paste")
			(net "P1V8_STBY")
		)
	)
	(footprint ""
		(layer "F.Cu")
		(at 59.832748 -137.438384 90)
		(property "Reference" "TP74"
			(at 0 0 90)
			(layer "F.SilkS")
			(hide yes)
			(effects
				(font
					(size 1.27 1.27)
				)
			)
		)
		(property "Value" "TPAD28-2-GP"
			(at -0.0127 -1.6637 90)
			(unlocked yes)
			(layer "F.Fab")
			(hide yes)
			(effects
				(font
					(size 1.016 1.016)
					(thickness 0.1524)
				)
			)
		)
		(property "Device Type" "TPAD28"
			(at -0.0127 -3.1877 90)
			(unlocked yes)
			(layer "F.Fab")
			(hide yes)
			(effects
				(font
					(size 1.016 1.016)
					(thickness 0.1524)
				)
			)
		)
		(duplicate_pad_numbers_are_jumpers no)
		(fp_poly
			(pts
				(arc
					(start 0 0.3556)
					(mid 0 -0.3556)
					(end 0 0.3556)
				)
			)
			(stroke
				(width 0)
				(type default)
			)
			(fill no)
			(layer "F.CrtYd")
		)
		(fp_poly
			(pts
				(arc
					(start 0 0.6096)
					(mid 0 -0.6096)
					(end 0 0.6096)
				)
			)
			(stroke
				(width 0)
				(type default)
			)
			(fill no)
			(layer "F.Fab")
		)
		(pad "1" smd circle
			(at 0 0 90)
			(size 0.7112 0.7112)
			(layers "F.Cu" "F.Mask" "F.Paste")
			(net "TP_BMC_GPIOI2")
		)
	)
	(footprint ""
		(layer "F.Cu")
		(at 206.629 -81.915 -90)
		(property "Reference" "R570"
			(at 0 0 270)
			(layer "F.SilkS")
			(hide yes)
			(effects
				(font
					(size 1.27 1.27)
				)
			)
		)
		(property "Value" "51R2F-2-GP"
			(at 0.064008 -3.993896 270)
			(unlocked yes)
			(layer "F.Fab")
			(hide yes)
			(effects
				(font
					(size 1.016 1.016)
					(thickness 0.1524)
				)
			)
		)
		(property "Device Type" "R402H16"
			(at 0.064008 -5.517896 270)
			(unlocked yes)
			(layer "F.Fab")
			(hide yes)
			(effects
				(font
					(size 1.016 1.016)
					(thickness 0.1524)
				)
			)
		)
		(duplicate_pad_numbers_are_jumpers no)
		(fp_line
			(start -0.508 -0.9398)
			(end -0.508 0.9398)
			(stroke
				(width 0.1524)
				(type default)
			)
			(layer "F.SilkS")
		)
		(fp_line
			(start 0.508 -0.9398)
			(end -0.508 -0.9398)
			(stroke
				(width 0.1524)
				(type default)
			)
			(layer "F.SilkS")
		)
		(fp_rect
			(start -0.508 0.9398)
			(end 0.508 -0.9398)
			(stroke
				(width 0)
				(type default)
			)
			(fill no)
			(layer "F.CrtYd")
		)
		(fp_rect
			(start -0.508 0.9398)
			(end 0.508 -0.9398)
			(stroke
				(width 0)
				(type default)
			)
			(fill no)
			(layer "F.Fab")
		)
		(pad "1" smd custom
			(at 0 -0.4445 270)
			(size 0.1397 0.1397)
			(layers "F.Cu" "F.Mask" "F.Paste")
			(net "PCIE_COMP_TO_IOM_CLK_2_DN")
			(options
				(clearance outline)
				(anchor circle)
			)
			(primitives
				(gr_poly
					(pts
						(arc
							(start -0.1778 -0.2794)
							(mid -0.249642 -0.249642)
							(end -0.2794 -0.1778)
						)
						(arc
							(start -0.2794 0.1778)
							(mid -0.249642 0.249642)
							(end -0.1778 0.2794)
						)
						(arc
							(start 0.1778 0.2794)
							(mid 0.249642 0.249642)
							(end 0.2794 0.1778)
						)
						(arc
							(start 0.2794 -0.1778)
							(mid 0.249642 -0.249642)
							(end 0.1778 -0.2794)
						)
					)
					(width 0)
					(fill yes)
				)
			)
		)
		(pad "2" smd custom
			(at 0 0.4445 270)
			(size 0.1397 0.1397)
			(layers "F.Cu" "F.Mask" "F.Paste")
			(net "GND")
			(options
				(clearance outline)
				(anchor circle)
			)
			(primitives
				(gr_poly
					(pts
						(arc
							(start -0.1778 -0.2794)
							(mid -0.249642 -0.249642)
							(end -0.2794 -0.1778)
						)
						(arc
							(start -0.2794 0.1778)
							(mid -0.249642 0.249642)
							(end -0.1778 0.2794)
						)
						(arc
							(start 0.1778 0.2794)
							(mid 0.249642 0.249642)
							(end 0.2794 0.1778)
						)
						(arc
							(start 0.2794 -0.1778)
							(mid 0.249642 -0.249642)
							(end 0.1778 -0.2794)
						)
					)
					(width 0)
					(fill yes)
				)
			)
		)
	)
	(footprint ""
		(layer "F.Cu")
		(at 198.501 -88.773 135)
		(property "Reference" "VIA19"
			(at 0 0 135)
			(layer "F.SilkS")
			(hide yes)
			(effects
				(font
					(size 1.27 1.27)
				)
			)
		)
		(property "Value" "85OHM-8L-1D6MM-L16L18-GP"
			(at 4.064105 0.609655 135)
			(unlocked yes)
			(layer "F.Fab")
			(hide yes)
			(effects
				(font
					(size 1.016 1.016)
					(thickness 0.1524)
				)
			)
		)
		(property "Device Type" "VIA-PCIE-4P-368076"
			(at 4.064105 -0.914474 135)
			(unlocked yes)
			(layer "F.Fab")
			(hide yes)
			(effects
				(font
					(size 1.016 1.016)
					(thickness 0.1524)
				)
			)
		)
		(duplicate_pad_numbers_are_jumpers no)
		(fp_poly
			(pts
				(xy -1.841491 -0.381057) (xy 1.841509 -0.381058) (xy 1.841508 0.380942) (xy -1.841491 0.380942)
			)
			(stroke
				(width 0)
				(type default)
			)
			(fill no)
			(layer "F.CrtYd")
		)
		(fp_poly
			(pts
				(xy -1.841491 -0.381057) (xy 1.841509 -0.381058) (xy 1.841508 0.380942) (xy -1.841491 0.380942)
			)
			(stroke
				(width 0)
				(type default)
			)
			(fill no)
			(layer "F.Fab")
		)
		(pad "1" thru_hole circle
			(at -1.460499 0 135)
			(size 0.508 0.508)
			(drill 0.254)
			(layers "*.Cu" "*.Mask")
			(remove_unused_layers no)
			(net "GND")
			(clearance 0.127)
			(thermal_gap 0.127)
		)
		(pad "2" thru_hole circle
			(at -0.4445 0 135)
			(size 0.508 0.508)
			(drill 0.254)
			(layers "*.Cu" "*.Mask")
			(remove_unused_layers no)
			(net "PCIE_COMP_TO_IOM_10_DP")
			(clearance 0.127)
			(thermal_gap 0.127)
		)
		(pad "3" thru_hole circle
			(at 0.4445 0 135)
			(size 0.508 0.508)
			(drill 0.254)
			(layers "*.Cu" "*.Mask")
			(remove_unused_layers no)
			(net "PCIE_COMP_TO_IOM_10_DN")
			(clearance 0.127)
			(thermal_gap 0.127)
		)
		(pad "4" thru_hole circle
			(at 1.460499 0 135)
			(size 0.508 0.508)
			(drill 0.254)
			(layers "*.Cu" "*.Mask")
			(remove_unused_layers no)
			(net "GND")
			(clearance 0.127)
			(thermal_gap 0.127)
		)
	)
	(footprint ""
		(layer "F.Cu")
		(at 112.86109 -8.726678 -90)
		(property "Reference" "C131"
			(at 0 0 270)
			(layer "F.SilkS")
			(hide yes)
			(effects
				(font
					(size 1.27 1.27)
				)
			)
		)
		(property "Value" "SCD01U25V2KX-3GP"
			(at 1.1811 -2.7051 270)
			(unlocked yes)
			(layer "F.Fab")
			(hide yes)
			(effects
				(font
					(size 1.016 1.016)
					(thickness 0.1524)
				)
			)
		)
		(property "Device Type" "C402H22"
			(at 1.1811 -4.2291 270)
			(unlocked yes)
			(layer "F.Fab")
			(hide yes)
			(effects
				(font
					(size 1.016 1.016)
					(thickness 0.1524)
				)
			)
		)
		(duplicate_pad_numbers_are_jumpers no)
		(fp_rect
			(start -0.4318 0.9525)
			(end 0.4318 -0.9525)
			(stroke
				(width 0)
				(type default)
			)
			(fill no)
			(layer "F.CrtYd")
		)
		(fp_rect
			(start -0.4318 0.9525)
			(end 0.4318 -0.9525)
			(stroke
				(width 0)
				(type default)
			)
			(fill no)
			(layer "F.Fab")
		)
		(pad "1" smd custom
			(at 0 -0.4445 270)
			(size 0.1524 0.1524)
			(layers "F.Cu" "F.Mask" "F.Paste")
			(net "MB0_TIME_R")
			(options
				(clearance outline)
				(anchor circle)
			)
			(primitives
				(gr_poly
					(pts
						(arc
							(start 0.3048 -0.2032)
							(mid 0.275042 -0.275042)
							(end 0.2032 -0.3048)
						)
						(arc
							(start -0.2032 -0.3048)
							(mid -0.275042 -0.275042)
							(end -0.3048 -0.2032)
						)
						(arc
							(start -0.3048 0.2032)
							(mid -0.275042 0.275042)
							(end -0.2032 0.3048)
						)
						(arc
							(start 0.2032 0.3048)
							(mid 0.275042 0.275042)
							(end 0.3048 0.2032)
						)
					)
					(width 0)
					(fill yes)
				)
			)
		)
		(pad "2" smd custom
			(at 0 0.4445 270)
			(size 0.1524 0.1524)
			(layers "F.Cu" "F.Mask" "F.Paste")
			(net "AGND_CURRENT_MON")
			(options
				(clearance outline)
				(anchor circle)
			)
			(primitives
				(gr_poly
					(pts
						(arc
							(start 0.3048 -0.2032)
							(mid 0.275042 -0.275042)
							(end 0.2032 -0.3048)
						)
						(arc
							(start -0.2032 -0.3048)
							(mid -0.275042 -0.275042)
							(end -0.3048 -0.2032)
						)
						(arc
							(start -0.3048 0.2032)
							(mid -0.275042 0.275042)
							(end -0.2032 0.3048)
						)
						(arc
							(start 0.2032 0.3048)
							(mid 0.275042 0.275042)
							(end 0.3048 0.2032)
						)
					)
					(width 0)
					(fill yes)
				)
			)
		)
	)
	(footprint ""
		(layer "F.Cu")
		(at 202.8698 -49.9618)
		(property "Reference" "TP141"
			(at 0 0 0)
			(layer "F.SilkS")
			(hide yes)
			(effects
				(font
					(size 1.27 1.27)
				)
			)
		)
		(property "Value" "TPAD28-2-GP"
			(at -0.0127 -1.6637 0)
			(unlocked yes)
			(layer "F.Fab")
			(hide yes)
			(effects
				(font
					(size 1.016 1.016)
					(thickness 0.1524)
				)
			)
		)
		(property "Device Type" "TPAD28"
			(at -0.0127 -3.1877 0)
			(unlocked yes)
			(layer "F.Fab")
			(hide yes)
			(effects
				(font
					(size 1.016 1.016)
					(thickness 0.1524)
				)
			)
		)
		(duplicate_pad_numbers_are_jumpers no)
		(fp_poly
			(pts
				(arc
					(start 0.3556 0)
					(mid -0.3556 0)
					(end 0.3556 0)
				)
			)
			(stroke
				(width 0)
				(type default)
			)
			(fill no)
			(layer "F.CrtYd")
		)
		(fp_poly
			(pts
				(arc
					(start 0.6096 0)
					(mid -0.6096 0)
					(end 0.6096 0)
				)
			)
			(stroke
				(width 0)
				(type default)
			)
			(fill no)
			(layer "F.Fab")
		)
		(pad "1" smd circle
			(at 0 0)
			(size 0.7112 0.7112)
			(layers "F.Cu" "F.Mask" "F.Paste")
			(net "ICE1_TMS")
		)
	)
	(footprint ""
		(layer "F.Cu")
		(at 184.1754 -118.0338 90)
		(property "Reference" "C270"
			(at 0 0 90)
			(layer "F.SilkS")
			(hide yes)
			(effects
				(font
					(size 1.27 1.27)
				)
			)
		)
		(property "Value" "SC10U16V5KX-7-GP-U"
			(at -0.0762 -6.1214 90)
			(unlocked yes)
			(layer "F.Fab")
			(hide yes)
			(effects
				(font
					(size 1.016 1.016)
					(thickness 0.1524)
				)
			)
		)
		(property "Device Type" "C805H58"
			(at -0.0762 -8.1534 90)
			(unlocked yes)
			(layer "F.Fab")
			(hide yes)
			(effects
				(font
					(size 1.016 1.016)
					(thickness 0.1524)
				)
			)
		)
		(duplicate_pad_numbers_are_jumpers no)
		(fp_line
			(start 0.635 0)
			(end -0.635 0)
			(stroke
				(width 0.508)
				(type default)
			)
			(layer "F.SilkS")
		)
		(fp_rect
			(start -0.9652 1.778)
			(end 0.9652 -1.778)
			(stroke
				(width 0)
				(type default)
			)
			(fill no)
			(layer "F.CrtYd")
		)
		(fp_poly
			(pts
				(xy -0.9652 -1.778) (xy 0.9652 -1.778) (xy 0.9652 1.778) (xy -0.9652 1.778)
			)
			(stroke
				(width 0)
				(type default)
			)
			(fill no)
			(layer "F.Fab")
		)
		(pad "1" smd rect
			(at 0 -0.9652 90)
			(size 1.397 1.143)
			(layers "F.Cu" "F.Mask" "F.Paste")
			(net "VT235_VDDH")
		)
		(pad "2" smd rect
			(at 0 0.9652 90)
			(size 1.397 1.143)
			(layers "F.Cu" "F.Mask" "F.Paste")
			(net "GND")
		)
	)
	(footprint ""
		(layer "F.Cu")
		(at 227.925376 -76.972414)
		(property "Reference" "Q14"
			(at 0 0 0)
			(layer "F.SilkS")
			(hide yes)
			(effects
				(font
					(size 1.27 1.27)
				)
			)
		)
		(property "Value" "SSM3K324R-GP"
			(at 0.127 -8.9662 0)
			(unlocked yes)
			(layer "F.Fab")
			(hide yes)
			(effects
				(font
					(size 1.016 1.016)
					(thickness 0.1524)
				)
			)
		)
		(property "Device Type" "SOT23DGS2D4H35"
			(at 0.127 -10.4902 0)
			(unlocked yes)
			(layer "F.Fab")
			(hide yes)
			(effects
				(font
					(size 1.016 1.016)
					(thickness 0.1524)
				)
			)
		)
		(duplicate_pad_numbers_are_jumpers no)
		(fp_line
			(start -1.651 -1.778)
			(end -1.651 1.778)
			(stroke
				(width 0.1524)
				(type default)
			)
			(layer "F.SilkS")
		)
		(fp_line
			(start -1.651 1.778)
			(end 1.651 1.778)
			(stroke
				(width 0.1524)
				(type default)
			)
			(layer "F.SilkS")
		)
		(fp_line
			(start 1.651 -1.778)
			(end -1.651 -1.778)
			(stroke
				(width 0.1524)
				(type default)
			)
			(layer "F.SilkS")
		)
		(fp_line
			(start 1.651 1.778)
			(end 1.651 -1.778)
			(stroke
				(width 0.1524)
				(type default)
			)
			(layer "F.SilkS")
		)
		(fp_poly
			(pts
				(xy -1.778 1.8796) (xy -1.778 -1.8796) (xy 1.778 -1.8796) (xy 1.778 1.8796)
			)
			(stroke
				(width 0)
				(type default)
			)
			(fill no)
			(layer "F.CrtYd")
		)
		(fp_poly
			(pts
				(xy -1.778 1.8796) (xy -1.778 -1.8796) (xy 1.778 -1.8796) (xy 1.778 1.8796)
			)
			(stroke
				(width 0)
				(type default)
			)
			(fill no)
			(layer "F.Fab")
		)
		(pad "D" smd custom
			(at 0 -0.9525)
			(size 0.1905 0.1905)
			(layers "F.Cu" "F.Mask" "F.Paste")
			(net "SYS_ERROR_LED_D")
			(options
				(clearance outline)
				(anchor circle)
			)
			(primitives
				(gr_poly
					(pts
						(arc
							(start -0.1778 0.5715)
							(mid -0.321484 0.511984)
							(end -0.381 0.3683)
						)
						(arc
							(start -0.381 -0.3683)
							(mid -0.321484 -0.511984)
							(end -0.1778 -0.5715)
						)
						(arc
							(start 0.1778 -0.5715)
							(mid 0.321484 -0.511984)
							(end 0.381 -0.3683)
						)
						(arc
							(start 0.381 0.3683)
							(mid 0.321484 0.511984)
							(end 0.1778 0.5715)
						)
					)
					(width 0)
					(fill yes)
				)
			)
		)
		(pad "G" smd custom
			(at -0.98425 0.9525)
			(size 0.1905 0.1905)
			(layers "F.Cu" "F.Mask" "F.Paste")
			(net "SYS_ERR_0")
			(options
				(clearance outline)
				(anchor circle)
			)
			(primitives
				(gr_poly
					(pts
						(arc
							(start -0.1778 0.5715)
							(mid -0.321484 0.511984)
							(end -0.381 0.3683)
						)
						(arc
							(start -0.381 -0.3683)
							(mid -0.321484 -0.511984)
							(end -0.1778 -0.5715)
						)
						(arc
							(start 0.1778 -0.5715)
							(mid 0.321484 -0.511984)
							(end 0.381 -0.3683)
						)
						(arc
							(start 0.381 0.3683)
							(mid 0.321484 0.511984)
							(end 0.1778 0.5715)
						)
					)
					(width 0)
					(fill yes)
				)
			)
		)
		(pad "S" smd custom
			(at 0.98425 0.9525)
			(size 0.1905 0.1905)
			(layers "F.Cu" "F.Mask" "F.Paste")
			(net "GND")
			(options
				(clearance outline)
				(anchor circle)
			)
			(primitives
				(gr_poly
					(pts
						(arc
							(start -0.1778 0.5715)
							(mid -0.321484 0.511984)
							(end -0.381 0.3683)
						)
						(arc
							(start -0.381 -0.3683)
							(mid -0.321484 -0.511984)
							(end -0.1778 -0.5715)
						)
						(arc
							(start 0.1778 -0.5715)
							(mid 0.321484 -0.511984)
							(end 0.381 -0.3683)
						)
						(arc
							(start 0.381 0.3683)
							(mid 0.321484 0.511984)
							(end 0.1778 0.5715)
						)
					)
					(width 0)
					(fill yes)
				)
			)
		)
	)
	(footprint ""
		(layer "F.Cu")
		(at 181.2036 -80.4672)
		(property "Reference" "TP105"
			(at 0 0 0)
			(layer "F.SilkS")
			(hide yes)
			(effects
				(font
					(size 1.27 1.27)
				)
			)
		)
		(property "Value" "TPAD28-2-GP"
			(at -0.0127 -1.6637 0)
			(unlocked yes)
			(layer "F.Fab")
			(hide yes)
			(effects
				(font
					(size 1.016 1.016)
					(thickness 0.1524)
				)
			)
		)
		(property "Device Type" "TPAD28"
			(at -0.0127 -3.1877 0)
			(unlocked yes)
			(layer "F.Fab")
			(hide yes)
			(effects
				(font
					(size 1.016 1.016)
					(thickness 0.1524)
				)
			)
		)
		(duplicate_pad_numbers_are_jumpers no)
		(fp_poly
			(pts
				(arc
					(start 0.3556 0)
					(mid -0.3556 0)
					(end 0.3556 0)
				)
			)
			(stroke
				(width 0)
				(type default)
			)
			(fill no)
			(layer "F.CrtYd")
		)
		(fp_poly
			(pts
				(arc
					(start 0.6096 0)
					(mid -0.6096 0)
					(end 0.6096 0)
				)
			)
			(stroke
				(width 0)
				(type default)
			)
			(fill no)
			(layer "F.Fab")
		)
		(pad "1" smd circle
			(at 0 0)
			(size 0.7112 0.7112)
			(layers "F.Cu" "F.Mask" "F.Paste")
			(net "IOC_GPIO_20")
		)
	)
	(footprint ""
		(layer "F.Cu")
		(at 92.499942 -187.999878)
		(property "Reference" ""
			(at 0 0 0)
			(layer "F.SilkS")
			(hide yes)
			(effects
				(font
					(size 1.27 1.27)
				)
			)
		)
		(property "Value" "*"
			(at -6.38175 0.19685 0)
			(unlocked yes)
			(layer "F.Fab")
			(hide yes)
			(effects
				(font
					(size 1.016 1.016)
					(thickness 0.1524)
				)
			)
		)
		(duplicate_pad_numbers_are_jumpers no)
		(fp_poly
			(pts
				(arc
					(start 5.0673 0)
					(mid -5.0673 0)
					(end 5.0673 0)
				)
			)
			(stroke
				(width 0)
				(type default)
			)
			(fill no)
			(layer "B.CrtYd")
		)
		(fp_poly
			(pts
				(arc
					(start 5.0673 0)
					(mid -5.0673 0)
					(end 5.0673 0)
				)
			)
			(stroke
				(width 0)
				(type default)
			)
			(fill no)
			(layer "F.CrtYd")
		)
		(fp_poly
			(pts
				(arc
					(start 5.0673 0)
					(mid -5.0673 0)
					(end 5.0673 0)
				)
			)
			(stroke
				(width 0)
				(type default)
			)
			(fill no)
			(layer "B.Fab")
		)
		(fp_poly
			(pts
				(arc
					(start 5.0673 0)
					(mid -5.0673 0)
					(end 5.0673 0)
				)
			)
			(stroke
				(width 0)
				(type default)
			)
			(fill no)
			(layer "F.Fab")
		)
		(pad "1" thru_hole circle
			(at 0 0)
			(size 9.525 9.525)
			(drill 3.5052)
			(layers "*.Cu" "*.Mask")
			(remove_unused_layers no)
			(net "Net_8")
			(clearance -2.5019)
			(thermal_gap 0.3048)
			(padstack
				(mode front_inner_back)
				(layer "Inner"
					(shape circle)
					(size 3.9116 3.9116)
					(clearance 0.3048)
				)
				(layer "B.Cu"
					(shape circle)
					(size 9.525 9.525)
					(clearance -2.5019)
				)
			)
		)
	)
	(footprint ""
		(layer "F.Cu")
		(at 199.2376 -25.654)
		(property "Reference" "R695"
			(at 0 0 0)
			(layer "F.SilkS")
			(hide yes)
			(effects
				(font
					(size 1.27 1.27)
				)
			)
		)
		(property "Value" "1KR2F-3-GP"
			(at 0.064008 -3.993896 0)
			(unlocked yes)
			(layer "F.Fab")
			(hide yes)
			(effects
				(font
					(size 1.016 1.016)
					(thickness 0.1524)
				)
			)
		)
		(property "Device Type" "R402H16"
			(at 0.064008 -5.517896 0)
			(unlocked yes)
			(layer "F.Fab")
			(hide yes)
			(effects
				(font
					(size 1.016 1.016)
					(thickness 0.1524)
				)
			)
		)
		(duplicate_pad_numbers_are_jumpers no)
		(fp_line
			(start -0.508 -0.9398)
			(end -0.508 0.9398)
			(stroke
				(width 0.1524)
				(type default)
			)
			(layer "F.SilkS")
		)
		(fp_line
			(start 0.508 -0.9398)
			(end -0.508 -0.9398)
			(stroke
				(width 0.1524)
				(type default)
			)
			(layer "F.SilkS")
		)
		(fp_rect
			(start -0.508 0.9398)
			(end 0.508 -0.9398)
			(stroke
				(width 0)
				(type default)
			)
			(fill no)
			(layer "F.CrtYd")
		)
		(fp_rect
			(start -0.508 0.9398)
			(end 0.508 -0.9398)
			(stroke
				(width 0)
				(type default)
			)
			(fill no)
			(layer "F.Fab")
		)
		(pad "1" smd custom
			(at 0 -0.4445)
			(size 0.1397 0.1397)
			(layers "F.Cu" "F.Mask" "F.Paste")
			(net "P5V_STBY")
			(options
				(clearance outline)
				(anchor circle)
			)
			(primitives
				(gr_poly
					(pts
						(arc
							(start -0.1778 -0.2794)
							(mid -0.249642 -0.249642)
							(end -0.2794 -0.1778)
						)
						(arc
							(start -0.2794 0.1778)
							(mid -0.249642 0.249642)
							(end -0.1778 0.2794)
						)
						(arc
							(start 0.1778 0.2794)
							(mid 0.249642 0.249642)
							(end 0.2794 0.1778)
						)
						(arc
							(start 0.2794 -0.1778)
							(mid 0.249642 -0.249642)
							(end 0.1778 -0.2794)
						)
					)
					(width 0)
					(fill yes)
				)
			)
		)
		(pad "2" smd custom
			(at 0 0.4445)
			(size 0.1397 0.1397)
			(layers "F.Cu" "F.Mask" "F.Paste")
			(net "EXT1_LED_BLUE_G2")
			(options
				(clearance outline)
				(anchor circle)
			)
			(primitives
				(gr_poly
					(pts
						(arc
							(start -0.1778 -0.2794)
							(mid -0.249642 -0.249642)
							(end -0.2794 -0.1778)
						)
						(arc
							(start -0.2794 0.1778)
							(mid -0.249642 0.249642)
							(end -0.1778 0.2794)
						)
						(arc
							(start 0.1778 0.2794)
							(mid 0.249642 0.249642)
							(end 0.2794 0.1778)
						)
						(arc
							(start 0.2794 -0.1778)
							(mid 0.249642 -0.249642)
							(end 0.1778 -0.2794)
						)
					)
					(width 0)
					(fill yes)
				)
			)
		)
	)
	(footprint ""
		(layer "F.Cu")
		(at 181.95163 -154.96286 180)
		(property "Reference" "R713"
			(at 0 0 180)
			(layer "F.SilkS")
			(hide yes)
			(effects
				(font
					(size 1.27 1.27)
				)
			)
		)
		(property "Value" "0R2J-2-GP"
			(at 0.064008 -3.993896 180)
			(unlocked yes)
			(layer "F.Fab")
			(hide yes)
			(effects
				(font
					(size 1.016 1.016)
					(thickness 0.1524)
				)
			)
		)
		(property "Device Type" "R402H16"
			(at 0.064008 -5.517896 180)
			(unlocked yes)
			(layer "F.Fab")
			(hide yes)
			(effects
				(font
					(size 1.016 1.016)
					(thickness 0.1524)
				)
			)
		)
		(duplicate_pad_numbers_are_jumpers no)
		(fp_line
			(start 0.508 -0.9398)
			(end -0.508 -0.9398)
			(stroke
				(width 0.1524)
				(type default)
			)
			(layer "F.SilkS")
		)
		(fp_line
			(start -0.508 -0.9398)
			(end -0.508 0.9398)
			(stroke
				(width 0.1524)
				(type default)
			)
			(layer "F.SilkS")
		)
		(fp_rect
			(start -0.508 0.9398)
			(end 0.508 -0.9398)
			(stroke
				(width 0)
				(type default)
			)
			(fill no)
			(layer "F.CrtYd")
		)
		(fp_rect
			(start -0.508 0.9398)
			(end 0.508 -0.9398)
			(stroke
				(width 0)
				(type default)
			)
			(fill no)
			(layer "F.Fab")
		)
		(pad "1" smd custom
			(at 0 -0.4445 180)
			(size 0.1397 0.1397)
			(layers "F.Cu" "F.Mask" "F.Paste")
			(net "P5V_EN_R")
			(options
				(clearance outline)
				(anchor circle)
			)
			(primitives
				(gr_poly
					(pts
						(arc
							(start -0.1778 -0.2794)
							(mid -0.249642 -0.249642)
							(end -0.2794 -0.1778)
						)
						(arc
							(start -0.2794 0.1778)
							(mid -0.249642 0.249642)
							(end -0.1778 0.2794)
						)
						(arc
							(start 0.1778 0.2794)
							(mid 0.249642 0.249642)
							(end 0.2794 0.1778)
						)
						(arc
							(start 0.2794 -0.1778)
							(mid 0.249642 -0.249642)
							(end 0.1778 -0.2794)
						)
					)
					(width 0)
					(fill yes)
				)
			)
		)
		(pad "2" smd custom
			(at 0 0.4445 180)
			(size 0.1397 0.1397)
			(layers "F.Cu" "F.Mask" "F.Paste")
			(net "P12V_IOM_PGOOD")
			(options
				(clearance outline)
				(anchor circle)
			)
			(primitives
				(gr_poly
					(pts
						(arc
							(start -0.1778 -0.2794)
							(mid -0.249642 -0.249642)
							(end -0.2794 -0.1778)
						)
						(arc
							(start -0.2794 0.1778)
							(mid -0.249642 0.249642)
							(end -0.1778 0.2794)
						)
						(arc
							(start 0.1778 0.2794)
							(mid 0.249642 0.249642)
							(end 0.2794 0.1778)
						)
						(arc
							(start 0.2794 -0.1778)
							(mid 0.249642 -0.249642)
							(end 0.1778 -0.2794)
						)
					)
					(width 0)
					(fill yes)
				)
			)
		)
	)
	(footprint ""
		(layer "F.Cu")
		(at 68.8086 -170.7642 180)
		(property "Reference" "R332"
			(at 0 0 180)
			(layer "F.SilkS")
			(hide yes)
			(effects
				(font
					(size 1.27 1.27)
				)
			)
		)
		(property "Value" "4K7R2F-GP"
			(at 0.064008 -3.993896 180)
			(unlocked yes)
			(layer "F.Fab")
			(hide yes)
			(effects
				(font
					(size 1.016 1.016)
					(thickness 0.1524)
				)
			)
		)
		(property "Device Type" "R402H16"
			(at 0.064008 -5.517896 180)
			(unlocked yes)
			(layer "F.Fab")
			(hide yes)
			(effects
				(font
					(size 1.016 1.016)
					(thickness 0.1524)
				)
			)
		)
		(duplicate_pad_numbers_are_jumpers no)
		(fp_line
			(start 0.508 -0.9398)
			(end -0.508 -0.9398)
			(stroke
				(width 0.1524)
				(type default)
			)
			(layer "F.SilkS")
		)
		(fp_line
			(start -0.508 -0.9398)
			(end -0.508 0.9398)
			(stroke
				(width 0.1524)
				(type default)
			)
			(layer "F.SilkS")
		)
		(fp_rect
			(start -0.508 0.9398)
			(end 0.508 -0.9398)
			(stroke
				(width 0)
				(type default)
			)
			(fill no)
			(layer "F.CrtYd")
		)
		(fp_rect
			(start -0.508 0.9398)
			(end 0.508 -0.9398)
			(stroke
				(width 0)
				(type default)
			)
			(fill no)
			(layer "F.Fab")
		)
		(pad "1" smd custom
			(at 0 -0.4445 180)
			(size 0.1397 0.1397)
			(layers "F.Cu" "F.Mask" "F.Paste")
			(net "P3V3_STBY")
			(options
				(clearance outline)
				(anchor circle)
			)
			(primitives
				(gr_poly
					(pts
						(arc
							(start -0.1778 -0.2794)
							(mid -0.249642 -0.249642)
							(end -0.2794 -0.1778)
						)
						(arc
							(start -0.2794 0.1778)
							(mid -0.249642 0.249642)
							(end -0.1778 0.2794)
						)
						(arc
							(start 0.1778 0.2794)
							(mid 0.249642 0.249642)
							(end 0.2794 0.1778)
						)
						(arc
							(start 0.2794 -0.1778)
							(mid 0.249642 -0.249642)
							(end 0.1778 -0.2794)
						)
					)
					(width 0)
					(fill yes)
				)
			)
		)
		(pad "2" smd custom
			(at 0 0.4445 180)
			(size 0.1397 0.1397)
			(layers "F.Cu" "F.Mask" "F.Paste")
			(net "COMP_TO_BMC_RESET_N_OUT")
			(options
				(clearance outline)
				(anchor circle)
			)
			(primitives
				(gr_poly
					(pts
						(arc
							(start -0.1778 -0.2794)
							(mid -0.249642 -0.249642)
							(end -0.2794 -0.1778)
						)
						(arc
							(start -0.2794 0.1778)
							(mid -0.249642 0.249642)
							(end -0.1778 0.2794)
						)
						(arc
							(start 0.1778 0.2794)
							(mid 0.249642 0.249642)
							(end 0.2794 0.1778)
						)
						(arc
							(start 0.2794 -0.1778)
							(mid 0.249642 -0.249642)
							(end 0.1778 -0.2794)
						)
					)
					(width 0)
					(fill yes)
				)
			)
		)
	)
	(footprint ""
		(layer "F.Cu")
		(at 87.619332 -27.578812 180)
		(property "Reference" "D13"
			(at 0 0 180)
			(layer "F.SilkS")
			(hide yes)
			(effects
				(font
					(size 1.27 1.27)
				)
			)
		)
		(property "Value" "PESD5V0S1BL-1-GP"
			(at 1.8923 -1.5621 180)
			(unlocked yes)
			(layer "F.Fab")
			(hide yes)
			(effects
				(font
					(size 1.016 1.016)
					(thickness 0.1524)
				)
			)
		)
		(property "Device Type" "SOD882-10D6-1H20"
			(at 1.8923 -3.0861 180)
			(unlocked yes)
			(layer "F.Fab")
			(hide yes)
			(effects
				(font
					(size 1.016 1.016)
					(thickness 0.1524)
				)
			)
		)
		(duplicate_pad_numbers_are_jumpers no)
		(fp_line
			(start -0.3048 -0.9271)
			(end 0.3048 -0.9271)
			(stroke
				(width 0.254)
				(type default)
			)
			(layer "F.SilkS")
		)
		(fp_rect
			(start -0.2921 0.4953)
			(end 0.2921 -0.4953)
			(stroke
				(width 0)
				(type default)
			)
			(fill no)
			(layer "F.CrtYd")
		)
		(fp_poly
			(pts
				(xy -0.4318 0.8001) (xy -0.4318 -0.266192) (xy -0.2921 -0.266192) (xy -0.2921 0.4953) (xy 0.2921 0.4953)
				(xy 0.2921 -0.4953) (xy -0.2921 -0.4953) (xy -0.2921 -0.2667) (xy -0.4318 -0.2667) (xy -0.4318 -0.8001)
				(xy 0.4318 -0.8001) (xy 0.4318 0.8001)
			)
			(stroke
				(width 0)
				(type default)
			)
			(fill no)
			(layer "F.CrtYd")
		)
		(fp_rect
			(start -0.4318 0.8001)
			(end 0.4318 -0.8001)
			(stroke
				(width 0)
				(type default)
			)
			(fill no)
			(layer "F.Fab")
		)
		(pad "1" smd custom
			(at 0 -0.4445 180)
			(size 0.1143 0.1143)
			(layers "F.Cu" "F.Mask" "F.Paste")
			(net "P5V_VBUS_CONN")
			(options
				(clearance outline)
				(anchor circle)
			)
			(primitives
				(gr_poly
					(pts
						(arc
							(start -0.2032 0.2286)
							(mid -0.275042 0.198842)
							(end -0.3048 0.127)
						)
						(arc
							(start -0.3048 -0.127)
							(mid -0.275042 -0.198842)
							(end -0.2032 -0.2286)
						)
						(arc
							(start 0.2032 -0.2286)
							(mid 0.275042 -0.198842)
							(end 0.3048 -0.127)
						)
						(arc
							(start 0.3048 0.127)
							(mid 0.275042 0.198842)
							(end 0.2032 0.2286)
						)
					)
					(width 0)
					(fill yes)
				)
			)
		)
		(pad "2" smd custom
			(at 0 0.4445 180)
			(size 0.1143 0.1143)
			(layers "F.Cu" "F.Mask" "F.Paste")
			(net "GND")
			(options
				(clearance outline)
				(anchor circle)
			)
			(primitives
				(gr_poly
					(pts
						(arc
							(start 0.2032 -0.2286)
							(mid 0.275042 -0.198842)
							(end 0.3048 -0.127)
						)
						(arc
							(start 0.3048 0.127)
							(mid 0.275042 0.198842)
							(end 0.2032 0.2286)
						)
						(arc
							(start -0.2032 0.2286)
							(mid -0.275042 0.198842)
							(end -0.3048 0.127)
						)
						(arc
							(start -0.3048 -0.127)
							(mid -0.275042 -0.198842)
							(end -0.2032 -0.2286)
						)
					)
					(width 0)
					(fill yes)
				)
			)
		)
	)
	(footprint ""
		(layer "F.Cu")
		(at 208.055972 -75.0316 90)
		(property "Reference" "C309"
			(at 0 0 90)
			(layer "F.SilkS")
			(hide yes)
			(effects
				(font
					(size 1.27 1.27)
				)
			)
		)
		(property "Value" "SCD01U16V1KX-GP"
			(at -2.8321 -1.7399 90)
			(unlocked yes)
			(layer "F.Fab")
			(hide yes)
			(effects
				(font
					(size 1.016 1.016)
					(thickness 0.1524)
				)
			)
		)
		(property "Device Type" "C0201H13"
			(at -2.8321 -3.2639 90)
			(unlocked yes)
			(layer "F.Fab")
			(hide yes)
			(effects
				(font
					(size 1.016 1.016)
					(thickness 0.1524)
				)
			)
		)
		(duplicate_pad_numbers_are_jumpers no)
		(fp_rect
			(start -0.2794 0.6477)
			(end 0.2794 -0.6477)
			(stroke
				(width 0)
				(type default)
			)
			(fill no)
			(layer "F.CrtYd")
		)
		(fp_rect
			(start -0.2794 0.6477)
			(end 0.2794 -0.6477)
			(stroke
				(width 0)
				(type default)
			)
			(fill no)
			(layer "F.Fab")
		)
		(pad "1" smd custom
			(at 0 -0.2794 90)
			(size 0.0762 0.0762)
			(layers "F.Cu" "F.Mask" "F.Paste")
			(net "PHY_IOC_TO_CON_A_1_DP_C")
			(options
				(clearance outline)
				(anchor circle)
			)
			(primitives
				(gr_poly
					(pts
						(arc
							(start 0.1524 -0.127)
							(mid 0.137521 -0.162921)
							(end 0.1016 -0.1778)
						)
						(arc
							(start -0.1016 -0.1778)
							(mid -0.137521 -0.162921)
							(end -0.1524 -0.127)
						)
						(arc
							(start -0.1524 0.127)
							(mid -0.137521 0.162921)
							(end -0.1016 0.1778)
						)
						(arc
							(start 0.1016 0.1778)
							(mid 0.137521 0.162921)
							(end 0.1524 0.127)
						)
					)
					(width 0)
					(fill yes)
				)
			)
		)
		(pad "2" smd custom
			(at 0 0.2794 90)
			(size 0.0762 0.0762)
			(layers "F.Cu" "F.Mask" "F.Paste")
			(net "PHY_IOC_TO_CON_A_1_DP")
			(options
				(clearance outline)
				(anchor circle)
			)
			(primitives
				(gr_poly
					(pts
						(arc
							(start 0.1524 -0.127)
							(mid 0.137521 -0.162921)
							(end 0.1016 -0.1778)
						)
						(arc
							(start -0.1016 -0.1778)
							(mid -0.137521 -0.162921)
							(end -0.1524 -0.127)
						)
						(arc
							(start -0.1524 0.127)
							(mid -0.137521 0.162921)
							(end -0.1016 0.1778)
						)
						(arc
							(start 0.1016 0.1778)
							(mid 0.137521 0.162921)
							(end 0.1524 0.127)
						)
					)
					(width 0)
					(fill yes)
				)
			)
		)
	)
	(footprint ""
		(layer "F.Cu")
		(at 133.9088 -13.6144 -90)
		(property "Reference" "R442"
			(at 0 0 270)
			(layer "F.SilkS")
			(hide yes)
			(effects
				(font
					(size 1.27 1.27)
				)
			)
		)
		(property "Value" "10R2F-L-GP"
			(at 0.064008 -3.993896 270)
			(unlocked yes)
			(layer "F.Fab")
			(hide yes)
			(effects
				(font
					(size 1.016 1.016)
					(thickness 0.1524)
				)
			)
		)
		(property "Device Type" "R402H14"
			(at 0.064008 -5.517896 270)
			(unlocked yes)
			(layer "F.Fab")
			(hide yes)
			(effects
				(font
					(size 1.016 1.016)
					(thickness 0.1524)
				)
			)
		)
		(duplicate_pad_numbers_are_jumpers no)
		(fp_line
			(start -0.508 -0.9398)
			(end -0.508 0.9398)
			(stroke
				(width 0.1524)
				(type default)
			)
			(layer "F.SilkS")
		)
		(fp_line
			(start 0.508 -0.9398)
			(end -0.508 -0.9398)
			(stroke
				(width 0.1524)
				(type default)
			)
			(layer "F.SilkS")
		)
		(fp_rect
			(start -0.508 0.9398)
			(end 0.508 -0.9398)
			(stroke
				(width 0)
				(type default)
			)
			(fill no)
			(layer "F.CrtYd")
		)
		(fp_rect
			(start -0.508 0.9398)
			(end 0.508 -0.9398)
			(stroke
				(width 0)
				(type default)
			)
			(fill no)
			(layer "F.Fab")
		)
		(pad "1" smd custom
			(at 0 -0.4445 270)
			(size 0.1397 0.1397)
			(layers "F.Cu" "F.Mask" "F.Paste")
			(net "MB0_CM_SENSE_R1_P")
			(options
				(clearance outline)
				(anchor circle)
			)
			(primitives
				(gr_poly
					(pts
						(arc
							(start -0.1778 -0.2794)
							(mid -0.249642 -0.249642)
							(end -0.2794 -0.1778)
						)
						(arc
							(start -0.2794 0.1778)
							(mid -0.249642 0.249642)
							(end -0.1778 0.2794)
						)
						(arc
							(start 0.1778 0.2794)
							(mid 0.249642 0.249642)
							(end 0.2794 0.1778)
						)
						(arc
							(start 0.2794 -0.1778)
							(mid 0.249642 -0.249642)
							(end 0.1778 -0.2794)
						)
					)
					(width 0)
					(fill yes)
				)
			)
		)
		(pad "2" smd custom
			(at 0 0.4445 270)
			(size 0.1397 0.1397)
			(layers "F.Cu" "F.Mask" "F.Paste")
			(net "ADM1278_HS_P")
			(options
				(clearance outline)
				(anchor circle)
			)
			(primitives
				(gr_poly
					(pts
						(arc
							(start -0.1778 -0.2794)
							(mid -0.249642 -0.249642)
							(end -0.2794 -0.1778)
						)
						(arc
							(start -0.2794 0.1778)
							(mid -0.249642 0.249642)
							(end -0.1778 0.2794)
						)
						(arc
							(start 0.1778 0.2794)
							(mid 0.249642 0.249642)
							(end 0.2794 0.1778)
						)
						(arc
							(start 0.2794 -0.1778)
							(mid 0.249642 -0.249642)
							(end 0.1778 -0.2794)
						)
					)
					(width 0)
					(fill yes)
				)
			)
		)
	)
	(footprint ""
		(layer "F.Cu")
		(at 168.6306 -107.1118 -90)
		(property "Reference" "C464"
			(at 0 0 270)
			(layer "F.SilkS")
			(hide yes)
			(effects
				(font
					(size 1.27 1.27)
				)
			)
		)
		(property "Value" "SC1U16V2KX-7-GP"
			(at 1.7526 -1.6002 270)
			(unlocked yes)
			(layer "F.Fab")
			(hide yes)
			(effects
				(font
					(size 1.016 1.016)
					(thickness 0.1524)
				)
			)
		)
		(property "Device Type" "C402-TO0D2H24"
			(at 1.7526 -3.1242 270)
			(unlocked yes)
			(layer "F.Fab")
			(hide yes)
			(effects
				(font
					(size 1.016 1.016)
					(thickness 0.1524)
				)
			)
		)
		(duplicate_pad_numbers_are_jumpers no)
		(fp_rect
			(start -0.4826 0.889)
			(end 0.4826 -0.889)
			(stroke
				(width 0)
				(type default)
			)
			(fill no)
			(layer "F.CrtYd")
		)
		(fp_rect
			(start -0.4826 0.889)
			(end 0.4826 -0.889)
			(stroke
				(width 0)
				(type default)
			)
			(fill no)
			(layer "F.Fab")
		)
		(pad "1" smd custom
			(at 0 -0.4572 270)
			(size 0.1524 0.1524)
			(layers "F.Cu" "F.Mask" "F.Paste")
			(net "P1V8")
			(options
				(clearance outline)
				(anchor circle)
			)
			(primitives
				(gr_poly
					(pts
						(arc
							(start -0.254 0.3048)
							(mid -0.325842 0.275042)
							(end -0.3556 0.2032)
						)
						(arc
							(start -0.3556 -0.2032)
							(mid -0.325842 -0.275042)
							(end -0.254 -0.3048)
						)
						(arc
							(start 0.254 -0.3048)
							(mid 0.325842 -0.275042)
							(end 0.3556 -0.2032)
						)
						(arc
							(start 0.3556 0.2032)
							(mid 0.325842 0.275042)
							(end 0.254 0.3048)
						)
					)
					(width 0)
					(fill yes)
				)
			)
		)
		(pad "2" smd custom
			(at 0 0.4572 270)
			(size 0.1524 0.1524)
			(layers "F.Cu" "F.Mask" "F.Paste")
			(net "GND")
			(options
				(clearance outline)
				(anchor circle)
			)
			(primitives
				(gr_poly
					(pts
						(arc
							(start -0.254 0.3048)
							(mid -0.325842 0.275042)
							(end -0.3556 0.2032)
						)
						(arc
							(start -0.3556 -0.2032)
							(mid -0.325842 -0.275042)
							(end -0.254 -0.3048)
						)
						(arc
							(start 0.254 -0.3048)
							(mid 0.325842 -0.275042)
							(end 0.3556 -0.2032)
						)
						(arc
							(start 0.3556 0.2032)
							(mid 0.325842 0.275042)
							(end 0.254 0.3048)
						)
					)
					(width 0)
					(fill yes)
				)
			)
		)
	)
	(footprint ""
		(layer "F.Cu")
		(at 52.8574 -130.8608)
		(property "Reference" "TP12"
			(at 0 0 0)
			(layer "F.SilkS")
			(hide yes)
			(effects
				(font
					(size 1.27 1.27)
				)
			)
		)
		(property "Value" "TPAD28-2-GP"
			(at -0.0127 -1.6637 0)
			(unlocked yes)
			(layer "F.Fab")
			(hide yes)
			(effects
				(font
					(size 1.016 1.016)
					(thickness 0.1524)
				)
			)
		)
		(property "Device Type" "TPAD28"
			(at -0.0127 -3.1877 0)
			(unlocked yes)
			(layer "F.Fab")
			(hide yes)
			(effects
				(font
					(size 1.016 1.016)
					(thickness 0.1524)
				)
			)
		)
		(duplicate_pad_numbers_are_jumpers no)
		(fp_poly
			(pts
				(arc
					(start 0.3556 0)
					(mid -0.3556 0)
					(end 0.3556 0)
				)
			)
			(stroke
				(width 0)
				(type default)
			)
			(fill no)
			(layer "F.CrtYd")
		)
		(fp_poly
			(pts
				(arc
					(start 0.6096 0)
					(mid -0.6096 0)
					(end 0.6096 0)
				)
			)
			(stroke
				(width 0)
				(type default)
			)
			(fill no)
			(layer "F.Fab")
		)
		(pad "1" smd circle
			(at 0 0)
			(size 0.7112 0.7112)
			(layers "F.Cu" "F.Mask" "F.Paste")
			(net "TP_BMC0_LPC_LAD3")
		)
	)
	(footprint ""
		(layer "F.Cu")
		(at 30.873446 -176.033938 180)
		(property "Reference" "R497"
			(at 0 0 180)
			(layer "F.SilkS")
			(hide yes)
			(effects
				(font
					(size 1.27 1.27)
				)
			)
		)
		(property "Value" "619KR2F-GP"
			(at 0.064008 -3.993896 180)
			(unlocked yes)
			(layer "F.Fab")
			(hide yes)
			(effects
				(font
					(size 1.016 1.016)
					(thickness 0.1524)
				)
			)
		)
		(property "Device Type" "R402H16"
			(at 0.064008 -5.517896 180)
			(unlocked yes)
			(layer "F.Fab")
			(hide yes)
			(effects
				(font
					(size 1.016 1.016)
					(thickness 0.1524)
				)
			)
		)
		(duplicate_pad_numbers_are_jumpers no)
		(fp_line
			(start 0.508 -0.9398)
			(end -0.508 -0.9398)
			(stroke
				(width 0.1524)
				(type default)
			)
			(layer "F.SilkS")
		)
		(fp_line
			(start -0.508 -0.9398)
			(end -0.508 0.9398)
			(stroke
				(width 0.1524)
				(type default)
			)
			(layer "F.SilkS")
		)
		(fp_rect
			(start -0.508 0.9398)
			(end 0.508 -0.9398)
			(stroke
				(width 0)
				(type default)
			)
			(fill no)
			(layer "F.CrtYd")
		)
		(fp_rect
			(start -0.508 0.9398)
			(end 0.508 -0.9398)
			(stroke
				(width 0)
				(type default)
			)
			(fill no)
			(layer "F.Fab")
		)
		(pad "1" smd custom
			(at 0 -0.4445 180)
			(size 0.1397 0.1397)
			(layers "F.Cu" "F.Mask" "F.Paste")
			(net "AGND_P3V3_STBY")
			(options
				(clearance outline)
				(anchor circle)
			)
			(primitives
				(gr_poly
					(pts
						(arc
							(start -0.1778 -0.2794)
							(mid -0.249642 -0.249642)
							(end -0.2794 -0.1778)
						)
						(arc
							(start -0.2794 0.1778)
							(mid -0.249642 0.249642)
							(end -0.1778 0.2794)
						)
						(arc
							(start 0.1778 0.2794)
							(mid 0.249642 0.249642)
							(end 0.2794 0.1778)
						)
						(arc
							(start 0.2794 -0.1778)
							(mid 0.249642 -0.249642)
							(end 0.1778 -0.2794)
						)
					)
					(width 0)
					(fill yes)
				)
			)
		)
		(pad "2" smd custom
			(at 0 0.4445 180)
			(size 0.1397 0.1397)
			(layers "F.Cu" "F.Mask" "F.Paste")
			(net "P3V3_STBY_RF")
			(options
				(clearance outline)
				(anchor circle)
			)
			(primitives
				(gr_poly
					(pts
						(arc
							(start -0.1778 -0.2794)
							(mid -0.249642 -0.249642)
							(end -0.2794 -0.1778)
						)
						(arc
							(start -0.2794 0.1778)
							(mid -0.249642 0.249642)
							(end -0.1778 0.2794)
						)
						(arc
							(start 0.1778 0.2794)
							(mid 0.249642 0.249642)
							(end 0.2794 0.1778)
						)
						(arc
							(start 0.2794 -0.1778)
							(mid 0.249642 -0.249642)
							(end 0.1778 -0.2794)
						)
					)
					(width 0)
					(fill yes)
				)
			)
		)
	)
	(footprint ""
		(layer "F.Cu")
		(at 134.389622 -8.14959 -90)
		(property "Reference" "Q5"
			(at 0 0 270)
			(layer "F.SilkS")
			(hide yes)
			(effects
				(font
					(size 1.27 1.27)
				)
			)
		)
		(property "Value" "PSMN0R9-25YLC-GP"
			(at -4.2799 -0.4572 270)
			(unlocked yes)
			(layer "F.Fab")
			(hide yes)
			(effects
				(font
					(size 1.016 1.016)
					(thickness 0.1524)
				)
			)
		)
		(property "Device Type" "LFPAK-5PH48-U"
			(at -4.2799 -1.9812 270)
			(unlocked yes)
			(layer "F.Fab")
			(hide yes)
			(effects
				(font
					(size 1.016 1.016)
					(thickness 0.1524)
				)
			)
		)
		(duplicate_pad_numbers_are_jumpers no)
		(fp_line
			(start -1.7272 1.1684)
			(end -2.1082 1.1684)
			(stroke
				(width 0.3302)
				(type default)
			)
			(layer "F.SilkS")
		)
		(fp_line
			(start -2.7559 1.0668)
			(end 2.7559 1.0668)
			(stroke
				(width 0.1524)
				(type default)
			)
			(layer "F.SilkS")
		)
		(fp_line
			(start 2.7559 1.0668)
			(end 2.7559 -6.5532)
			(stroke
				(width 0.1524)
				(type default)
			)
			(layer "F.SilkS")
		)
		(fp_line
			(start -2.7559 -6.5532)
			(end -2.7559 1.0668)
			(stroke
				(width 0.1524)
				(type default)
			)
			(layer "F.SilkS")
		)
		(fp_line
			(start 2.7559 -6.5532)
			(end -2.7559 -6.5532)
			(stroke
				(width 0.1524)
				(type default)
			)
			(layer "F.SilkS")
		)
		(fp_poly
			(pts
				(xy -2.3368 1.5748) (xy -1.905 1.143) (xy -1.4732 1.5748)
			)
			(stroke
				(width 0)
				(type default)
			)
			(fill yes)
			(layer "F.SilkS")
		)
		(fp_poly
			(pts
				(xy -2.5019 -1.09601) (xy -0.3302 -1.09601) (xy -0.3302 -3.36931) (xy -2.5019 -3.36931)
			)
			(stroke
				(width 0)
				(type default)
			)
			(fill yes)
			(layer "F.Paste")
		)
		(fp_poly
			(pts
				(xy 0.3302 -1.09601) (xy 2.5019 -1.09601) (xy 2.5019 -3.36931) (xy 0.3302 -3.36931)
			)
			(stroke
				(width 0)
				(type default)
			)
			(fill yes)
			(layer "F.Paste")
		)
		(fp_poly
			(pts
				(xy -2.5019 -4.02971) (xy -0.3302 -4.02971) (xy -0.3302 -6.30301) (xy -2.5019 -6.30301)
			)
			(stroke
				(width 0)
				(type default)
			)
			(fill yes)
			(layer "F.Paste")
		)
		(fp_poly
			(pts
				(xy 0.3302 -4.02971) (xy 2.5019 -4.02971) (xy 2.5019 -6.30301) (xy 0.3302 -6.30301)
			)
			(stroke
				(width 0)
				(type default)
			)
			(fill yes)
			(layer "F.Paste")
		)
		(fp_rect
			(start -2.4511 0.3048)
			(end 2.4511 -5.6896)
			(stroke
				(width 0)
				(type default)
			)
			(fill no)
			(layer "F.CrtYd")
		)
		(fp_poly
			(pts
				(xy -3.0099 1.3208) (xy -3.0099 -6.8072) (xy 3.0099 -6.8072) (xy 3.0099 -1.016) (xy 2.4511 -1.016)
				(xy 2.4511 -5.6896) (xy -2.4511 -5.6896) (xy -2.4511 0.3048) (xy 2.4511 0.3048) (xy 2.4511 -1.0033)
				(xy 3.0099 -1.0033) (xy 3.0099 1.3208)
			)
			(stroke
				(width 0)
				(type default)
			)
			(fill no)
			(layer "F.CrtYd")
		)
		(fp_rect
			(start -3.0099 1.3208)
			(end 3.0099 -6.8072)
			(stroke
				(width 0)
				(type default)
			)
			(fill no)
			(layer "F.Fab")
		)
		(pad "1" smd rect
			(at -1.905 0 270)
			(size 0.762 1.6256)
			(layers "F.Cu" "F.Mask" "F.Paste")
			(net "P12V_STBY")
		)
		(pad "2" smd rect
			(at -0.635 0 270)
			(size 0.762 1.6256)
			(layers "F.Cu" "F.Mask" "F.Paste")
			(net "P12V_STBY")
		)
		(pad "3" smd rect
			(at 0.635 0 270)
			(size 0.762 1.6256)
			(layers "F.Cu" "F.Mask" "F.Paste")
			(net "P12V_STBY")
		)
		(pad "4" smd rect
			(at 1.905 0 270)
			(size 0.762 1.6256)
			(layers "F.Cu" "F.Mask" "F.Paste")
			(net "MB0_12V_CTRL_GATE1")
		)
		(pad "5" smd rect
			(at 0 -3.69951 270)
			(size 5.0038 5.207)
			(layers "F.Cu" "F.Mask" "F.Paste")
			(net "MB0_P12V_MAIN_R")
		)
	)
	(footprint ""
		(layer "F.Cu")
		(at 77.18298 -155.5369 -90)
		(property "Reference" "C234"
			(at 0 0 270)
			(layer "F.SilkS")
			(hide yes)
			(effects
				(font
					(size 1.27 1.27)
				)
			)
		)
		(property "Value" "SC1KP50V2KX-1GP"
			(at 1.1811 -2.7051 270)
			(unlocked yes)
			(layer "F.Fab")
			(hide yes)
			(effects
				(font
					(size 1.016 1.016)
					(thickness 0.1524)
				)
			)
		)
		(property "Device Type" "C402H22"
			(at 1.1811 -4.2291 270)
			(unlocked yes)
			(layer "F.Fab")
			(hide yes)
			(effects
				(font
					(size 1.016 1.016)
					(thickness 0.1524)
				)
			)
		)
		(duplicate_pad_numbers_are_jumpers no)
		(fp_rect
			(start -0.4318 0.9525)
			(end 0.4318 -0.9525)
			(stroke
				(width 0)
				(type default)
			)
			(fill no)
			(layer "F.CrtYd")
		)
		(fp_rect
			(start -0.4318 0.9525)
			(end 0.4318 -0.9525)
			(stroke
				(width 0)
				(type default)
			)
			(fill no)
			(layer "F.Fab")
		)
		(pad "1" smd custom
			(at 0 -0.4445 270)
			(size 0.1524 0.1524)
			(layers "F.Cu" "F.Mask" "F.Paste")
			(net "TPS74801_P1V15_STBY_OUT")
			(options
				(clearance outline)
				(anchor circle)
			)
			(primitives
				(gr_poly
					(pts
						(arc
							(start 0.3048 -0.2032)
							(mid 0.275042 -0.275042)
							(end 0.2032 -0.3048)
						)
						(arc
							(start -0.2032 -0.3048)
							(mid -0.275042 -0.275042)
							(end -0.3048 -0.2032)
						)
						(arc
							(start -0.3048 0.2032)
							(mid -0.275042 0.275042)
							(end -0.2032 0.3048)
						)
						(arc
							(start 0.2032 0.3048)
							(mid 0.275042 0.275042)
							(end 0.3048 0.2032)
						)
					)
					(width 0)
					(fill yes)
				)
			)
		)
		(pad "2" smd custom
			(at 0 0.4445 270)
			(size 0.1524 0.1524)
			(layers "F.Cu" "F.Mask" "F.Paste")
			(net "TPS74801_P1V15_STBY_FB")
			(options
				(clearance outline)
				(anchor circle)
			)
			(primitives
				(gr_poly
					(pts
						(arc
							(start 0.3048 -0.2032)
							(mid 0.275042 -0.275042)
							(end 0.2032 -0.3048)
						)
						(arc
							(start -0.2032 -0.3048)
							(mid -0.275042 -0.275042)
							(end -0.3048 -0.2032)
						)
						(arc
							(start -0.3048 0.2032)
							(mid -0.275042 0.275042)
							(end -0.2032 0.3048)
						)
						(arc
							(start 0.2032 0.3048)
							(mid 0.275042 0.275042)
							(end 0.3048 0.2032)
						)
					)
					(width 0)
					(fill yes)
				)
			)
		)
	)
	(footprint ""
		(layer "F.Cu")
		(at 174.560738 -70.49262 90)
		(property "Reference" "R580"
			(at 0 0 90)
			(layer "F.SilkS")
			(hide yes)
			(effects
				(font
					(size 1.27 1.27)
				)
			)
		)
		(property "Value" "2K2R2F-GP"
			(at 0.064008 -3.993896 90)
			(unlocked yes)
			(layer "F.Fab")
			(hide yes)
			(effects
				(font
					(size 1.016 1.016)
					(thickness 0.1524)
				)
			)
		)
		(property "Device Type" "R402H16"
			(at 0.064008 -5.517896 90)
			(unlocked yes)
			(layer "F.Fab")
			(hide yes)
			(effects
				(font
					(size 1.016 1.016)
					(thickness 0.1524)
				)
			)
		)
		(duplicate_pad_numbers_are_jumpers no)
		(fp_line
			(start 0.508 -0.9398)
			(end -0.508 -0.9398)
			(stroke
				(width 0.1524)
				(type default)
			)
			(layer "F.SilkS")
		)
		(fp_line
			(start -0.508 -0.9398)
			(end -0.508 0.9398)
			(stroke
				(width 0.1524)
				(type default)
			)
			(layer "F.SilkS")
		)
		(fp_rect
			(start -0.508 0.9398)
			(end 0.508 -0.9398)
			(stroke
				(width 0)
				(type default)
			)
			(fill no)
			(layer "F.CrtYd")
		)
		(fp_rect
			(start -0.508 0.9398)
			(end 0.508 -0.9398)
			(stroke
				(width 0)
				(type default)
			)
			(fill no)
			(layer "F.Fab")
		)
		(pad "1" smd custom
			(at 0 -0.4445 90)
			(size 0.1397 0.1397)
			(layers "F.Cu" "F.Mask" "F.Paste")
			(net "P1V8")
			(options
				(clearance outline)
				(anchor circle)
			)
			(primitives
				(gr_poly
					(pts
						(arc
							(start -0.1778 -0.2794)
							(mid -0.249642 -0.249642)
							(end -0.2794 -0.1778)
						)
						(arc
							(start -0.2794 0.1778)
							(mid -0.249642 0.249642)
							(end -0.1778 0.2794)
						)
						(arc
							(start 0.1778 0.2794)
							(mid 0.249642 0.249642)
							(end 0.2794 0.1778)
						)
						(arc
							(start 0.2794 -0.1778)
							(mid 0.249642 -0.249642)
							(end 0.1778 -0.2794)
						)
					)
					(width 0)
					(fill yes)
				)
			)
		)
		(pad "2" smd custom
			(at 0 0.4445 90)
			(size 0.1397 0.1397)
			(layers "F.Cu" "F.Mask" "F.Paste")
			(net "IOC_SCL_0")
			(options
				(clearance outline)
				(anchor circle)
			)
			(primitives
				(gr_poly
					(pts
						(arc
							(start -0.1778 -0.2794)
							(mid -0.249642 -0.249642)
							(end -0.2794 -0.1778)
						)
						(arc
							(start -0.2794 0.1778)
							(mid -0.249642 0.249642)
							(end -0.1778 0.2794)
						)
						(arc
							(start 0.1778 0.2794)
							(mid 0.249642 0.249642)
							(end 0.2794 0.1778)
						)
						(arc
							(start 0.2794 -0.1778)
							(mid 0.249642 -0.249642)
							(end 0.1778 -0.2794)
						)
					)
					(width 0)
					(fill yes)
				)
			)
		)
	)
	(footprint ""
		(layer "F.Cu")
		(at 77.1398 -156.561536 -90)
		(property "Reference" "R537"
			(at 0 0 270)
			(layer "F.SilkS")
			(hide yes)
			(effects
				(font
					(size 1.27 1.27)
				)
			)
		)
		(property "Value" "2K05R2F-1-GP"
			(at 0.064008 -3.993896 270)
			(unlocked yes)
			(layer "F.Fab")
			(hide yes)
			(effects
				(font
					(size 1.016 1.016)
					(thickness 0.1524)
				)
			)
		)
		(property "Device Type" "R402H16"
			(at 0.064008 -5.517896 270)
			(unlocked yes)
			(layer "F.Fab")
			(hide yes)
			(effects
				(font
					(size 1.016 1.016)
					(thickness 0.1524)
				)
			)
		)
		(duplicate_pad_numbers_are_jumpers no)
		(fp_line
			(start -0.508 -0.9398)
			(end -0.508 0.9398)
			(stroke
				(width 0.1524)
				(type default)
			)
			(layer "F.SilkS")
		)
		(fp_line
			(start 0.508 -0.9398)
			(end -0.508 -0.9398)
			(stroke
				(width 0.1524)
				(type default)
			)
			(layer "F.SilkS")
		)
		(fp_rect
			(start -0.508 0.9398)
			(end 0.508 -0.9398)
			(stroke
				(width 0)
				(type default)
			)
			(fill no)
			(layer "F.CrtYd")
		)
		(fp_rect
			(start -0.508 0.9398)
			(end 0.508 -0.9398)
			(stroke
				(width 0)
				(type default)
			)
			(fill no)
			(layer "F.Fab")
		)
		(pad "1" smd custom
			(at 0 -0.4445 270)
			(size 0.1397 0.1397)
			(layers "F.Cu" "F.Mask" "F.Paste")
			(net "TPS74801_P1V15_STBY_OUT")
			(options
				(clearance outline)
				(anchor circle)
			)
			(primitives
				(gr_poly
					(pts
						(arc
							(start -0.1778 -0.2794)
							(mid -0.249642 -0.249642)
							(end -0.2794 -0.1778)
						)
						(arc
							(start -0.2794 0.1778)
							(mid -0.249642 0.249642)
							(end -0.1778 0.2794)
						)
						(arc
							(start 0.1778 0.2794)
							(mid 0.249642 0.249642)
							(end 0.2794 0.1778)
						)
						(arc
							(start 0.2794 -0.1778)
							(mid 0.249642 -0.249642)
							(end 0.1778 -0.2794)
						)
					)
					(width 0)
					(fill yes)
				)
			)
		)
		(pad "2" smd custom
			(at 0 0.4445 270)
			(size 0.1397 0.1397)
			(layers "F.Cu" "F.Mask" "F.Paste")
			(net "TPS74801_P1V15_STBY_FB")
			(options
				(clearance outline)
				(anchor circle)
			)
			(primitives
				(gr_poly
					(pts
						(arc
							(start -0.1778 -0.2794)
							(mid -0.249642 -0.249642)
							(end -0.2794 -0.1778)
						)
						(arc
							(start -0.2794 0.1778)
							(mid -0.249642 0.249642)
							(end -0.1778 0.2794)
						)
						(arc
							(start 0.1778 0.2794)
							(mid 0.249642 0.249642)
							(end 0.2794 0.1778)
						)
						(arc
							(start 0.2794 -0.1778)
							(mid 0.249642 -0.249642)
							(end 0.1778 -0.2794)
						)
					)
					(width 0)
					(fill yes)
				)
			)
		)
	)
	(footprint ""
		(layer "F.Cu")
		(at 74.442828 -175.754538 90)
		(property "Reference" "R506"
			(at 0 0 90)
			(layer "F.SilkS")
			(hide yes)
			(effects
				(font
					(size 1.27 1.27)
				)
			)
		)
		(property "Value" "1K69R2F-2-GP"
			(at 0.064008 -3.993896 90)
			(unlocked yes)
			(layer "F.Fab")
			(hide yes)
			(effects
				(font
					(size 1.016 1.016)
					(thickness 0.1524)
				)
			)
		)
		(property "Device Type" "R402H16"
			(at 0.064008 -5.517896 90)
			(unlocked yes)
			(layer "F.Fab")
			(hide yes)
			(effects
				(font
					(size 1.016 1.016)
					(thickness 0.1524)
				)
			)
		)
		(duplicate_pad_numbers_are_jumpers no)
		(fp_line
			(start 0.508 -0.9398)
			(end -0.508 -0.9398)
			(stroke
				(width 0.1524)
				(type default)
			)
			(layer "F.SilkS")
		)
		(fp_line
			(start -0.508 -0.9398)
			(end -0.508 0.9398)
			(stroke
				(width 0.1524)
				(type default)
			)
			(layer "F.SilkS")
		)
		(fp_rect
			(start -0.508 0.9398)
			(end 0.508 -0.9398)
			(stroke
				(width 0)
				(type default)
			)
			(fill no)
			(layer "F.CrtYd")
		)
		(fp_rect
			(start -0.508 0.9398)
			(end 0.508 -0.9398)
			(stroke
				(width 0)
				(type default)
			)
			(fill no)
			(layer "F.Fab")
		)
		(pad "1" smd custom
			(at 0 -0.4445 90)
			(size 0.1397 0.1397)
			(layers "F.Cu" "F.Mask" "F.Paste")
			(net "TPS74801_P2V5_STBY_FB")
			(options
				(clearance outline)
				(anchor circle)
			)
			(primitives
				(gr_poly
					(pts
						(arc
							(start -0.1778 -0.2794)
							(mid -0.249642 -0.249642)
							(end -0.2794 -0.1778)
						)
						(arc
							(start -0.2794 0.1778)
							(mid -0.249642 0.249642)
							(end -0.1778 0.2794)
						)
						(arc
							(start 0.1778 0.2794)
							(mid 0.249642 0.249642)
							(end 0.2794 0.1778)
						)
						(arc
							(start 0.2794 -0.1778)
							(mid 0.249642 -0.249642)
							(end 0.1778 -0.2794)
						)
					)
					(width 0)
					(fill yes)
				)
			)
		)
		(pad "2" smd custom
			(at 0 0.4445 90)
			(size 0.1397 0.1397)
			(layers "F.Cu" "F.Mask" "F.Paste")
			(net "GND")
			(options
				(clearance outline)
				(anchor circle)
			)
			(primitives
				(gr_poly
					(pts
						(arc
							(start -0.1778 -0.2794)
							(mid -0.249642 -0.249642)
							(end -0.2794 -0.1778)
						)
						(arc
							(start -0.2794 0.1778)
							(mid -0.249642 0.249642)
							(end -0.1778 0.2794)
						)
						(arc
							(start 0.1778 0.2794)
							(mid 0.249642 0.249642)
							(end 0.2794 0.1778)
						)
						(arc
							(start 0.2794 -0.1778)
							(mid 0.249642 -0.249642)
							(end 0.1778 -0.2794)
						)
					)
					(width 0)
					(fill yes)
				)
			)
		)
	)
	(footprint ""
		(layer "F.Cu")
		(at 160.9852 -86.2838)
		(property "Reference" "C481"
			(at 0 0 0)
			(layer "F.SilkS")
			(hide yes)
			(effects
				(font
					(size 1.27 1.27)
				)
			)
		)
		(property "Value" "SCD1U16V2KX-3GP"
			(at 1.1811 -2.7051 0)
			(unlocked yes)
			(layer "F.Fab")
			(hide yes)
			(effects
				(font
					(size 1.016 1.016)
					(thickness 0.1524)
				)
			)
		)
		(property "Device Type" "C402H22"
			(at 1.1811 -4.2291 0)
			(unlocked yes)
			(layer "F.Fab")
			(hide yes)
			(effects
				(font
					(size 1.016 1.016)
					(thickness 0.1524)
				)
			)
		)
		(duplicate_pad_numbers_are_jumpers no)
		(fp_rect
			(start -0.4318 0.9525)
			(end 0.4318 -0.9525)
			(stroke
				(width 0)
				(type default)
			)
			(fill no)
			(layer "F.CrtYd")
		)
		(fp_rect
			(start -0.4318 0.9525)
			(end 0.4318 -0.9525)
			(stroke
				(width 0)
				(type default)
			)
			(fill no)
			(layer "F.Fab")
		)
		(pad "1" smd custom
			(at 0 -0.4445)
			(size 0.1524 0.1524)
			(layers "F.Cu" "F.Mask" "F.Paste")
			(net "P1V8")
			(options
				(clearance outline)
				(anchor circle)
			)
			(primitives
				(gr_poly
					(pts
						(arc
							(start 0.3048 -0.2032)
							(mid 0.275042 -0.275042)
							(end 0.2032 -0.3048)
						)
						(arc
							(start -0.2032 -0.3048)
							(mid -0.275042 -0.275042)
							(end -0.3048 -0.2032)
						)
						(arc
							(start -0.3048 0.2032)
							(mid -0.275042 0.275042)
							(end -0.2032 0.3048)
						)
						(arc
							(start 0.2032 0.3048)
							(mid 0.275042 0.275042)
							(end 0.3048 0.2032)
						)
					)
					(width 0)
					(fill yes)
				)
			)
		)
		(pad "2" smd custom
			(at 0 0.4445)
			(size 0.1524 0.1524)
			(layers "F.Cu" "F.Mask" "F.Paste")
			(net "GND")
			(options
				(clearance outline)
				(anchor circle)
			)
			(primitives
				(gr_poly
					(pts
						(arc
							(start 0.3048 -0.2032)
							(mid 0.275042 -0.275042)
							(end 0.2032 -0.3048)
						)
						(arc
							(start -0.2032 -0.3048)
							(mid -0.275042 -0.275042)
							(end -0.3048 -0.2032)
						)
						(arc
							(start -0.3048 0.2032)
							(mid -0.275042 0.275042)
							(end -0.2032 0.3048)
						)
						(arc
							(start 0.2032 0.3048)
							(mid 0.275042 0.275042)
							(end 0.3048 0.2032)
						)
					)
					(width 0)
					(fill yes)
				)
			)
		)
	)
	(footprint ""
		(layer "F.Cu")
		(at 63.3476 -145.669 90)
		(property "Reference" "R182"
			(at 0 0 90)
			(layer "F.SilkS")
			(hide yes)
			(effects
				(font
					(size 1.27 1.27)
				)
			)
		)
		(property "Value" "2K2R2F-GP"
			(at 0.064008 -3.993896 90)
			(unlocked yes)
			(layer "F.Fab")
			(hide yes)
			(effects
				(font
					(size 1.016 1.016)
					(thickness 0.1524)
				)
			)
		)
		(property "Device Type" "R402H16"
			(at 0.064008 -5.517896 90)
			(unlocked yes)
			(layer "F.Fab")
			(hide yes)
			(effects
				(font
					(size 1.016 1.016)
					(thickness 0.1524)
				)
			)
		)
		(duplicate_pad_numbers_are_jumpers no)
		(fp_line
			(start 0.508 -0.9398)
			(end -0.508 -0.9398)
			(stroke
				(width 0.1524)
				(type default)
			)
			(layer "F.SilkS")
		)
		(fp_line
			(start -0.508 -0.9398)
			(end -0.508 0.9398)
			(stroke
				(width 0.1524)
				(type default)
			)
			(layer "F.SilkS")
		)
		(fp_rect
			(start -0.508 0.9398)
			(end 0.508 -0.9398)
			(stroke
				(width 0)
				(type default)
			)
			(fill no)
			(layer "F.CrtYd")
		)
		(fp_rect
			(start -0.508 0.9398)
			(end 0.508 -0.9398)
			(stroke
				(width 0)
				(type default)
			)
			(fill no)
			(layer "F.Fab")
		)
		(pad "1" smd custom
			(at 0 -0.4445 90)
			(size 0.1397 0.1397)
			(layers "F.Cu" "F.Mask" "F.Paste")
			(net "I2C_SCC_SDA_OUT")
			(options
				(clearance outline)
				(anchor circle)
			)
			(primitives
				(gr_poly
					(pts
						(arc
							(start -0.1778 -0.2794)
							(mid -0.249642 -0.249642)
							(end -0.2794 -0.1778)
						)
						(arc
							(start -0.2794 0.1778)
							(mid -0.249642 0.249642)
							(end -0.1778 0.2794)
						)
						(arc
							(start 0.1778 0.2794)
							(mid 0.249642 0.249642)
							(end 0.2794 0.1778)
						)
						(arc
							(start 0.2794 -0.1778)
							(mid 0.249642 -0.249642)
							(end 0.1778 -0.2794)
						)
					)
					(width 0)
					(fill yes)
				)
			)
		)
		(pad "2" smd custom
			(at 0 0.4445 90)
			(size 0.1397 0.1397)
			(layers "F.Cu" "F.Mask" "F.Paste")
			(net "P3V3_STBY")
			(options
				(clearance outline)
				(anchor circle)
			)
			(primitives
				(gr_poly
					(pts
						(arc
							(start -0.1778 -0.2794)
							(mid -0.249642 -0.249642)
							(end -0.2794 -0.1778)
						)
						(arc
							(start -0.2794 0.1778)
							(mid -0.249642 0.249642)
							(end -0.1778 0.2794)
						)
						(arc
							(start 0.1778 0.2794)
							(mid 0.249642 0.249642)
							(end 0.2794 0.1778)
						)
						(arc
							(start 0.2794 -0.1778)
							(mid 0.249642 -0.249642)
							(end 0.1778 -0.2794)
						)
					)
					(width 0)
					(fill yes)
				)
			)
		)
	)
	(footprint ""
		(layer "F.Cu")
		(at 28.790646 -176.618138 180)
		(property "Reference" "R493"
			(at 0 0 180)
			(layer "F.SilkS")
			(hide yes)
			(effects
				(font
					(size 1.27 1.27)
				)
			)
		)
		(property "Value" "100KR2F-L1-GP"
			(at 0.064008 -3.993896 180)
			(unlocked yes)
			(layer "F.Fab")
			(hide yes)
			(effects
				(font
					(size 1.016 1.016)
					(thickness 0.1524)
				)
			)
		)
		(property "Device Type" "R402H16"
			(at 0.064008 -5.517896 180)
			(unlocked yes)
			(layer "F.Fab")
			(hide yes)
			(effects
				(font
					(size 1.016 1.016)
					(thickness 0.1524)
				)
			)
		)
		(duplicate_pad_numbers_are_jumpers no)
		(fp_line
			(start 0.508 -0.9398)
			(end -0.508 -0.9398)
			(stroke
				(width 0.1524)
				(type default)
			)
			(layer "F.SilkS")
		)
		(fp_line
			(start -0.508 -0.9398)
			(end -0.508 0.9398)
			(stroke
				(width 0.1524)
				(type default)
			)
			(layer "F.SilkS")
		)
		(fp_rect
			(start -0.508 0.9398)
			(end 0.508 -0.9398)
			(stroke
				(width 0)
				(type default)
			)
			(fill no)
			(layer "F.CrtYd")
		)
		(fp_rect
			(start -0.508 0.9398)
			(end 0.508 -0.9398)
			(stroke
				(width 0)
				(type default)
			)
			(fill no)
			(layer "F.Fab")
		)
		(pad "1" smd custom
			(at 0 -0.4445 180)
			(size 0.1397 0.1397)
			(layers "F.Cu" "F.Mask" "F.Paste")
			(net "AGND_P3V3_STBY")
			(options
				(clearance outline)
				(anchor circle)
			)
			(primitives
				(gr_poly
					(pts
						(arc
							(start -0.1778 -0.2794)
							(mid -0.249642 -0.249642)
							(end -0.2794 -0.1778)
						)
						(arc
							(start -0.2794 0.1778)
							(mid -0.249642 0.249642)
							(end -0.1778 0.2794)
						)
						(arc
							(start 0.1778 0.2794)
							(mid 0.249642 0.249642)
							(end 0.2794 0.1778)
						)
						(arc
							(start 0.2794 -0.1778)
							(mid 0.249642 -0.249642)
							(end 0.1778 -0.2794)
						)
					)
					(width 0)
					(fill yes)
				)
			)
		)
		(pad "2" smd custom
			(at 0 0.4445 180)
			(size 0.1397 0.1397)
			(layers "F.Cu" "F.Mask" "F.Paste")
			(net "P3V3_STBY_MODE")
			(options
				(clearance outline)
				(anchor circle)
			)
			(primitives
				(gr_poly
					(pts
						(arc
							(start -0.1778 -0.2794)
							(mid -0.249642 -0.249642)
							(end -0.2794 -0.1778)
						)
						(arc
							(start -0.2794 0.1778)
							(mid -0.249642 0.249642)
							(end -0.1778 0.2794)
						)
						(arc
							(start 0.1778 0.2794)
							(mid 0.249642 0.249642)
							(end 0.2794 0.1778)
						)
						(arc
							(start 0.2794 -0.1778)
							(mid 0.249642 -0.249642)
							(end 0.1778 -0.2794)
						)
					)
					(width 0)
					(fill yes)
				)
			)
		)
	)
	(footprint ""
		(layer "F.Cu")
		(at 77.914754 -135.980424 -90)
		(property "Reference" "R95"
			(at 0 0 270)
			(layer "F.SilkS")
			(hide yes)
			(effects
				(font
					(size 1.27 1.27)
				)
			)
		)
		(property "Value" "0R2J-2-GP"
			(at 0.064008 -3.993896 270)
			(unlocked yes)
			(layer "F.Fab")
			(hide yes)
			(effects
				(font
					(size 1.016 1.016)
					(thickness 0.1524)
				)
			)
		)
		(property "Device Type" "R402H16"
			(at 0.064008 -5.517896 270)
			(unlocked yes)
			(layer "F.Fab")
			(hide yes)
			(effects
				(font
					(size 1.016 1.016)
					(thickness 0.1524)
				)
			)
		)
		(duplicate_pad_numbers_are_jumpers no)
		(fp_line
			(start -0.508 -0.9398)
			(end -0.508 0.9398)
			(stroke
				(width 0.1524)
				(type default)
			)
			(layer "F.SilkS")
		)
		(fp_line
			(start 0.508 -0.9398)
			(end -0.508 -0.9398)
			(stroke
				(width 0.1524)
				(type default)
			)
			(layer "F.SilkS")
		)
		(fp_rect
			(start -0.508 0.9398)
			(end 0.508 -0.9398)
			(stroke
				(width 0)
				(type default)
			)
			(fill no)
			(layer "F.CrtYd")
		)
		(fp_rect
			(start -0.508 0.9398)
			(end 0.508 -0.9398)
			(stroke
				(width 0)
				(type default)
			)
			(fill no)
			(layer "F.Fab")
		)
		(pad "1" smd custom
			(at 0 -0.4445 270)
			(size 0.1397 0.1397)
			(layers "F.Cu" "F.Mask" "F.Paste")
			(net "UART_SEL_MUX")
			(options
				(clearance outline)
				(anchor circle)
			)
			(primitives
				(gr_poly
					(pts
						(arc
							(start -0.1778 -0.2794)
							(mid -0.249642 -0.249642)
							(end -0.2794 -0.1778)
						)
						(arc
							(start -0.2794 0.1778)
							(mid -0.249642 0.249642)
							(end -0.1778 0.2794)
						)
						(arc
							(start 0.1778 0.2794)
							(mid 0.249642 0.249642)
							(end 0.2794 0.1778)
						)
						(arc
							(start 0.2794 -0.1778)
							(mid 0.249642 -0.249642)
							(end 0.1778 -0.2794)
						)
					)
					(width 0)
					(fill yes)
				)
			)
		)
		(pad "2" smd custom
			(at 0 0.4445 270)
			(size 0.1397 0.1397)
			(layers "F.Cu" "F.Mask" "F.Paste")
			(net "D_FLIP_Q#")
			(options
				(clearance outline)
				(anchor circle)
			)
			(primitives
				(gr_poly
					(pts
						(arc
							(start -0.1778 -0.2794)
							(mid -0.249642 -0.249642)
							(end -0.2794 -0.1778)
						)
						(arc
							(start -0.2794 0.1778)
							(mid -0.249642 0.249642)
							(end -0.1778 0.2794)
						)
						(arc
							(start 0.1778 0.2794)
							(mid 0.249642 0.249642)
							(end 0.2794 0.1778)
						)
						(arc
							(start 0.2794 -0.1778)
							(mid 0.249642 -0.249642)
							(end 0.1778 -0.2794)
						)
					)
					(width 0)
					(fill yes)
				)
			)
		)
	)
	(footprint ""
		(layer "F.Cu")
		(at 136.7155 -17.85366 180)
		(property "Reference" "C138"
			(at 0 0 180)
			(layer "F.SilkS")
			(hide yes)
			(effects
				(font
					(size 1.27 1.27)
				)
			)
		)
		(property "Value" "SCD1U25V2KX-2-GP"
			(at 1.1811 -2.7051 180)
			(unlocked yes)
			(layer "F.Fab")
			(hide yes)
			(effects
				(font
					(size 1.016 1.016)
					(thickness 0.1524)
				)
			)
		)
		(property "Device Type" "C402H22"
			(at 1.1811 -4.2291 180)
			(unlocked yes)
			(layer "F.Fab")
			(hide yes)
			(effects
				(font
					(size 1.016 1.016)
					(thickness 0.1524)
				)
			)
		)
		(duplicate_pad_numbers_are_jumpers no)
		(fp_rect
			(start -0.4318 0.9525)
			(end 0.4318 -0.9525)
			(stroke
				(width 0)
				(type default)
			)
			(fill no)
			(layer "F.CrtYd")
		)
		(fp_rect
			(start -0.4318 0.9525)
			(end 0.4318 -0.9525)
			(stroke
				(width 0)
				(type default)
			)
			(fill no)
			(layer "F.Fab")
		)
		(pad "1" smd custom
			(at 0 -0.4445 180)
			(size 0.1524 0.1524)
			(layers "F.Cu" "F.Mask" "F.Paste")
			(net "P12V_IOM")
			(options
				(clearance outline)
				(anchor circle)
			)
			(primitives
				(gr_poly
					(pts
						(arc
							(start 0.3048 -0.2032)
							(mid 0.275042 -0.275042)
							(end 0.2032 -0.3048)
						)
						(arc
							(start -0.2032 -0.3048)
							(mid -0.275042 -0.275042)
							(end -0.3048 -0.2032)
						)
						(arc
							(start -0.3048 0.2032)
							(mid -0.275042 0.275042)
							(end -0.2032 0.3048)
						)
						(arc
							(start 0.2032 0.3048)
							(mid 0.275042 0.275042)
							(end 0.3048 0.2032)
						)
					)
					(width 0)
					(fill yes)
				)
			)
		)
		(pad "2" smd custom
			(at 0 0.4445 180)
			(size 0.1524 0.1524)
			(layers "F.Cu" "F.Mask" "F.Paste")
			(net "GND")
			(options
				(clearance outline)
				(anchor circle)
			)
			(primitives
				(gr_poly
					(pts
						(arc
							(start 0.3048 -0.2032)
							(mid 0.275042 -0.275042)
							(end 0.2032 -0.3048)
						)
						(arc
							(start -0.2032 -0.3048)
							(mid -0.275042 -0.275042)
							(end -0.3048 -0.2032)
						)
						(arc
							(start -0.3048 0.2032)
							(mid -0.275042 0.275042)
							(end -0.2032 0.3048)
						)
						(arc
							(start 0.2032 0.3048)
							(mid 0.275042 0.275042)
							(end 0.3048 0.2032)
						)
					)
					(width 0)
					(fill yes)
				)
			)
		)
	)
	(footprint ""
		(layer "F.Cu")
		(at 83.520534 -133.682486 -90)
		(property "Reference" "R53"
			(at 0 0 270)
			(layer "F.SilkS")
			(hide yes)
			(effects
				(font
					(size 1.27 1.27)
				)
			)
		)
		(property "Value" "4K7R2F-GP"
			(at 0.064008 -3.993896 270)
			(unlocked yes)
			(layer "F.Fab")
			(hide yes)
			(effects
				(font
					(size 1.016 1.016)
					(thickness 0.1524)
				)
			)
		)
		(property "Device Type" "R402H16"
			(at 0.064008 -5.517896 270)
			(unlocked yes)
			(layer "F.Fab")
			(hide yes)
			(effects
				(font
					(size 1.016 1.016)
					(thickness 0.1524)
				)
			)
		)
		(duplicate_pad_numbers_are_jumpers no)
		(fp_line
			(start -0.508 -0.9398)
			(end -0.508 0.9398)
			(stroke
				(width 0.1524)
				(type default)
			)
			(layer "F.SilkS")
		)
		(fp_line
			(start 0.508 -0.9398)
			(end -0.508 -0.9398)
			(stroke
				(width 0.1524)
				(type default)
			)
			(layer "F.SilkS")
		)
		(fp_rect
			(start -0.508 0.9398)
			(end 0.508 -0.9398)
			(stroke
				(width 0)
				(type default)
			)
			(fill no)
			(layer "F.CrtYd")
		)
		(fp_rect
			(start -0.508 0.9398)
			(end 0.508 -0.9398)
			(stroke
				(width 0)
				(type default)
			)
			(fill no)
			(layer "F.Fab")
		)
		(pad "1" smd custom
			(at 0 -0.4445 270)
			(size 0.1397 0.1397)
			(layers "F.Cu" "F.Mask" "F.Paste")
			(net "P3V3_STBY")
			(options
				(clearance outline)
				(anchor circle)
			)
			(primitives
				(gr_poly
					(pts
						(arc
							(start -0.1778 -0.2794)
							(mid -0.249642 -0.249642)
							(end -0.2794 -0.1778)
						)
						(arc
							(start -0.2794 0.1778)
							(mid -0.249642 0.249642)
							(end -0.1778 0.2794)
						)
						(arc
							(start 0.1778 0.2794)
							(mid 0.249642 0.249642)
							(end 0.2794 0.1778)
						)
						(arc
							(start 0.2794 -0.1778)
							(mid 0.249642 -0.249642)
							(end 0.1778 -0.2794)
						)
					)
					(width 0)
					(fill yes)
				)
			)
		)
		(pad "2" smd custom
			(at 0 0.4445 270)
			(size 0.1397 0.1397)
			(layers "F.Cu" "F.Mask" "F.Paste")
			(net "I2C_DEBUG_SCL")
			(options
				(clearance outline)
				(anchor circle)
			)
			(primitives
				(gr_poly
					(pts
						(arc
							(start -0.1778 -0.2794)
							(mid -0.249642 -0.249642)
							(end -0.2794 -0.1778)
						)
						(arc
							(start -0.2794 0.1778)
							(mid -0.249642 0.249642)
							(end -0.1778 0.2794)
						)
						(arc
							(start 0.1778 0.2794)
							(mid 0.249642 0.249642)
							(end 0.2794 0.1778)
						)
						(arc
							(start 0.2794 -0.1778)
							(mid 0.249642 -0.249642)
							(end 0.1778 -0.2794)
						)
					)
					(width 0)
					(fill yes)
				)
			)
		)
	)
	(footprint ""
		(layer "F.Cu")
		(at 98.8822 -149.751034 -90)
		(property "Reference" "R30"
			(at 0 0 270)
			(layer "F.SilkS")
			(hide yes)
			(effects
				(font
					(size 1.27 1.27)
				)
			)
		)
		(property "Value" "4K7R2F-GP"
			(at 0.064008 -3.993896 270)
			(unlocked yes)
			(layer "F.Fab")
			(hide yes)
			(effects
				(font
					(size 1.016 1.016)
					(thickness 0.1524)
				)
			)
		)
		(property "Device Type" "R402H16"
			(at 0.064008 -5.517896 270)
			(unlocked yes)
			(layer "F.Fab")
			(hide yes)
			(effects
				(font
					(size 1.016 1.016)
					(thickness 0.1524)
				)
			)
		)
		(duplicate_pad_numbers_are_jumpers no)
		(fp_line
			(start -0.508 -0.9398)
			(end -0.508 0.9398)
			(stroke
				(width 0.1524)
				(type default)
			)
			(layer "F.SilkS")
		)
		(fp_line
			(start 0.508 -0.9398)
			(end -0.508 -0.9398)
			(stroke
				(width 0.1524)
				(type default)
			)
			(layer "F.SilkS")
		)
		(fp_rect
			(start -0.508 0.9398)
			(end 0.508 -0.9398)
			(stroke
				(width 0)
				(type default)
			)
			(fill no)
			(layer "F.CrtYd")
		)
		(fp_rect
			(start -0.508 0.9398)
			(end 0.508 -0.9398)
			(stroke
				(width 0)
				(type default)
			)
			(fill no)
			(layer "F.Fab")
		)
		(pad "1" smd custom
			(at 0 -0.4445 270)
			(size 0.1397 0.1397)
			(layers "F.Cu" "F.Mask" "F.Paste")
			(net "P3V3_STBY")
			(options
				(clearance outline)
				(anchor circle)
			)
			(primitives
				(gr_poly
					(pts
						(arc
							(start -0.1778 -0.2794)
							(mid -0.249642 -0.249642)
							(end -0.2794 -0.1778)
						)
						(arc
							(start -0.2794 0.1778)
							(mid -0.249642 0.249642)
							(end -0.1778 0.2794)
						)
						(arc
							(start 0.1778 0.2794)
							(mid 0.249642 0.249642)
							(end 0.2794 0.1778)
						)
						(arc
							(start 0.2794 -0.1778)
							(mid 0.249642 -0.249642)
							(end 0.1778 -0.2794)
						)
					)
					(width 0)
					(fill yes)
				)
			)
		)
		(pad "2" smd custom
			(at 0 0.4445 270)
			(size 0.1397 0.1397)
			(layers "F.Cu" "F.Mask" "F.Paste")
			(net "USB_OCS_N3")
			(options
				(clearance outline)
				(anchor circle)
			)
			(primitives
				(gr_poly
					(pts
						(arc
							(start -0.1778 -0.2794)
							(mid -0.249642 -0.249642)
							(end -0.2794 -0.1778)
						)
						(arc
							(start -0.2794 0.1778)
							(mid -0.249642 0.249642)
							(end -0.1778 0.2794)
						)
						(arc
							(start 0.1778 0.2794)
							(mid 0.249642 0.249642)
							(end 0.2794 0.1778)
						)
						(arc
							(start 0.2794 -0.1778)
							(mid 0.249642 -0.249642)
							(end 0.1778 -0.2794)
						)
					)
					(width 0)
					(fill yes)
				)
			)
		)
	)
	(footprint ""
		(layer "F.Cu")
		(at 187.57011 -88.37549 180)
		(property "Reference" "R655"
			(at 0 0 180)
			(layer "F.SilkS")
			(hide yes)
			(effects
				(font
					(size 1.27 1.27)
				)
			)
		)
		(property "Value" "10KR2F-2-GP"
			(at 0.064008 -3.993896 180)
			(unlocked yes)
			(layer "F.Fab")
			(hide yes)
			(effects
				(font
					(size 1.016 1.016)
					(thickness 0.1524)
				)
			)
		)
		(property "Device Type" "R402H16"
			(at 0.064008 -5.517896 180)
			(unlocked yes)
			(layer "F.Fab")
			(hide yes)
			(effects
				(font
					(size 1.016 1.016)
					(thickness 0.1524)
				)
			)
		)
		(duplicate_pad_numbers_are_jumpers no)
		(fp_line
			(start 0.508 -0.9398)
			(end -0.508 -0.9398)
			(stroke
				(width 0.1524)
				(type default)
			)
			(layer "F.SilkS")
		)
		(fp_line
			(start -0.508 -0.9398)
			(end -0.508 0.9398)
			(stroke
				(width 0.1524)
				(type default)
			)
			(layer "F.SilkS")
		)
		(fp_rect
			(start -0.508 0.9398)
			(end 0.508 -0.9398)
			(stroke
				(width 0)
				(type default)
			)
			(fill no)
			(layer "F.CrtYd")
		)
		(fp_rect
			(start -0.508 0.9398)
			(end 0.508 -0.9398)
			(stroke
				(width 0)
				(type default)
			)
			(fill no)
			(layer "F.Fab")
		)
		(pad "1" smd custom
			(at 0 -0.4445 180)
			(size 0.1397 0.1397)
			(layers "F.Cu" "F.Mask" "F.Paste")
			(net "SYS_DBMODE1")
			(options
				(clearance outline)
				(anchor circle)
			)
			(primitives
				(gr_poly
					(pts
						(arc
							(start -0.1778 -0.2794)
							(mid -0.249642 -0.249642)
							(end -0.2794 -0.1778)
						)
						(arc
							(start -0.2794 0.1778)
							(mid -0.249642 0.249642)
							(end -0.1778 0.2794)
						)
						(arc
							(start 0.1778 0.2794)
							(mid 0.249642 0.249642)
							(end 0.2794 0.1778)
						)
						(arc
							(start 0.2794 -0.1778)
							(mid 0.249642 -0.249642)
							(end 0.1778 -0.2794)
						)
					)
					(width 0)
					(fill yes)
				)
			)
		)
		(pad "2" smd custom
			(at 0 0.4445 180)
			(size 0.1397 0.1397)
			(layers "F.Cu" "F.Mask" "F.Paste")
			(net "GND")
			(options
				(clearance outline)
				(anchor circle)
			)
			(primitives
				(gr_poly
					(pts
						(arc
							(start -0.1778 -0.2794)
							(mid -0.249642 -0.249642)
							(end -0.2794 -0.1778)
						)
						(arc
							(start -0.2794 0.1778)
							(mid -0.249642 0.249642)
							(end -0.1778 0.2794)
						)
						(arc
							(start 0.1778 0.2794)
							(mid 0.249642 0.249642)
							(end 0.2794 0.1778)
						)
						(arc
							(start 0.2794 -0.1778)
							(mid 0.249642 -0.249642)
							(end 0.1778 -0.2794)
						)
					)
					(width 0)
					(fill yes)
				)
			)
		)
	)
	(footprint ""
		(layer "F.Cu")
		(at 72.04964 -165.6334 90)
		(property "Reference" "R542"
			(at 0 0 90)
			(layer "F.SilkS")
			(hide yes)
			(effects
				(font
					(size 1.27 1.27)
				)
			)
		)
		(property "Value" "0R2J-2-GP"
			(at 0.064008 -3.993896 90)
			(unlocked yes)
			(layer "F.Fab")
			(hide yes)
			(effects
				(font
					(size 1.016 1.016)
					(thickness 0.1524)
				)
			)
		)
		(property "Device Type" "R402H16"
			(at 0.064008 -5.517896 90)
			(unlocked yes)
			(layer "F.Fab")
			(hide yes)
			(effects
				(font
					(size 1.016 1.016)
					(thickness 0.1524)
				)
			)
		)
		(duplicate_pad_numbers_are_jumpers no)
		(fp_line
			(start 0.508 -0.9398)
			(end -0.508 -0.9398)
			(stroke
				(width 0.1524)
				(type default)
			)
			(layer "F.SilkS")
		)
		(fp_line
			(start -0.508 -0.9398)
			(end -0.508 0.9398)
			(stroke
				(width 0.1524)
				(type default)
			)
			(layer "F.SilkS")
		)
		(fp_rect
			(start -0.508 0.9398)
			(end 0.508 -0.9398)
			(stroke
				(width 0)
				(type default)
			)
			(fill no)
			(layer "F.CrtYd")
		)
		(fp_rect
			(start -0.508 0.9398)
			(end 0.508 -0.9398)
			(stroke
				(width 0)
				(type default)
			)
			(fill no)
			(layer "F.Fab")
		)
		(pad "1" smd custom
			(at 0 -0.4445 90)
			(size 0.1397 0.1397)
			(layers "F.Cu" "F.Mask" "F.Paste")
			(net "PWRGD_P1V2_STBY")
			(options
				(clearance outline)
				(anchor circle)
			)
			(primitives
				(gr_poly
					(pts
						(arc
							(start -0.1778 -0.2794)
							(mid -0.249642 -0.249642)
							(end -0.2794 -0.1778)
						)
						(arc
							(start -0.2794 0.1778)
							(mid -0.249642 0.249642)
							(end -0.1778 0.2794)
						)
						(arc
							(start 0.1778 0.2794)
							(mid 0.249642 0.249642)
							(end 0.2794 0.1778)
						)
						(arc
							(start 0.2794 -0.1778)
							(mid 0.249642 -0.249642)
							(end 0.1778 -0.2794)
						)
					)
					(width 0)
					(fill yes)
				)
			)
		)
		(pad "2" smd custom
			(at 0 0.4445 90)
			(size 0.1397 0.1397)
			(layers "F.Cu" "F.Mask" "F.Paste")
			(net "TPS74801_P1V15_STBY_EN")
			(options
				(clearance outline)
				(anchor circle)
			)
			(primitives
				(gr_poly
					(pts
						(arc
							(start -0.1778 -0.2794)
							(mid -0.249642 -0.249642)
							(end -0.2794 -0.1778)
						)
						(arc
							(start -0.2794 0.1778)
							(mid -0.249642 0.249642)
							(end -0.1778 0.2794)
						)
						(arc
							(start 0.1778 0.2794)
							(mid 0.249642 0.249642)
							(end 0.2794 0.1778)
						)
						(arc
							(start 0.2794 -0.1778)
							(mid 0.249642 -0.249642)
							(end 0.1778 -0.2794)
						)
					)
					(width 0)
					(fill yes)
				)
			)
		)
	)
	(footprint ""
		(layer "F.Cu")
		(at 133.48208 -17.90446)
		(property "Reference" "D1"
			(at 0 0 0)
			(layer "F.SilkS")
			(hide yes)
			(effects
				(font
					(size 1.27 1.27)
				)
			)
		)
		(property "Value" "SMF15A-GP"
			(at -2.0955 1.2192 0)
			(unlocked yes)
			(layer "F.Fab")
			(hide yes)
			(effects
				(font
					(size 1.016 1.016)
					(thickness 0.1524)
				)
			)
		)
		(property "Device Type" "SOD123AK-2H43"
			(at -2.0955 -0.3048 0)
			(unlocked yes)
			(layer "F.Fab")
			(hide yes)
			(effects
				(font
					(size 1.016 1.016)
					(thickness 0.1524)
				)
			)
		)
		(duplicate_pad_numbers_are_jumpers no)
		(fp_line
			(start -1.1557 -2.7686)
			(end -1.1557 2.7686)
			(stroke
				(width 0.1524)
				(type default)
			)
			(layer "F.SilkS")
		)
		(fp_line
			(start -1.1557 2.7686)
			(end 1.1557 2.7686)
			(stroke
				(width 0.1524)
				(type default)
			)
			(layer "F.SilkS")
		)
		(fp_line
			(start 1.1557 -2.7686)
			(end -1.1557 -2.7686)
			(stroke
				(width 0.1524)
				(type default)
			)
			(layer "F.SilkS")
		)
		(fp_line
			(start 1.1557 2.7686)
			(end 1.1557 -2.7686)
			(stroke
				(width 0.1524)
				(type default)
			)
			(layer "F.SilkS")
		)
		(fp_line
			(start 1.1557 2.921)
			(end -1.1557 2.921)
			(stroke
				(width 0.508)
				(type default)
			)
			(layer "F.SilkS")
		)
		(fp_poly
			(pts
				(xy -0.4572 1.8669) (xy -0.4572 1.397) (xy -0.9017 1.397) (xy -0.9017 -1.397) (xy -0.4572 -1.397)
				(xy -0.4572 -1.8669) (xy 0.4572 -1.8669) (xy 0.4572 -1.397) (xy 0.9017 -1.397) (xy 0.9017 1.397)
				(xy 0.4572 1.397) (xy 0.4572 1.8669)
			)
			(stroke
				(width 0)
				(type default)
			)
			(fill no)
			(layer "F.CrtYd")
		)
		(fp_poly
			(pts
				(xy -1.4097 2.8448) (xy -1.4097 -2.8448) (xy 1.4097 -2.8448) (xy 1.4097 1.3716) (xy 0.9017 1.3716)
				(xy 0.9017 -1.397) (xy 0.4572 -1.397) (xy 0.4572 -1.8669) (xy -0.4572 -1.8669) (xy -0.4572 -1.397)
				(xy -0.9017 -1.397) (xy -0.9017 1.397) (xy -0.4572 1.397) (xy -0.4572 1.8669) (xy 0.4572 1.8669)
				(xy 0.4572 1.397) (xy 0.9017 1.397) (xy 0.9017 1.3843) (xy 1.4097 1.3843) (xy 1.4097 2.8448)
			)
			(stroke
				(width 0)
				(type default)
			)
			(fill no)
			(layer "F.CrtYd")
		)
		(fp_rect
			(start -1.4097 2.8448)
			(end 1.4097 -2.8448)
			(stroke
				(width 0)
				(type default)
			)
			(fill no)
			(layer "F.Fab")
		)
		(pad "A" smd rect
			(at 0 -1.75768)
			(size 1.143 1.4986)
			(layers "F.Cu" "F.Mask" "F.Paste")
			(net "GND")
		)
		(pad "K" smd rect
			(at 0 1.75768)
			(size 1.143 1.4986)
			(layers "F.Cu" "F.Mask" "F.Paste")
			(net "P12V_IOM")
		)
	)
	(footprint ""
		(layer "F.Cu")
		(at 40.220646 -179.12461 180)
		(property "Reference" "R487"
			(at 0 0 180)
			(layer "F.SilkS")
			(hide yes)
			(effects
				(font
					(size 1.27 1.27)
				)
			)
		)
		(property "Value" "10KR2F-2-GP"
			(at 0.064008 -3.993896 180)
			(unlocked yes)
			(layer "F.Fab")
			(hide yes)
			(effects
				(font
					(size 1.016 1.016)
					(thickness 0.1524)
				)
			)
		)
		(property "Device Type" "R402H16"
			(at 0.064008 -5.517896 180)
			(unlocked yes)
			(layer "F.Fab")
			(hide yes)
			(effects
				(font
					(size 1.016 1.016)
					(thickness 0.1524)
				)
			)
		)
		(duplicate_pad_numbers_are_jumpers no)
		(fp_line
			(start 0.508 -0.9398)
			(end -0.508 -0.9398)
			(stroke
				(width 0.1524)
				(type default)
			)
			(layer "F.SilkS")
		)
		(fp_line
			(start -0.508 -0.9398)
			(end -0.508 0.9398)
			(stroke
				(width 0.1524)
				(type default)
			)
			(layer "F.SilkS")
		)
		(fp_rect
			(start -0.508 0.9398)
			(end 0.508 -0.9398)
			(stroke
				(width 0)
				(type default)
			)
			(fill no)
			(layer "F.CrtYd")
		)
		(fp_rect
			(start -0.508 0.9398)
			(end 0.508 -0.9398)
			(stroke
				(width 0)
				(type default)
			)
			(fill no)
			(layer "F.Fab")
		)
		(pad "1" smd custom
			(at 0 -0.4445 180)
			(size 0.1397 0.1397)
			(layers "F.Cu" "F.Mask" "F.Paste")
			(net "P3V3_STBY_VREG")
			(options
				(clearance outline)
				(anchor circle)
			)
			(primitives
				(gr_poly
					(pts
						(arc
							(start -0.1778 -0.2794)
							(mid -0.249642 -0.249642)
							(end -0.2794 -0.1778)
						)
						(arc
							(start -0.2794 0.1778)
							(mid -0.249642 0.249642)
							(end -0.1778 0.2794)
						)
						(arc
							(start 0.1778 0.2794)
							(mid 0.249642 0.249642)
							(end 0.2794 0.1778)
						)
						(arc
							(start 0.2794 -0.1778)
							(mid 0.249642 -0.249642)
							(end 0.1778 -0.2794)
						)
					)
					(width 0)
					(fill yes)
				)
			)
		)
		(pad "2" smd custom
			(at 0 0.4445 180)
			(size 0.1397 0.1397)
			(layers "F.Cu" "F.Mask" "F.Paste")
			(net "PWRGD_P3V3_STBY")
			(options
				(clearance outline)
				(anchor circle)
			)
			(primitives
				(gr_poly
					(pts
						(arc
							(start -0.1778 -0.2794)
							(mid -0.249642 -0.249642)
							(end -0.2794 -0.1778)
						)
						(arc
							(start -0.2794 0.1778)
							(mid -0.249642 0.249642)
							(end -0.1778 0.2794)
						)
						(arc
							(start 0.1778 0.2794)
							(mid 0.249642 0.249642)
							(end 0.2794 0.1778)
						)
						(arc
							(start 0.2794 -0.1778)
							(mid 0.249642 -0.249642)
							(end 0.1778 -0.2794)
						)
					)
					(width 0)
					(fill yes)
				)
			)
		)
	)
	(footprint ""
		(layer "F.Cu")
		(at 219.691712 -98.448368)
		(property "Reference" "C373"
			(at 0 0 0)
			(layer "F.SilkS")
			(hide yes)
			(effects
				(font
					(size 1.27 1.27)
				)
			)
		)
		(property "Value" "SC100U6D3V6MX-GP"
			(at -0.0762 -5.1308 0)
			(unlocked yes)
			(layer "F.Fab")
			(hide yes)
			(effects
				(font
					(size 1.016 1.016)
					(thickness 0.1524)
				)
			)
		)
		(property "Device Type" "C1206H71"
			(at -0.127 -6.6548 0)
			(unlocked yes)
			(layer "F.Fab")
			(hide yes)
			(effects
				(font
					(size 1.016 1.016)
					(thickness 0.1524)
				)
			)
		)
		(duplicate_pad_numbers_are_jumpers no)
		(fp_line
			(start -1.016 -2.2352)
			(end 1.016 -2.2352)
			(stroke
				(width 0.1524)
				(type default)
			)
			(layer "F.SilkS")
		)
		(fp_line
			(start -1.016 -0.8382)
			(end -1.016 -2.2352)
			(stroke
				(width 0.1524)
				(type default)
			)
			(layer "F.SilkS")
		)
		(fp_line
			(start -1.016 2.2352)
			(end -1.016 0.8382)
			(stroke
				(width 0.1524)
				(type default)
			)
			(layer "F.SilkS")
		)
		(fp_line
			(start 1.016 -2.2352)
			(end 1.016 -0.8382)
			(stroke
				(width 0.1524)
				(type default)
			)
			(layer "F.SilkS")
		)
		(fp_line
			(start 1.016 0.8382)
			(end 1.016 2.2352)
			(stroke
				(width 0.1524)
				(type default)
			)
			(layer "F.SilkS")
		)
		(fp_line
			(start 1.016 2.2352)
			(end -1.016 2.2352)
			(stroke
				(width 0.1524)
				(type default)
			)
			(layer "F.SilkS")
		)
		(fp_rect
			(start -1.0922 2.3114)
			(end 1.0922 -2.3114)
			(stroke
				(width 0)
				(type default)
			)
			(fill no)
			(layer "F.CrtYd")
		)
		(fp_poly
			(pts
				(xy 1.0922 -2.3114) (xy 1.0922 2.3114) (xy -1.0922 2.3114) (xy -1.0922 -2.3114)
			)
			(stroke
				(width 0)
				(type default)
			)
			(fill no)
			(layer "F.Fab")
		)
		(pad "1" smd rect
			(at 0 -1.397)
			(size 1.651 1.27)
			(layers "F.Cu" "F.Mask" "F.Paste")
			(net "GND")
		)
		(pad "2" smd rect
			(at 0 1.397)
			(size 1.651 1.27)
			(layers "F.Cu" "F.Mask" "F.Paste")
			(net "SAS0_AVDD")
		)
	)
	(footprint ""
		(layer "F.Cu")
		(at 160.64484 -40.40632 180)
		(property "Reference" "C527"
			(at 0 0 180)
			(layer "F.SilkS")
			(hide yes)
			(effects
				(font
					(size 1.27 1.27)
				)
			)
		)
		(property "Value" "SC1000P2KV6KX-GP-U"
			(at 0.0508 -3.5052 180)
			(unlocked yes)
			(layer "F.Fab")
			(hide yes)
			(effects
				(font
					(size 1.016 1.016)
					(thickness 0.1524)
				)
			)
		)
		(property "Device Type" "C1206H58"
			(at 0.0508 -5.0292 180)
			(unlocked yes)
			(layer "F.Fab")
			(hide yes)
			(effects
				(font
					(size 1.016 1.016)
					(thickness 0.1524)
				)
			)
		)
		(duplicate_pad_numbers_are_jumpers no)
		(fp_line
			(start 1.016 2.2352)
			(end -1.016 2.2352)
			(stroke
				(width 0.1524)
				(type default)
			)
			(layer "F.SilkS")
		)
		(fp_line
			(start 1.016 0.8382)
			(end 1.016 2.2352)
			(stroke
				(width 0.1524)
				(type default)
			)
			(layer "F.SilkS")
		)
		(fp_line
			(start 1.016 -2.2352)
			(end 1.016 -0.8382)
			(stroke
				(width 0.1524)
				(type default)
			)
			(layer "F.SilkS")
		)
		(fp_line
			(start 1.016 -2.2352)
			(end -1.016 -2.2352)
			(stroke
				(width 0.1524)
				(type default)
			)
			(layer "F.SilkS")
		)
		(fp_line
			(start -1.016 2.2352)
			(end -1.016 0.8128)
			(stroke
				(width 0.1524)
				(type default)
			)
			(layer "F.SilkS")
		)
		(fp_line
			(start -1.016 -2.2352)
			(end -1.016 -0.8382)
			(stroke
				(width 0.1524)
				(type default)
			)
			(layer "F.SilkS")
		)
		(fp_rect
			(start -1.0922 2.3114)
			(end 1.0922 -2.3114)
			(stroke
				(width 0)
				(type default)
			)
			(fill no)
			(layer "F.CrtYd")
		)
		(fp_poly
			(pts
				(xy -1.0922 -2.3114) (xy 1.0922 -2.3114) (xy 1.0922 2.3114) (xy -1.0922 2.3114)
			)
			(stroke
				(width 0)
				(type default)
			)
			(fill no)
			(layer "F.Fab")
		)
		(pad "1" smd rect
			(at 0 -1.397 180)
			(size 1.651 1.27)
			(layers "F.Cu" "F.Mask" "F.Paste")
			(net "EXT2_CONN_GND")
		)
		(pad "2" smd rect
			(at 0 1.397 180)
			(size 1.651 1.27)
			(layers "F.Cu" "F.Mask" "F.Paste")
			(net "GND")
		)
	)
	(footprint ""
		(layer "F.Cu")
		(at 99.380548 -17.925034 180)
		(property "Reference" "R38"
			(at 0 0 180)
			(layer "F.SilkS")
			(hide yes)
			(effects
				(font
					(size 1.27 1.27)
				)
			)
		)
		(property "Value" "0R2J-2-GP"
			(at 0.064008 -3.993896 180)
			(unlocked yes)
			(layer "F.Fab")
			(hide yes)
			(effects
				(font
					(size 1.016 1.016)
					(thickness 0.1524)
				)
			)
		)
		(property "Device Type" "R402H16"
			(at 0.064008 -5.517896 180)
			(unlocked yes)
			(layer "F.Fab")
			(hide yes)
			(effects
				(font
					(size 1.016 1.016)
					(thickness 0.1524)
				)
			)
		)
		(duplicate_pad_numbers_are_jumpers no)
		(fp_line
			(start 0.508 -0.9398)
			(end -0.508 -0.9398)
			(stroke
				(width 0.1524)
				(type default)
			)
			(layer "F.SilkS")
		)
		(fp_line
			(start -0.508 -0.9398)
			(end -0.508 0.9398)
			(stroke
				(width 0.1524)
				(type default)
			)
			(layer "F.SilkS")
		)
		(fp_rect
			(start -0.508 0.9398)
			(end 0.508 -0.9398)
			(stroke
				(width 0)
				(type default)
			)
			(fill no)
			(layer "F.CrtYd")
		)
		(fp_rect
			(start -0.508 0.9398)
			(end 0.508 -0.9398)
			(stroke
				(width 0)
				(type default)
			)
			(fill no)
			(layer "F.Fab")
		)
		(pad "1" smd custom
			(at 0 -0.4445 180)
			(size 0.1397 0.1397)
			(layers "F.Cu" "F.Mask" "F.Paste")
			(net "USB_P1_F_DP1")
			(options
				(clearance outline)
				(anchor circle)
			)
			(primitives
				(gr_poly
					(pts
						(arc
							(start -0.1778 -0.2794)
							(mid -0.249642 -0.249642)
							(end -0.2794 -0.1778)
						)
						(arc
							(start -0.2794 0.1778)
							(mid -0.249642 0.249642)
							(end -0.1778 0.2794)
						)
						(arc
							(start 0.1778 0.2794)
							(mid 0.249642 0.249642)
							(end 0.2794 0.1778)
						)
						(arc
							(start 0.2794 -0.1778)
							(mid 0.249642 -0.249642)
							(end 0.1778 -0.2794)
						)
					)
					(width 0)
					(fill yes)
				)
			)
		)
		(pad "2" smd custom
			(at 0 0.4445 180)
			(size 0.1397 0.1397)
			(layers "F.Cu" "F.Mask" "F.Paste")
			(net "USB_P1_DP")
			(options
				(clearance outline)
				(anchor circle)
			)
			(primitives
				(gr_poly
					(pts
						(arc
							(start -0.1778 -0.2794)
							(mid -0.249642 -0.249642)
							(end -0.2794 -0.1778)
						)
						(arc
							(start -0.2794 0.1778)
							(mid -0.249642 0.249642)
							(end -0.1778 0.2794)
						)
						(arc
							(start 0.1778 0.2794)
							(mid 0.249642 0.249642)
							(end 0.2794 0.1778)
						)
						(arc
							(start 0.2794 -0.1778)
							(mid 0.249642 -0.249642)
							(end 0.1778 -0.2794)
						)
					)
					(width 0)
					(fill yes)
				)
			)
		)
	)
	(footprint ""
		(layer "F.Cu")
		(at 38.544246 -177.14341)
		(property "Reference" "R486"
			(at 0 0 0)
			(layer "F.SilkS")
			(hide yes)
			(effects
				(font
					(size 1.27 1.27)
				)
			)
		)
		(property "Value" "3K83R2F-GP"
			(at 0.064008 -3.993896 0)
			(unlocked yes)
			(layer "F.Fab")
			(hide yes)
			(effects
				(font
					(size 1.016 1.016)
					(thickness 0.1524)
				)
			)
		)
		(property "Device Type" "R402H16"
			(at 0.064008 -5.517896 0)
			(unlocked yes)
			(layer "F.Fab")
			(hide yes)
			(effects
				(font
					(size 1.016 1.016)
					(thickness 0.1524)
				)
			)
		)
		(duplicate_pad_numbers_are_jumpers no)
		(fp_line
			(start -0.508 -0.9398)
			(end -0.508 0.9398)
			(stroke
				(width 0.1524)
				(type default)
			)
			(layer "F.SilkS")
		)
		(fp_line
			(start 0.508 -0.9398)
			(end -0.508 -0.9398)
			(stroke
				(width 0.1524)
				(type default)
			)
			(layer "F.SilkS")
		)
		(fp_rect
			(start -0.508 0.9398)
			(end 0.508 -0.9398)
			(stroke
				(width 0)
				(type default)
			)
			(fill no)
			(layer "F.CrtYd")
		)
		(fp_rect
			(start -0.508 0.9398)
			(end 0.508 -0.9398)
			(stroke
				(width 0)
				(type default)
			)
			(fill no)
			(layer "F.Fab")
		)
		(pad "1" smd custom
			(at 0 -0.4445)
			(size 0.1397 0.1397)
			(layers "F.Cu" "F.Mask" "F.Paste")
			(net "P3V3_STBY_EN")
			(options
				(clearance outline)
				(anchor circle)
			)
			(primitives
				(gr_poly
					(pts
						(arc
							(start -0.1778 -0.2794)
							(mid -0.249642 -0.249642)
							(end -0.2794 -0.1778)
						)
						(arc
							(start -0.2794 0.1778)
							(mid -0.249642 0.249642)
							(end -0.1778 0.2794)
						)
						(arc
							(start 0.1778 0.2794)
							(mid 0.249642 0.249642)
							(end 0.2794 0.1778)
						)
						(arc
							(start 0.2794 -0.1778)
							(mid 0.249642 -0.249642)
							(end 0.1778 -0.2794)
						)
					)
					(width 0)
					(fill yes)
				)
			)
		)
		(pad "2" smd custom
			(at 0 0.4445)
			(size 0.1397 0.1397)
			(layers "F.Cu" "F.Mask" "F.Paste")
			(net "GND")
			(options
				(clearance outline)
				(anchor circle)
			)
			(primitives
				(gr_poly
					(pts
						(arc
							(start -0.1778 -0.2794)
							(mid -0.249642 -0.249642)
							(end -0.2794 -0.1778)
						)
						(arc
							(start -0.2794 0.1778)
							(mid -0.249642 0.249642)
							(end -0.1778 0.2794)
						)
						(arc
							(start 0.1778 0.2794)
							(mid 0.249642 0.249642)
							(end 0.2794 0.1778)
						)
						(arc
							(start 0.2794 -0.1778)
							(mid 0.249642 -0.249642)
							(end 0.1778 -0.2794)
						)
					)
					(width 0)
					(fill yes)
				)
			)
		)
	)
	(footprint ""
		(layer "F.Cu")
		(at 179.2351 -48.1457)
		(property "Reference" "R671"
			(at 0 0 0)
			(layer "F.SilkS")
			(hide yes)
			(effects
				(font
					(size 1.27 1.27)
				)
			)
		)
		(property "Value" "10KR2F-2-GP"
			(at 0.064008 -3.993896 0)
			(unlocked yes)
			(layer "F.Fab")
			(hide yes)
			(effects
				(font
					(size 1.016 1.016)
					(thickness 0.1524)
				)
			)
		)
		(property "Device Type" "R402H16"
			(at 0.064008 -5.517896 0)
			(unlocked yes)
			(layer "F.Fab")
			(hide yes)
			(effects
				(font
					(size 1.016 1.016)
					(thickness 0.1524)
				)
			)
		)
		(duplicate_pad_numbers_are_jumpers no)
		(fp_line
			(start -0.508 -0.9398)
			(end -0.508 0.9398)
			(stroke
				(width 0.1524)
				(type default)
			)
			(layer "F.SilkS")
		)
		(fp_line
			(start 0.508 -0.9398)
			(end -0.508 -0.9398)
			(stroke
				(width 0.1524)
				(type default)
			)
			(layer "F.SilkS")
		)
		(fp_rect
			(start -0.508 0.9398)
			(end 0.508 -0.9398)
			(stroke
				(width 0)
				(type default)
			)
			(fill no)
			(layer "F.CrtYd")
		)
		(fp_rect
			(start -0.508 0.9398)
			(end 0.508 -0.9398)
			(stroke
				(width 0)
				(type default)
			)
			(fill no)
			(layer "F.Fab")
		)
		(pad "1" smd custom
			(at 0 -0.4445)
			(size 0.1397 0.1397)
			(layers "F.Cu" "F.Mask" "F.Paste")
			(net "XM_ADDR_5")
			(options
				(clearance outline)
				(anchor circle)
			)
			(primitives
				(gr_poly
					(pts
						(arc
							(start -0.1778 -0.2794)
							(mid -0.249642 -0.249642)
							(end -0.2794 -0.1778)
						)
						(arc
							(start -0.2794 0.1778)
							(mid -0.249642 0.249642)
							(end -0.1778 0.2794)
						)
						(arc
							(start 0.1778 0.2794)
							(mid 0.249642 0.249642)
							(end 0.2794 0.1778)
						)
						(arc
							(start 0.2794 -0.1778)
							(mid 0.249642 -0.249642)
							(end 0.1778 -0.2794)
						)
					)
					(width 0)
					(fill yes)
				)
			)
		)
		(pad "2" smd custom
			(at 0 0.4445)
			(size 0.1397 0.1397)
			(layers "F.Cu" "F.Mask" "F.Paste")
			(net "GND")
			(options
				(clearance outline)
				(anchor circle)
			)
			(primitives
				(gr_poly
					(pts
						(arc
							(start -0.1778 -0.2794)
							(mid -0.249642 -0.249642)
							(end -0.2794 -0.1778)
						)
						(arc
							(start -0.2794 0.1778)
							(mid -0.249642 0.249642)
							(end -0.1778 0.2794)
						)
						(arc
							(start 0.1778 0.2794)
							(mid 0.249642 0.249642)
							(end 0.2794 0.1778)
						)
						(arc
							(start 0.2794 -0.1778)
							(mid 0.249642 -0.249642)
							(end 0.1778 -0.2794)
						)
					)
					(width 0)
					(fill yes)
				)
			)
		)
	)
	(footprint ""
		(layer "F.Cu")
		(at 68.1482 -163.322 -90)
		(property "Reference" "R73"
			(at 0 0 270)
			(layer "F.SilkS")
			(hide yes)
			(effects
				(font
					(size 1.27 1.27)
				)
			)
		)
		(property "Value" "4K75R2F-1-GP"
			(at 0.064008 -3.993896 270)
			(unlocked yes)
			(layer "F.Fab")
			(hide yes)
			(effects
				(font
					(size 1.016 1.016)
					(thickness 0.1524)
				)
			)
		)
		(property "Device Type" "R402H16"
			(at 0.064008 -5.517896 270)
			(unlocked yes)
			(layer "F.Fab")
			(hide yes)
			(effects
				(font
					(size 1.016 1.016)
					(thickness 0.1524)
				)
			)
		)
		(duplicate_pad_numbers_are_jumpers no)
		(fp_line
			(start -0.508 -0.9398)
			(end -0.508 0.9398)
			(stroke
				(width 0.1524)
				(type default)
			)
			(layer "F.SilkS")
		)
		(fp_line
			(start 0.508 -0.9398)
			(end -0.508 -0.9398)
			(stroke
				(width 0.1524)
				(type default)
			)
			(layer "F.SilkS")
		)
		(fp_rect
			(start -0.508 0.9398)
			(end 0.508 -0.9398)
			(stroke
				(width 0)
				(type default)
			)
			(fill no)
			(layer "F.CrtYd")
		)
		(fp_rect
			(start -0.508 0.9398)
			(end 0.508 -0.9398)
			(stroke
				(width 0)
				(type default)
			)
			(fill no)
			(layer "F.Fab")
		)
		(pad "1" smd custom
			(at 0 -0.4445 270)
			(size 0.1397 0.1397)
			(layers "F.Cu" "F.Mask" "F.Paste")
			(net "P3V3_STBY")
			(options
				(clearance outline)
				(anchor circle)
			)
			(primitives
				(gr_poly
					(pts
						(arc
							(start -0.1778 -0.2794)
							(mid -0.249642 -0.249642)
							(end -0.2794 -0.1778)
						)
						(arc
							(start -0.2794 0.1778)
							(mid -0.249642 0.249642)
							(end -0.1778 0.2794)
						)
						(arc
							(start 0.1778 0.2794)
							(mid 0.249642 0.249642)
							(end 0.2794 0.1778)
						)
						(arc
							(start 0.2794 -0.1778)
							(mid 0.249642 -0.249642)
							(end 0.1778 -0.2794)
						)
					)
					(width 0)
					(fill yes)
				)
			)
		)
		(pad "2" smd custom
			(at 0 0.4445 270)
			(size 0.1397 0.1397)
			(layers "F.Cu" "F.Mask" "F.Paste")
			(net "BMC_TPM_RST_N")
			(options
				(clearance outline)
				(anchor circle)
			)
			(primitives
				(gr_poly
					(pts
						(arc
							(start -0.1778 -0.2794)
							(mid -0.249642 -0.249642)
							(end -0.2794 -0.1778)
						)
						(arc
							(start -0.2794 0.1778)
							(mid -0.249642 0.249642)
							(end -0.1778 0.2794)
						)
						(arc
							(start 0.1778 0.2794)
							(mid 0.249642 0.249642)
							(end 0.2794 0.1778)
						)
						(arc
							(start 0.2794 -0.1778)
							(mid 0.249642 -0.249642)
							(end 0.1778 -0.2794)
						)
					)
					(width 0)
					(fill yes)
				)
			)
		)
	)
	(footprint ""
		(layer "F.Cu")
		(at 67.5386 -140.2334 90)
		(property "Reference" "R56"
			(at 0 0 90)
			(layer "F.SilkS")
			(hide yes)
			(effects
				(font
					(size 1.27 1.27)
				)
			)
		)
		(property "Value" "10KR2F-2-GP"
			(at 0.064008 -3.993896 90)
			(unlocked yes)
			(layer "F.Fab")
			(hide yes)
			(effects
				(font
					(size 1.016 1.016)
					(thickness 0.1524)
				)
			)
		)
		(property "Device Type" "R402H16"
			(at 0.064008 -5.517896 90)
			(unlocked yes)
			(layer "F.Fab")
			(hide yes)
			(effects
				(font
					(size 1.016 1.016)
					(thickness 0.1524)
				)
			)
		)
		(duplicate_pad_numbers_are_jumpers no)
		(fp_line
			(start 0.508 -0.9398)
			(end -0.508 -0.9398)
			(stroke
				(width 0.1524)
				(type default)
			)
			(layer "F.SilkS")
		)
		(fp_line
			(start -0.508 -0.9398)
			(end -0.508 0.9398)
			(stroke
				(width 0.1524)
				(type default)
			)
			(layer "F.SilkS")
		)
		(fp_rect
			(start -0.508 0.9398)
			(end 0.508 -0.9398)
			(stroke
				(width 0)
				(type default)
			)
			(fill no)
			(layer "F.CrtYd")
		)
		(fp_rect
			(start -0.508 0.9398)
			(end 0.508 -0.9398)
			(stroke
				(width 0)
				(type default)
			)
			(fill no)
			(layer "F.Fab")
		)
		(pad "1" smd custom
			(at 0 -0.4445 90)
			(size 0.1397 0.1397)
			(layers "F.Cu" "F.Mask" "F.Paste")
			(net "P3V3_STBY")
			(options
				(clearance outline)
				(anchor circle)
			)
			(primitives
				(gr_poly
					(pts
						(arc
							(start -0.1778 -0.2794)
							(mid -0.249642 -0.249642)
							(end -0.2794 -0.1778)
						)
						(arc
							(start -0.2794 0.1778)
							(mid -0.249642 0.249642)
							(end -0.1778 0.2794)
						)
						(arc
							(start 0.1778 0.2794)
							(mid 0.249642 0.249642)
							(end 0.2794 0.1778)
						)
						(arc
							(start 0.2794 -0.1778)
							(mid 0.249642 -0.249642)
							(end 0.1778 -0.2794)
						)
					)
					(width 0)
					(fill yes)
				)
			)
		)
		(pad "2" smd custom
			(at 0 0.4445 90)
			(size 0.1397 0.1397)
			(layers "F.Cu" "F.Mask" "F.Paste")
			(net "FP_RETBTN")
			(options
				(clearance outline)
				(anchor circle)
			)
			(primitives
				(gr_poly
					(pts
						(arc
							(start -0.1778 -0.2794)
							(mid -0.249642 -0.249642)
							(end -0.2794 -0.1778)
						)
						(arc
							(start -0.2794 0.1778)
							(mid -0.249642 0.249642)
							(end -0.1778 0.2794)
						)
						(arc
							(start 0.1778 0.2794)
							(mid 0.249642 0.249642)
							(end 0.2794 0.1778)
						)
						(arc
							(start 0.2794 -0.1778)
							(mid 0.249642 -0.249642)
							(end 0.1778 -0.2794)
						)
					)
					(width 0)
					(fill yes)
				)
			)
		)
	)
	(footprint ""
		(layer "F.Cu")
		(at 193.5988 -48.387 180)
		(property "Reference" "R645"
			(at 0 0 180)
			(layer "F.SilkS")
			(hide yes)
			(effects
				(font
					(size 1.27 1.27)
				)
			)
		)
		(property "Value" "10KR2F-2-GP"
			(at 0.064008 -3.993896 180)
			(unlocked yes)
			(layer "F.Fab")
			(hide yes)
			(effects
				(font
					(size 1.016 1.016)
					(thickness 0.1524)
				)
			)
		)
		(property "Device Type" "R402H16"
			(at 0.064008 -5.517896 180)
			(unlocked yes)
			(layer "F.Fab")
			(hide yes)
			(effects
				(font
					(size 1.016 1.016)
					(thickness 0.1524)
				)
			)
		)
		(duplicate_pad_numbers_are_jumpers no)
		(fp_line
			(start 0.508 -0.9398)
			(end -0.508 -0.9398)
			(stroke
				(width 0.1524)
				(type default)
			)
			(layer "F.SilkS")
		)
		(fp_line
			(start -0.508 -0.9398)
			(end -0.508 0.9398)
			(stroke
				(width 0.1524)
				(type default)
			)
			(layer "F.SilkS")
		)
		(fp_rect
			(start -0.508 0.9398)
			(end 0.508 -0.9398)
			(stroke
				(width 0)
				(type default)
			)
			(fill no)
			(layer "F.CrtYd")
		)
		(fp_rect
			(start -0.508 0.9398)
			(end 0.508 -0.9398)
			(stroke
				(width 0)
				(type default)
			)
			(fill no)
			(layer "F.Fab")
		)
		(pad "1" smd custom
			(at 0 -0.4445 180)
			(size 0.1397 0.1397)
			(layers "F.Cu" "F.Mask" "F.Paste")
			(net "P1V8")
			(options
				(clearance outline)
				(anchor circle)
			)
			(primitives
				(gr_poly
					(pts
						(arc
							(start -0.1778 -0.2794)
							(mid -0.249642 -0.249642)
							(end -0.2794 -0.1778)
						)
						(arc
							(start -0.2794 0.1778)
							(mid -0.249642 0.249642)
							(end -0.1778 0.2794)
						)
						(arc
							(start 0.1778 0.2794)
							(mid 0.249642 0.249642)
							(end 0.2794 0.1778)
						)
						(arc
							(start 0.2794 -0.1778)
							(mid 0.249642 -0.249642)
							(end 0.1778 -0.2794)
						)
					)
					(width 0)
					(fill yes)
				)
			)
		)
		(pad "2" smd custom
			(at 0 0.4445 180)
			(size 0.1397 0.1397)
			(layers "F.Cu" "F.Mask" "F.Paste")
			(net "LSI_TN")
			(options
				(clearance outline)
				(anchor circle)
			)
			(primitives
				(gr_poly
					(pts
						(arc
							(start -0.1778 -0.2794)
							(mid -0.249642 -0.249642)
							(end -0.2794 -0.1778)
						)
						(arc
							(start -0.2794 0.1778)
							(mid -0.249642 0.249642)
							(end -0.1778 0.2794)
						)
						(arc
							(start 0.1778 0.2794)
							(mid 0.249642 0.249642)
							(end 0.2794 0.1778)
						)
						(arc
							(start 0.2794 -0.1778)
							(mid 0.249642 -0.249642)
							(end 0.1778 -0.2794)
						)
					)
					(width 0)
					(fill yes)
				)
			)
		)
	)
	(footprint ""
		(layer "F.Cu")
		(at 82.457544 -160.376616 180)
		(property "Reference" "C235"
			(at 0 0 180)
			(layer "F.SilkS")
			(hide yes)
			(effects
				(font
					(size 1.27 1.27)
				)
			)
		)
		(property "Value" "SC10U6D3V5KX-4GP"
			(at -0.0762 -6.1214 180)
			(unlocked yes)
			(layer "F.Fab")
			(hide yes)
			(effects
				(font
					(size 1.016 1.016)
					(thickness 0.1524)
				)
			)
		)
		(property "Device Type" "C805H58"
			(at -0.0762 -8.1534 180)
			(unlocked yes)
			(layer "F.Fab")
			(hide yes)
			(effects
				(font
					(size 1.016 1.016)
					(thickness 0.1524)
				)
			)
		)
		(duplicate_pad_numbers_are_jumpers no)
		(fp_line
			(start 0.635 0)
			(end -0.635 0)
			(stroke
				(width 0.508)
				(type default)
			)
			(layer "F.SilkS")
		)
		(fp_rect
			(start -0.9652 1.778)
			(end 0.9652 -1.778)
			(stroke
				(width 0)
				(type default)
			)
			(fill no)
			(layer "F.CrtYd")
		)
		(fp_poly
			(pts
				(xy -0.9652 -1.778) (xy 0.9652 -1.778) (xy 0.9652 1.778) (xy -0.9652 1.778)
			)
			(stroke
				(width 0)
				(type default)
			)
			(fill no)
			(layer "F.Fab")
		)
		(pad "1" smd rect
			(at 0 -0.9652 180)
			(size 1.397 1.143)
			(layers "F.Cu" "F.Mask" "F.Paste")
			(net "TPS74801_P1V15_STBY_OUT")
		)
		(pad "2" smd rect
			(at 0 0.9652 180)
			(size 1.397 1.143)
			(layers "F.Cu" "F.Mask" "F.Paste")
			(net "GND")
		)
	)
	(footprint ""
		(layer "F.Cu")
		(at 89.52992 -149.317456 180)
		(property "Reference" "R33"
			(at 0 0 180)
			(layer "F.SilkS")
			(hide yes)
			(effects
				(font
					(size 1.27 1.27)
				)
			)
		)
		(property "Value" "4K7R2F-GP"
			(at 0.064008 -3.993896 180)
			(unlocked yes)
			(layer "F.Fab")
			(hide yes)
			(effects
				(font
					(size 1.016 1.016)
					(thickness 0.1524)
				)
			)
		)
		(property "Device Type" "R402H16"
			(at 0.064008 -5.517896 180)
			(unlocked yes)
			(layer "F.Fab")
			(hide yes)
			(effects
				(font
					(size 1.016 1.016)
					(thickness 0.1524)
				)
			)
		)
		(duplicate_pad_numbers_are_jumpers no)
		(fp_line
			(start 0.508 -0.9398)
			(end -0.508 -0.9398)
			(stroke
				(width 0.1524)
				(type default)
			)
			(layer "F.SilkS")
		)
		(fp_line
			(start -0.508 -0.9398)
			(end -0.508 0.9398)
			(stroke
				(width 0.1524)
				(type default)
			)
			(layer "F.SilkS")
		)
		(fp_rect
			(start -0.508 0.9398)
			(end 0.508 -0.9398)
			(stroke
				(width 0)
				(type default)
			)
			(fill no)
			(layer "F.CrtYd")
		)
		(fp_rect
			(start -0.508 0.9398)
			(end 0.508 -0.9398)
			(stroke
				(width 0)
				(type default)
			)
			(fill no)
			(layer "F.Fab")
		)
		(pad "1" smd custom
			(at 0 -0.4445 180)
			(size 0.1397 0.1397)
			(layers "F.Cu" "F.Mask" "F.Paste")
			(net "P3V3_STBY")
			(options
				(clearance outline)
				(anchor circle)
			)
			(primitives
				(gr_poly
					(pts
						(arc
							(start -0.1778 -0.2794)
							(mid -0.249642 -0.249642)
							(end -0.2794 -0.1778)
						)
						(arc
							(start -0.2794 0.1778)
							(mid -0.249642 0.249642)
							(end -0.1778 0.2794)
						)
						(arc
							(start 0.1778 0.2794)
							(mid 0.249642 0.249642)
							(end 0.2794 0.1778)
						)
						(arc
							(start 0.2794 -0.1778)
							(mid 0.249642 -0.249642)
							(end 0.1778 -0.2794)
						)
					)
					(width 0)
					(fill yes)
				)
			)
		)
		(pad "2" smd custom
			(at 0 0.4445 180)
			(size 0.1397 0.1397)
			(layers "F.Cu" "F.Mask" "F.Paste")
			(net "USB_EN_1")
			(options
				(clearance outline)
				(anchor circle)
			)
			(primitives
				(gr_poly
					(pts
						(arc
							(start -0.1778 -0.2794)
							(mid -0.249642 -0.249642)
							(end -0.2794 -0.1778)
						)
						(arc
							(start -0.2794 0.1778)
							(mid -0.249642 0.249642)
							(end -0.1778 0.2794)
						)
						(arc
							(start 0.1778 0.2794)
							(mid 0.249642 0.249642)
							(end 0.2794 0.1778)
						)
						(arc
							(start 0.2794 -0.1778)
							(mid 0.249642 -0.249642)
							(end 0.1778 -0.2794)
						)
					)
					(width 0)
					(fill yes)
				)
			)
		)
	)
	(footprint ""
		(layer "F.Cu")
		(at 171.2468 -127.9906 90)
		(property "Reference" "R527"
			(at 0 0 90)
			(layer "F.SilkS")
			(hide yes)
			(effects
				(font
					(size 1.27 1.27)
				)
			)
		)
		(property "Value" "4K7R2F-GP"
			(at 0.064008 -3.993896 90)
			(unlocked yes)
			(layer "F.Fab")
			(hide yes)
			(effects
				(font
					(size 1.016 1.016)
					(thickness 0.1524)
				)
			)
		)
		(property "Device Type" "R402H16"
			(at 0.064008 -5.517896 90)
			(unlocked yes)
			(layer "F.Fab")
			(hide yes)
			(effects
				(font
					(size 1.016 1.016)
					(thickness 0.1524)
				)
			)
		)
		(duplicate_pad_numbers_are_jumpers no)
		(fp_line
			(start 0.508 -0.9398)
			(end -0.508 -0.9398)
			(stroke
				(width 0.1524)
				(type default)
			)
			(layer "F.SilkS")
		)
		(fp_line
			(start -0.508 -0.9398)
			(end -0.508 0.9398)
			(stroke
				(width 0.1524)
				(type default)
			)
			(layer "F.SilkS")
		)
		(fp_rect
			(start -0.508 0.9398)
			(end 0.508 -0.9398)
			(stroke
				(width 0)
				(type default)
			)
			(fill no)
			(layer "F.CrtYd")
		)
		(fp_rect
			(start -0.508 0.9398)
			(end 0.508 -0.9398)
			(stroke
				(width 0)
				(type default)
			)
			(fill no)
			(layer "F.Fab")
		)
		(pad "1" smd custom
			(at 0 -0.4445 90)
			(size 0.1397 0.1397)
			(layers "F.Cu" "F.Mask" "F.Paste")
			(net "P3V3")
			(options
				(clearance outline)
				(anchor circle)
			)
			(primitives
				(gr_poly
					(pts
						(arc
							(start -0.1778 -0.2794)
							(mid -0.249642 -0.249642)
							(end -0.2794 -0.1778)
						)
						(arc
							(start -0.2794 0.1778)
							(mid -0.249642 0.249642)
							(end -0.1778 0.2794)
						)
						(arc
							(start 0.1778 0.2794)
							(mid 0.249642 0.249642)
							(end 0.2794 0.1778)
						)
						(arc
							(start 0.2794 -0.1778)
							(mid 0.249642 -0.249642)
							(end 0.1778 -0.2794)
						)
					)
					(width 0)
					(fill yes)
				)
			)
		)
		(pad "2" smd custom
			(at 0 0.4445 90)
			(size 0.1397 0.1397)
			(layers "F.Cu" "F.Mask" "F.Paste")
			(net "Q7_G")
			(options
				(clearance outline)
				(anchor circle)
			)
			(primitives
				(gr_poly
					(pts
						(arc
							(start -0.1778 -0.2794)
							(mid -0.249642 -0.249642)
							(end -0.2794 -0.1778)
						)
						(arc
							(start -0.2794 0.1778)
							(mid -0.249642 0.249642)
							(end -0.1778 0.2794)
						)
						(arc
							(start 0.1778 0.2794)
							(mid 0.249642 0.249642)
							(end 0.2794 0.1778)
						)
						(arc
							(start 0.2794 -0.1778)
							(mid 0.249642 -0.249642)
							(end 0.1778 -0.2794)
						)
					)
					(width 0)
					(fill yes)
				)
			)
		)
	)
	(footprint ""
		(layer "F.Cu")
		(at 60.689744 -168.952926 180)
		(property "Reference" "R75"
			(at 0 0 180)
			(layer "F.SilkS")
			(hide yes)
			(effects
				(font
					(size 1.27 1.27)
				)
			)
		)
		(property "Value" "0R2J-2-GP"
			(at 0.064008 -3.993896 180)
			(unlocked yes)
			(layer "F.Fab")
			(hide yes)
			(effects
				(font
					(size 1.016 1.016)
					(thickness 0.1524)
				)
			)
		)
		(property "Device Type" "R402H16"
			(at 0.064008 -5.517896 180)
			(unlocked yes)
			(layer "F.Fab")
			(hide yes)
			(effects
				(font
					(size 1.016 1.016)
					(thickness 0.1524)
				)
			)
		)
		(duplicate_pad_numbers_are_jumpers no)
		(fp_line
			(start 0.508 -0.9398)
			(end -0.508 -0.9398)
			(stroke
				(width 0.1524)
				(type default)
			)
			(layer "F.SilkS")
		)
		(fp_line
			(start -0.508 -0.9398)
			(end -0.508 0.9398)
			(stroke
				(width 0.1524)
				(type default)
			)
			(layer "F.SilkS")
		)
		(fp_rect
			(start -0.508 0.9398)
			(end 0.508 -0.9398)
			(stroke
				(width 0)
				(type default)
			)
			(fill no)
			(layer "F.CrtYd")
		)
		(fp_rect
			(start -0.508 0.9398)
			(end 0.508 -0.9398)
			(stroke
				(width 0)
				(type default)
			)
			(fill no)
			(layer "F.Fab")
		)
		(pad "1" smd custom
			(at 0 -0.4445 180)
			(size 0.1397 0.1397)
			(layers "F.Cu" "F.Mask" "F.Paste")
			(net "BMC_SELF_HW_RST_D")
			(options
				(clearance outline)
				(anchor circle)
			)
			(primitives
				(gr_poly
					(pts
						(arc
							(start -0.1778 -0.2794)
							(mid -0.249642 -0.249642)
							(end -0.2794 -0.1778)
						)
						(arc
							(start -0.2794 0.1778)
							(mid -0.249642 0.249642)
							(end -0.1778 0.2794)
						)
						(arc
							(start 0.1778 0.2794)
							(mid 0.249642 0.249642)
							(end 0.2794 0.1778)
						)
						(arc
							(start 0.2794 -0.1778)
							(mid 0.249642 -0.249642)
							(end 0.1778 -0.2794)
						)
					)
					(width 0)
					(fill yes)
				)
			)
		)
		(pad "2" smd custom
			(at 0 0.4445 180)
			(size 0.1397 0.1397)
			(layers "F.Cu" "F.Mask" "F.Paste")
			(net "FM_TPM_PRSNT_RST_N")
			(options
				(clearance outline)
				(anchor circle)
			)
			(primitives
				(gr_poly
					(pts
						(arc
							(start -0.1778 -0.2794)
							(mid -0.249642 -0.249642)
							(end -0.2794 -0.1778)
						)
						(arc
							(start -0.2794 0.1778)
							(mid -0.249642 0.249642)
							(end -0.1778 0.2794)
						)
						(arc
							(start 0.1778 0.2794)
							(mid 0.249642 0.249642)
							(end 0.2794 0.1778)
						)
						(arc
							(start 0.2794 -0.1778)
							(mid 0.249642 -0.249642)
							(end 0.1778 -0.2794)
						)
					)
					(width 0)
					(fill yes)
				)
			)
		)
	)
	(footprint ""
		(layer "F.Cu")
		(at 112.967516 -11.201654)
		(property "Reference" "R453"
			(at 0 0 0)
			(layer "F.SilkS")
			(hide yes)
			(effects
				(font
					(size 1.27 1.27)
				)
			)
		)
		(property "Value" "100KR2J-4-GP"
			(at 0.064008 -3.993896 0)
			(unlocked yes)
			(layer "F.Fab")
			(hide yes)
			(effects
				(font
					(size 1.016 1.016)
					(thickness 0.1524)
				)
			)
		)
		(property "Device Type" "R402H15"
			(at 0.064008 -5.517896 0)
			(unlocked yes)
			(layer "F.Fab")
			(hide yes)
			(effects
				(font
					(size 1.016 1.016)
					(thickness 0.1524)
				)
			)
		)
		(duplicate_pad_numbers_are_jumpers no)
		(fp_line
			(start -0.508 -0.9398)
			(end -0.508 0.9398)
			(stroke
				(width 0.1524)
				(type default)
			)
			(layer "F.SilkS")
		)
		(fp_line
			(start 0.508 -0.9398)
			(end -0.508 -0.9398)
			(stroke
				(width 0.1524)
				(type default)
			)
			(layer "F.SilkS")
		)
		(fp_rect
			(start -0.508 0.9398)
			(end 0.508 -0.9398)
			(stroke
				(width 0)
				(type default)
			)
			(fill no)
			(layer "F.CrtYd")
		)
		(fp_rect
			(start -0.508 0.9398)
			(end 0.508 -0.9398)
			(stroke
				(width 0)
				(type default)
			)
			(fill no)
			(layer "F.Fab")
		)
		(pad "1" smd custom
			(at 0 -0.4445)
			(size 0.1397 0.1397)
			(layers "F.Cu" "F.Mask" "F.Paste")
			(net "MB0_VCAP_R")
			(options
				(clearance outline)
				(anchor circle)
			)
			(primitives
				(gr_poly
					(pts
						(arc
							(start -0.1778 -0.2794)
							(mid -0.249642 -0.249642)
							(end -0.2794 -0.1778)
						)
						(arc
							(start -0.2794 0.1778)
							(mid -0.249642 0.249642)
							(end -0.1778 0.2794)
						)
						(arc
							(start 0.1778 0.2794)
							(mid 0.249642 0.249642)
							(end 0.2794 0.1778)
						)
						(arc
							(start 0.2794 -0.1778)
							(mid 0.249642 -0.249642)
							(end 0.1778 -0.2794)
						)
					)
					(width 0)
					(fill yes)
				)
			)
		)
		(pad "2" smd custom
			(at 0 0.4445)
			(size 0.1397 0.1397)
			(layers "F.Cu" "F.Mask" "F.Paste")
			(net "MB0_ISET_R")
			(options
				(clearance outline)
				(anchor circle)
			)
			(primitives
				(gr_poly
					(pts
						(arc
							(start -0.1778 -0.2794)
							(mid -0.249642 -0.249642)
							(end -0.2794 -0.1778)
						)
						(arc
							(start -0.2794 0.1778)
							(mid -0.249642 0.249642)
							(end -0.1778 0.2794)
						)
						(arc
							(start 0.1778 0.2794)
							(mid 0.249642 0.249642)
							(end 0.2794 0.1778)
						)
						(arc
							(start 0.2794 -0.1778)
							(mid 0.249642 -0.249642)
							(end 0.1778 -0.2794)
						)
					)
					(width 0)
					(fill yes)
				)
			)
		)
	)
	(footprint ""
		(layer "F.Cu")
		(at 93.577156 -162.51428 90)
		(property "Reference" "C20"
			(at 0 0 90)
			(layer "F.SilkS")
			(hide yes)
			(effects
				(font
					(size 1.27 1.27)
				)
			)
		)
		(property "Value" "SC18P50V2JN-1-GP"
			(at 1.1811 -2.7051 90)
			(unlocked yes)
			(layer "F.Fab")
			(hide yes)
			(effects
				(font
					(size 1.016 1.016)
					(thickness 0.1524)
				)
			)
		)
		(property "Device Type" "C402H22"
			(at 1.1811 -4.2291 90)
			(unlocked yes)
			(layer "F.Fab")
			(hide yes)
			(effects
				(font
					(size 1.016 1.016)
					(thickness 0.1524)
				)
			)
		)
		(duplicate_pad_numbers_are_jumpers no)
		(fp_rect
			(start -0.4318 0.9525)
			(end 0.4318 -0.9525)
			(stroke
				(width 0)
				(type default)
			)
			(fill no)
			(layer "F.CrtYd")
		)
		(fp_rect
			(start -0.4318 0.9525)
			(end 0.4318 -0.9525)
			(stroke
				(width 0)
				(type default)
			)
			(fill no)
			(layer "F.Fab")
		)
		(pad "1" smd custom
			(at 0 -0.4445 90)
			(size 0.1524 0.1524)
			(layers "F.Cu" "F.Mask" "F.Paste")
			(net "USB_HUB_XTAL_OUT")
			(options
				(clearance outline)
				(anchor circle)
			)
			(primitives
				(gr_poly
					(pts
						(arc
							(start 0.3048 -0.2032)
							(mid 0.275042 -0.275042)
							(end 0.2032 -0.3048)
						)
						(arc
							(start -0.2032 -0.3048)
							(mid -0.275042 -0.275042)
							(end -0.3048 -0.2032)
						)
						(arc
							(start -0.3048 0.2032)
							(mid -0.275042 0.275042)
							(end -0.2032 0.3048)
						)
						(arc
							(start 0.2032 0.3048)
							(mid 0.275042 0.275042)
							(end 0.3048 0.2032)
						)
					)
					(width 0)
					(fill yes)
				)
			)
		)
		(pad "2" smd custom
			(at 0 0.4445 90)
			(size 0.1524 0.1524)
			(layers "F.Cu" "F.Mask" "F.Paste")
			(net "GND")
			(options
				(clearance outline)
				(anchor circle)
			)
			(primitives
				(gr_poly
					(pts
						(arc
							(start 0.3048 -0.2032)
							(mid 0.275042 -0.275042)
							(end 0.2032 -0.3048)
						)
						(arc
							(start -0.2032 -0.3048)
							(mid -0.275042 -0.275042)
							(end -0.3048 -0.2032)
						)
						(arc
							(start -0.3048 0.2032)
							(mid -0.275042 0.275042)
							(end -0.2032 0.3048)
						)
						(arc
							(start 0.2032 0.3048)
							(mid 0.275042 0.275042)
							(end 0.3048 0.2032)
						)
					)
					(width 0)
					(fill yes)
				)
			)
		)
	)
	(footprint ""
		(layer "F.Cu")
		(at 21.717 -161.163)
		(property "Reference" "C227"
			(at 0 0 0)
			(layer "F.SilkS")
			(hide yes)
			(effects
				(font
					(size 1.27 1.27)
				)
			)
		)
		(property "Value" "SCD1U16V2KX-3GP"
			(at 1.1811 -2.7051 0)
			(unlocked yes)
			(layer "F.Fab")
			(hide yes)
			(effects
				(font
					(size 1.016 1.016)
					(thickness 0.1524)
				)
			)
		)
		(property "Device Type" "C402H22"
			(at 1.1811 -4.2291 0)
			(unlocked yes)
			(layer "F.Fab")
			(hide yes)
			(effects
				(font
					(size 1.016 1.016)
					(thickness 0.1524)
				)
			)
		)
		(duplicate_pad_numbers_are_jumpers no)
		(fp_rect
			(start -0.4318 0.9525)
			(end 0.4318 -0.9525)
			(stroke
				(width 0)
				(type default)
			)
			(fill no)
			(layer "F.CrtYd")
		)
		(fp_rect
			(start -0.4318 0.9525)
			(end 0.4318 -0.9525)
			(stroke
				(width 0)
				(type default)
			)
			(fill no)
			(layer "F.Fab")
		)
		(pad "1" smd custom
			(at 0 -0.4445)
			(size 0.1524 0.1524)
			(layers "F.Cu" "F.Mask" "F.Paste")
			(net "TPS74801_P1V2_STBY_OUT")
			(options
				(clearance outline)
				(anchor circle)
			)
			(primitives
				(gr_poly
					(pts
						(arc
							(start 0.3048 -0.2032)
							(mid 0.275042 -0.275042)
							(end 0.2032 -0.3048)
						)
						(arc
							(start -0.2032 -0.3048)
							(mid -0.275042 -0.275042)
							(end -0.3048 -0.2032)
						)
						(arc
							(start -0.3048 0.2032)
							(mid -0.275042 0.275042)
							(end -0.2032 0.3048)
						)
						(arc
							(start 0.2032 0.3048)
							(mid 0.275042 0.275042)
							(end 0.3048 0.2032)
						)
					)
					(width 0)
					(fill yes)
				)
			)
		)
		(pad "2" smd custom
			(at 0 0.4445)
			(size 0.1524 0.1524)
			(layers "F.Cu" "F.Mask" "F.Paste")
			(net "GND")
			(options
				(clearance outline)
				(anchor circle)
			)
			(primitives
				(gr_poly
					(pts
						(arc
							(start 0.3048 -0.2032)
							(mid 0.275042 -0.275042)
							(end 0.2032 -0.3048)
						)
						(arc
							(start -0.2032 -0.3048)
							(mid -0.275042 -0.275042)
							(end -0.3048 -0.2032)
						)
						(arc
							(start -0.3048 0.2032)
							(mid -0.275042 0.275042)
							(end -0.2032 0.3048)
						)
						(arc
							(start 0.2032 0.3048)
							(mid 0.275042 0.275042)
							(end 0.3048 0.2032)
						)
					)
					(width 0)
					(fill yes)
				)
			)
		)
	)
	(footprint ""
		(layer "F.Cu")
		(at 22.011386 -131.007358 180)
		(property "Reference" "R144"
			(at 0 0 180)
			(layer "F.SilkS")
			(hide yes)
			(effects
				(font
					(size 1.27 1.27)
				)
			)
		)
		(property "Value" "4K7R2F-GP"
			(at 0.064008 -3.993896 180)
			(unlocked yes)
			(layer "F.Fab")
			(hide yes)
			(effects
				(font
					(size 1.016 1.016)
					(thickness 0.1524)
				)
			)
		)
		(property "Device Type" "R402H16"
			(at 0.064008 -5.517896 180)
			(unlocked yes)
			(layer "F.Fab")
			(hide yes)
			(effects
				(font
					(size 1.016 1.016)
					(thickness 0.1524)
				)
			)
		)
		(duplicate_pad_numbers_are_jumpers no)
		(fp_line
			(start 0.508 -0.9398)
			(end -0.508 -0.9398)
			(stroke
				(width 0.1524)
				(type default)
			)
			(layer "F.SilkS")
		)
		(fp_line
			(start -0.508 -0.9398)
			(end -0.508 0.9398)
			(stroke
				(width 0.1524)
				(type default)
			)
			(layer "F.SilkS")
		)
		(fp_rect
			(start -0.508 0.9398)
			(end 0.508 -0.9398)
			(stroke
				(width 0)
				(type default)
			)
			(fill no)
			(layer "F.CrtYd")
		)
		(fp_rect
			(start -0.508 0.9398)
			(end 0.508 -0.9398)
			(stroke
				(width 0)
				(type default)
			)
			(fill no)
			(layer "F.Fab")
		)
		(pad "1" smd custom
			(at 0 -0.4445 180)
			(size 0.1397 0.1397)
			(layers "F.Cu" "F.Mask" "F.Paste")
			(net "DDR4_ALERT")
			(options
				(clearance outline)
				(anchor circle)
			)
			(primitives
				(gr_poly
					(pts
						(arc
							(start -0.1778 -0.2794)
							(mid -0.249642 -0.249642)
							(end -0.2794 -0.1778)
						)
						(arc
							(start -0.2794 0.1778)
							(mid -0.249642 0.249642)
							(end -0.1778 0.2794)
						)
						(arc
							(start 0.1778 0.2794)
							(mid 0.249642 0.249642)
							(end 0.2794 0.1778)
						)
						(arc
							(start 0.2794 -0.1778)
							(mid 0.249642 -0.249642)
							(end 0.1778 -0.2794)
						)
					)
					(width 0)
					(fill yes)
				)
			)
		)
		(pad "2" smd custom
			(at 0 0.4445 180)
			(size 0.1397 0.1397)
			(layers "F.Cu" "F.Mask" "F.Paste")
			(net "P1V2_STBY")
			(options
				(clearance outline)
				(anchor circle)
			)
			(primitives
				(gr_poly
					(pts
						(arc
							(start -0.1778 -0.2794)
							(mid -0.249642 -0.249642)
							(end -0.2794 -0.1778)
						)
						(arc
							(start -0.2794 0.1778)
							(mid -0.249642 0.249642)
							(end -0.1778 0.2794)
						)
						(arc
							(start 0.1778 0.2794)
							(mid 0.249642 0.249642)
							(end 0.2794 0.1778)
						)
						(arc
							(start 0.2794 -0.1778)
							(mid 0.249642 -0.249642)
							(end 0.1778 -0.2794)
						)
					)
					(width 0)
					(fill yes)
				)
			)
		)
	)
	(footprint ""
		(layer "F.Cu")
		(at 70.5104 -149.733 -90)
		(property "Reference" "U30"
			(at 0 0 270)
			(layer "F.SilkS")
			(hide yes)
			(effects
				(font
					(size 1.27 1.27)
				)
			)
		)
		(property "Value" "ICS551MLFT-GP"
			(at -3.707384 -1.5367 270)
			(unlocked yes)
			(layer "F.Fab")
			(hide yes)
			(effects
				(font
					(size 1.016 1.016)
					(thickness 0.1524)
				)
			)
		)
		(property "Device Type" "SOIC8H69"
			(at -3.707384 -3.0607 270)
			(unlocked yes)
			(layer "F.Fab")
			(hide yes)
			(effects
				(font
					(size 1.016 1.016)
					(thickness 0.1524)
				)
			)
		)
		(duplicate_pad_numbers_are_jumpers no)
		(fp_line
			(start -2.6289 3.4417)
			(end -2.6289 1.4732)
			(stroke
				(width 0.381)
				(type default)
			)
			(layer "F.SilkS")
		)
		(fp_line
			(start -2.7432 1.4224)
			(end -2.6416 1.4224)
			(stroke
				(width 0.1524)
				(type default)
			)
			(layer "F.SilkS")
		)
		(fp_line
			(start -2.7432 1.4224)
			(end 2.1336 1.4224)
			(stroke
				(width 0.1524)
				(type default)
			)
			(layer "F.SilkS")
		)
		(fp_line
			(start 2.1336 1.4224)
			(end 2.1336 -1.4224)
			(stroke
				(width 0.1524)
				(type default)
			)
			(layer "F.SilkS")
		)
		(fp_line
			(start -2.1844 -0.0508)
			(end -2.7178 0.508)
			(stroke
				(width 0.1524)
				(type default)
			)
			(layer "F.SilkS")
		)
		(fp_line
			(start -2.7178 -0.508)
			(end -2.1844 -0.0508)
			(stroke
				(width 0.1524)
				(type default)
			)
			(layer "F.SilkS")
		)
		(fp_line
			(start -2.7432 -1.4224)
			(end -2.7432 1.4224)
			(stroke
				(width 0.1524)
				(type default)
			)
			(layer "F.SilkS")
		)
		(fp_line
			(start 2.1336 -1.4224)
			(end -2.7432 -1.4224)
			(stroke
				(width 0.1524)
				(type default)
			)
			(layer "F.SilkS")
		)
		(fp_poly
			(pts
				(xy -2.2098 -1.4224) (xy -2.2098 1.4224) (xy 2.2098 1.4224) (xy 2.2098 -1.4224)
			)
			(stroke
				(width 0)
				(type default)
			)
			(fill yes)
			(layer "F.SilkS")
		)
		(fp_rect
			(start -2.450084 2.999994)
			(end 2.450084 -2.999994)
			(stroke
				(width 0)
				(type default)
			)
			(fill no)
			(layer "F.CrtYd")
		)
		(fp_poly
			(pts
				(xy -2.8194 3.6322) (xy -2.8194 -3.6322) (xy 2.8194 -3.6322) (xy 2.8194 1.18364) (xy 2.450084 1.18364)
				(xy 2.450084 -2.999994) (xy -2.450084 -2.999994) (xy -2.450084 2.999994) (xy 2.450084 2.999994)
				(xy 2.450084 1.18618) (xy 2.8194 1.18618) (xy 2.8194 3.6322)
			)
			(stroke
				(width 0)
				(type default)
			)
			(fill no)
			(layer "F.CrtYd")
		)
		(fp_rect
			(start -2.8194 3.6322)
			(end 2.8194 -3.6322)
			(stroke
				(width 0)
				(type default)
			)
			(fill no)
			(layer "F.Fab")
		)
		(pad "1" smd rect
			(at -1.905 2.54 270)
			(size 0.635 1.651)
			(layers "F.Cu" "F.Mask" "F.Paste")
			(net "50M_CLK_OUT_R")
		)
		(pad "2" smd rect
			(at -0.635 2.54 270)
			(size 0.635 1.651)
			(layers "F.Cu" "F.Mask" "F.Paste")
			(net "U30_Q1")
		)
		(pad "3" smd rect
			(at 0.635 2.54 270)
			(size 0.635 1.651)
			(layers "F.Cu" "F.Mask" "F.Paste")
			(net "Net_326")
		)
		(pad "4" smd rect
			(at 1.905 2.54 270)
			(size 0.635 1.651)
			(layers "F.Cu" "F.Mask" "F.Paste")
			(net "NCSI_RCLK_R")
		)
		(pad "5" smd rect
			(at 1.905 -2.54 270)
			(size 0.635 1.651)
			(layers "F.Cu" "F.Mask" "F.Paste")
			(net "Net_327")
		)
		(pad "6" smd rect
			(at 0.635 -2.54 270)
			(size 0.635 1.651)
			(layers "F.Cu" "F.Mask" "F.Paste")
			(net "GND")
		)
		(pad "7" smd rect
			(at -0.635 -2.54 270)
			(size 0.635 1.651)
			(layers "F.Cu" "F.Mask" "F.Paste")
			(net "P3V3_STBY")
		)
		(pad "8" smd rect
			(at -1.905 -2.54 270)
			(size 0.635 1.651)
			(layers "F.Cu" "F.Mask" "F.Paste")
			(net "50M_CLK_OE")
		)
	)
	(footprint ""
		(layer "F.Cu")
		(at 98.5266 -172.1866 -90)
		(property "Reference" "R123"
			(at 0 0 270)
			(layer "F.SilkS")
			(hide yes)
			(effects
				(font
					(size 1.27 1.27)
				)
			)
		)
		(property "Value" "0R2J-2-GP"
			(at 0.064008 -3.993896 270)
			(unlocked yes)
			(layer "F.Fab")
			(hide yes)
			(effects
				(font
					(size 1.016 1.016)
					(thickness 0.1524)
				)
			)
		)
		(property "Device Type" "R402H16"
			(at 0.064008 -5.517896 270)
			(unlocked yes)
			(layer "F.Fab")
			(hide yes)
			(effects
				(font
					(size 1.016 1.016)
					(thickness 0.1524)
				)
			)
		)
		(duplicate_pad_numbers_are_jumpers no)
		(fp_line
			(start -0.508 -0.9398)
			(end -0.508 0.9398)
			(stroke
				(width 0.1524)
				(type default)
			)
			(layer "F.SilkS")
		)
		(fp_line
			(start 0.508 -0.9398)
			(end -0.508 -0.9398)
			(stroke
				(width 0.1524)
				(type default)
			)
			(layer "F.SilkS")
		)
		(fp_rect
			(start -0.508 0.9398)
			(end 0.508 -0.9398)
			(stroke
				(width 0)
				(type default)
			)
			(fill no)
			(layer "F.CrtYd")
		)
		(fp_rect
			(start -0.508 0.9398)
			(end 0.508 -0.9398)
			(stroke
				(width 0)
				(type default)
			)
			(fill no)
			(layer "F.Fab")
		)
		(pad "1" smd custom
			(at 0 -0.4445 270)
			(size 0.1397 0.1397)
			(layers "F.Cu" "F.Mask" "F.Paste")
			(net "I2C_DPB_MISC_SDA")
			(options
				(clearance outline)
				(anchor circle)
			)
			(primitives
				(gr_poly
					(pts
						(arc
							(start -0.1778 -0.2794)
							(mid -0.249642 -0.249642)
							(end -0.2794 -0.1778)
						)
						(arc
							(start -0.2794 0.1778)
							(mid -0.249642 0.249642)
							(end -0.1778 0.2794)
						)
						(arc
							(start 0.1778 0.2794)
							(mid 0.249642 0.249642)
							(end 0.2794 0.1778)
						)
						(arc
							(start 0.2794 -0.1778)
							(mid 0.249642 -0.249642)
							(end 0.1778 -0.2794)
						)
					)
					(width 0)
					(fill yes)
				)
			)
		)
		(pad "2" smd custom
			(at 0 0.4445 270)
			(size 0.1397 0.1397)
			(layers "F.Cu" "F.Mask" "F.Paste")
			(net "I2C_DPB_MISC_SDA_R")
			(options
				(clearance outline)
				(anchor circle)
			)
			(primitives
				(gr_poly
					(pts
						(arc
							(start -0.1778 -0.2794)
							(mid -0.249642 -0.249642)
							(end -0.2794 -0.1778)
						)
						(arc
							(start -0.2794 0.1778)
							(mid -0.249642 0.249642)
							(end -0.1778 0.2794)
						)
						(arc
							(start 0.1778 0.2794)
							(mid 0.249642 0.249642)
							(end 0.2794 0.1778)
						)
						(arc
							(start 0.2794 -0.1778)
							(mid 0.249642 -0.249642)
							(end 0.1778 -0.2794)
						)
					)
					(width 0)
					(fill yes)
				)
			)
		)
	)
	(footprint ""
		(layer "F.Cu")
		(at 46.035976 -119.346218 -90)
		(property "Reference" "R83"
			(at 0 0 270)
			(layer "F.SilkS")
			(hide yes)
			(effects
				(font
					(size 1.27 1.27)
				)
			)
		)
		(property "Value" "2K2R2J-2-GP"
			(at 0.064008 -3.993896 270)
			(unlocked yes)
			(layer "F.Fab")
			(hide yes)
			(effects
				(font
					(size 1.016 1.016)
					(thickness 0.1524)
				)
			)
		)
		(property "Device Type" "R402H16"
			(at 0.064008 -5.517896 270)
			(unlocked yes)
			(layer "F.Fab")
			(hide yes)
			(effects
				(font
					(size 1.016 1.016)
					(thickness 0.1524)
				)
			)
		)
		(duplicate_pad_numbers_are_jumpers no)
		(fp_line
			(start -0.508 -0.9398)
			(end -0.508 0.9398)
			(stroke
				(width 0.1524)
				(type default)
			)
			(layer "F.SilkS")
		)
		(fp_line
			(start 0.508 -0.9398)
			(end -0.508 -0.9398)
			(stroke
				(width 0.1524)
				(type default)
			)
			(layer "F.SilkS")
		)
		(fp_rect
			(start -0.508 0.9398)
			(end 0.508 -0.9398)
			(stroke
				(width 0)
				(type default)
			)
			(fill no)
			(layer "F.CrtYd")
		)
		(fp_rect
			(start -0.508 0.9398)
			(end 0.508 -0.9398)
			(stroke
				(width 0)
				(type default)
			)
			(fill no)
			(layer "F.Fab")
		)
		(pad "1" smd custom
			(at 0 -0.4445 270)
			(size 0.1397 0.1397)
			(layers "F.Cu" "F.Mask" "F.Paste")
			(net "P3V3_STBY")
			(options
				(clearance outline)
				(anchor circle)
			)
			(primitives
				(gr_poly
					(pts
						(arc
							(start -0.1778 -0.2794)
							(mid -0.249642 -0.249642)
							(end -0.2794 -0.1778)
						)
						(arc
							(start -0.2794 0.1778)
							(mid -0.249642 0.249642)
							(end -0.1778 0.2794)
						)
						(arc
							(start 0.1778 0.2794)
							(mid 0.249642 0.249642)
							(end 0.2794 0.1778)
						)
						(arc
							(start 0.2794 -0.1778)
							(mid 0.249642 -0.249642)
							(end 0.1778 -0.2794)
						)
					)
					(width 0)
					(fill yes)
				)
			)
		)
		(pad "2" smd custom
			(at 0 0.4445 270)
			(size 0.1397 0.1397)
			(layers "F.Cu" "F.Mask" "F.Paste")
			(net "FLA0_SPI_RST")
			(options
				(clearance outline)
				(anchor circle)
			)
			(primitives
				(gr_poly
					(pts
						(arc
							(start -0.1778 -0.2794)
							(mid -0.249642 -0.249642)
							(end -0.2794 -0.1778)
						)
						(arc
							(start -0.2794 0.1778)
							(mid -0.249642 0.249642)
							(end -0.1778 0.2794)
						)
						(arc
							(start 0.1778 0.2794)
							(mid 0.249642 0.249642)
							(end 0.2794 0.1778)
						)
						(arc
							(start 0.2794 -0.1778)
							(mid 0.249642 -0.249642)
							(end 0.1778 -0.2794)
						)
					)
					(width 0)
					(fill yes)
				)
			)
		)
	)
	(footprint ""
		(layer "F.Cu")
		(at 141.299946 -44.200064 180)
		(property "Reference" "CN1"
			(at 0 0 180)
			(layer "F.SilkS")
			(hide yes)
			(effects
				(font
					(size 1.27 1.27)
				)
			)
		)
		(property "Value" "AMP-CONN200-13R-4-GP"
			(at 30.332934 43.515534 180)
			(unlocked yes)
			(layer "F.Fab")
			(hide yes)
			(effects
				(font
					(size 1.016 1.016)
					(thickness 0.1524)
				)
			)
		)
		(property "Device Type" "PREFIT-200P-360520-1H542"
			(at 30.332934 41.991534 180)
			(unlocked yes)
			(layer "F.Fab")
			(hide yes)
			(effects
				(font
					(size 1.016 1.016)
					(thickness 0.1524)
				)
			)
		)
		(duplicate_pad_numbers_are_jumpers no)
		(fp_line
			(start 35.56 3.800094)
			(end -0.9398 3.800094)
			(stroke
				(width 0.1524)
				(type default)
			)
			(layer "F.SilkS")
		)
		(fp_line
			(start 35.56 -15.7226)
			(end 35.56 3.800094)
			(stroke
				(width 0.1524)
				(type default)
			)
			(layer "F.SilkS")
		)
		(fp_line
			(start -0.9398 3.800094)
			(end -0.9398 -15.7226)
			(stroke
				(width 0.1524)
				(type default)
			)
			(layer "F.SilkS")
		)
		(fp_line
			(start -0.9398 -15.7226)
			(end 35.56 -15.7226)
			(stroke
				(width 0.1524)
				(type default)
			)
			(layer "F.SilkS")
		)
		(fp_poly
			(pts
				(xy -0.9398 3.800094) (xy -0.9398 -7.80034) (xy -0.635 -7.80034) (xy -0.635 2.93497) (xy 34.835084 2.93497)
				(xy 34.835084 -13.934948) (xy 34.8361 -13.934948) (xy 34.8361 -14.478) (xy 22.1488 -14.478) (xy 22.1488 -15.5321)
				(xy 11.684 -15.5321) (xy 11.684 -14.478) (xy -0.635 -14.478) (xy -0.635 -7.801356) (xy -0.9398 -7.801356)
				(xy -0.9398 -15.7226) (xy 35.56 -15.7226) (xy 35.56 3.800094)
			)
			(stroke
				(width 0)
				(type default)
			)
			(fill yes)
			(layer "F.SilkS")
		)
		(fp_poly
			(pts
				(arc
					(start 34.453576 -13.208)
					(mid 34.199576 -12.954)
					(end 33.945576 -13.208)
				)
				(arc
					(start 33.945576 -13.716)
					(mid 34.199576 -13.97)
					(end 34.453576 -13.716)
				)
			)
			(stroke
				(width 0)
				(type default)
			)
			(fill yes)
			(layer "F.SilkS")
		)
		(fp_poly
			(pts
				(arc
					(start 32.653478 2.032)
					(mid 32.399478 2.286)
					(end 32.145478 2.032)
				)
				(arc
					(start 32.145478 1.524)
					(mid 32.399478 1.27)
					(end 32.653478 1.524)
				)
			)
			(stroke
				(width 0)
				(type default)
			)
			(fill yes)
			(layer "F.SilkS")
		)
		(fp_poly
			(pts
				(arc
					(start 30.853634 -13.208)
					(mid 30.599634 -12.954)
					(end 30.345634 -13.208)
				)
				(arc
					(start 30.345634 -13.716)
					(mid 30.599634 -13.97)
					(end 30.853634 -13.716)
				)
			)
			(stroke
				(width 0)
				(type default)
			)
			(fill yes)
			(layer "F.SilkS")
		)
		(fp_poly
			(pts
				(arc
					(start 29.053536 2.032)
					(mid 28.799536 2.286)
					(end 28.545536 2.032)
				)
				(arc
					(start 28.545536 1.524)
					(mid 28.799536 1.27)
					(end 29.053536 1.524)
				)
			)
			(stroke
				(width 0)
				(type default)
			)
			(fill yes)
			(layer "F.SilkS")
		)
		(fp_poly
			(pts
				(arc
					(start 27.253692 -13.208)
					(mid 26.999692 -12.954)
					(end 26.745692 -13.208)
				)
				(arc
					(start 26.745692 -13.716)
					(mid 26.999692 -13.97)
					(end 27.253692 -13.716)
				)
			)
			(stroke
				(width 0)
				(type default)
			)
			(fill yes)
			(layer "F.SilkS")
		)
		(fp_poly
			(pts
				(arc
					(start 25.453594 2.032)
					(mid 25.199594 2.286)
					(end 24.945594 2.032)
				)
				(arc
					(start 24.945594 1.524)
					(mid 25.199594 1.27)
					(end 25.453594 1.524)
				)
			)
			(stroke
				(width 0)
				(type default)
			)
			(fill yes)
			(layer "F.SilkS")
		)
		(fp_poly
			(pts
				(arc
					(start 23.65375 -13.208)
					(mid 23.39975 -12.954)
					(end 23.14575 -13.208)
				)
				(arc
					(start 23.14575 -13.716)
					(mid 23.39975 -13.97)
					(end 23.65375 -13.716)
				)
			)
			(stroke
				(width 0)
				(type default)
			)
			(fill yes)
			(layer "F.SilkS")
		)
		(fp_poly
			(pts
				(arc
					(start 21.853652 2.032)
					(mid 21.599652 2.286)
					(end 21.345652 2.032)
				)
				(arc
					(start 21.345652 1.524)
					(mid 21.599652 1.27)
					(end 21.853652 1.524)
				)
			)
			(stroke
				(width 0)
				(type default)
			)
			(fill yes)
			(layer "F.SilkS")
		)
		(fp_poly
			(pts
				(arc
					(start 12.853924 -13.208)
					(mid 12.599924 -12.954)
					(end 12.345924 -13.208)
				)
				(arc
					(start 12.345924 -13.716)
					(mid 12.599924 -13.97)
					(end 12.853924 -13.716)
				)
			)
			(stroke
				(width 0)
				(type default)
			)
			(fill yes)
			(layer "F.SilkS")
		)
		(fp_poly
			(pts
				(arc
					(start 11.053826 2.032)
					(mid 10.799826 2.286)
					(end 10.545826 2.032)
				)
				(arc
					(start 10.545826 1.524)
					(mid 10.799826 1.27)
					(end 11.053826 1.524)
				)
			)
			(stroke
				(width 0)
				(type default)
			)
			(fill yes)
			(layer "F.SilkS")
		)
		(fp_poly
			(pts
				(arc
					(start 9.253982 -13.208)
					(mid 8.999982 -12.954)
					(end 8.745982 -13.208)
				)
				(arc
					(start 8.745982 -13.716)
					(mid 8.999982 -13.97)
					(end 9.253982 -13.716)
				)
			)
			(stroke
				(width 0)
				(type default)
			)
			(fill yes)
			(layer "F.SilkS")
		)
		(fp_poly
			(pts
				(arc
					(start 7.453884 2.032)
					(mid 7.199884 2.286)
					(end 6.945884 2.032)
				)
				(arc
					(start 6.945884 1.524)
					(mid 7.199884 1.27)
					(end 7.453884 1.524)
				)
			)
			(stroke
				(width 0)
				(type default)
			)
			(fill yes)
			(layer "F.SilkS")
		)
		(fp_poly
			(pts
				(arc
					(start 5.65404 -13.208)
					(mid 5.40004 -12.954)
					(end 5.14604 -13.208)
				)
				(arc
					(start 5.14604 -13.716)
					(mid 5.40004 -13.97)
					(end 5.65404 -13.716)
				)
			)
			(stroke
				(width 0)
				(type default)
			)
			(fill yes)
			(layer "F.SilkS")
		)
		(fp_poly
			(pts
				(arc
					(start 3.853942 2.032)
					(mid 3.599942 2.286)
					(end 3.345942 2.032)
				)
				(arc
					(start 3.345942 1.524)
					(mid 3.599942 1.27)
					(end 3.853942 1.524)
				)
			)
			(stroke
				(width 0)
				(type default)
			)
			(fill yes)
			(layer "F.SilkS")
		)
		(fp_poly
			(pts
				(arc
					(start 2.054098 -13.208)
					(mid 1.800098 -12.954)
					(end 1.546098 -13.208)
				)
				(arc
					(start 1.546098 -13.716)
					(mid 1.800098 -13.97)
					(end 2.054098 -13.716)
				)
			)
			(stroke
				(width 0)
				(type default)
			)
			(fill yes)
			(layer "F.SilkS")
		)
		(fp_poly
			(pts
				(arc
					(start 0.254 2.032)
					(mid 0 2.286)
					(end -0.254 2.032)
				)
				(arc
					(start -0.254 1.524)
					(mid 0 1.27)
					(end 0.254 1.524)
				)
			)
			(stroke
				(width 0)
				(type default)
			)
			(fill yes)
			(layer "F.SilkS")
		)
		(fp_rect
			(start -5.3848 7.6962)
			(end 39.5732 -18.6944)
			(stroke
				(width 0)
				(type default)
			)
			(fill no)
			(layer "B.CrtYd")
		)
		(fp_poly
			(pts
				(xy 15.2908 36.5506) (xy 15.2908 14.5542) (xy -0.6858 14.5542) (xy -0.6858 -15.4686) (xy 35.306 -15.4686)
				(xy 35.306 14.5542) (xy 18.9738 14.5542) (xy 18.9738 36.5506)
			)
			(stroke
				(width 0)
				(type default)
			)
			(fill no)
			(layer "F.CrtYd")
		)
		(fp_poly
			(pts
				(xy 14.7828 37.0586) (xy 14.7828 15.0622) (xy -1.1938 15.0622) (xy -1.1938 -15.9766) (xy 35.814 -15.9766)
				(xy 35.814 0) (xy 35.306 0) (xy 35.306 -15.4686) (xy -0.6858 -15.4686) (xy -0.6858 14.5542) (xy 15.2908 14.5542)
				(xy 15.2908 36.5506) (xy 18.9738 36.5506) (xy 18.9738 14.5542) (xy 35.306 14.5542) (xy 35.306 0.0127)
				(xy 35.814 0.0127) (xy 35.814 15.0622) (xy 19.4818 15.0622) (xy 19.4818 37.0586)
			)
			(stroke
				(width 0)
				(type default)
			)
			(fill no)
			(layer "F.CrtYd")
		)
		(fp_poly
			(pts
				(xy 10.287 41.5544) (xy 10.287 19.558) (xy -5.6896 19.558) (xy -5.6896 -20.4724) (xy 40.3098 -20.4724)
				(xy 40.3098 0) (xy 35.814 0) (xy 35.814 -15.9766) (xy -1.1938 -15.9766) (xy -1.1938 15.0622) (xy 14.7828 15.0622)
				(xy 14.7828 37.0586) (xy 19.4818 37.0586) (xy 19.4818 15.0622) (xy 35.814 15.0622) (xy 35.814 0.0127)
				(xy 40.3098 0.0127) (xy 40.3098 19.558) (xy 23.9776 19.558) (xy 23.9776 41.5544)
			)
			(stroke
				(width 0)
				(type default)
			)
			(fill no)
			(layer "F.CrtYd")
		)
		(fp_rect
			(start -5.3848 7.6962)
			(end 39.5732 -18.6944)
			(stroke
				(width 0)
				(type default)
			)
			(fill no)
			(layer "B.Fab")
		)
		(fp_rect
			(start -10.3886 12.7)
			(end 44.577 -23.6982)
			(stroke
				(width 0)
				(type default)
			)
			(fill no)
			(layer "B.Fab")
		)
		(fp_poly
			(pts
				(xy 14.7828 37.0586) (xy 14.7828 15.0622) (xy -1.1938 15.0622) (xy -1.1938 -15.9766) (xy 35.814 -15.9766)
				(xy 35.814 15.0622) (xy 19.4818 15.0622) (xy 19.4818 37.0586)
			)
			(stroke
				(width 0)
				(type default)
			)
			(fill no)
			(layer "F.Fab")
		)
		(fp_poly
			(pts
				(xy 10.287 41.5544) (xy 10.287 19.558) (xy -5.6896 19.558) (xy -5.6896 -20.4724) (xy 40.3098 -20.4724)
				(xy 40.3098 19.558) (xy 23.9776 19.558) (xy 23.9776 41.5544)
			)
			(stroke
				(width 0)
				(type default)
			)
			(fill no)
			(layer "F.Fab")
		)
		(fp_poly
			(pts
				(xy 5.2832 46.5582) (xy 5.2832 24.5618) (xy -10.6934 24.5618) (xy -10.6934 -25.4762) (xy 45.3136 -25.4762)
				(xy 45.3136 24.5618) (xy 28.9814 24.5618) (xy 28.9814 46.5582)
			)
			(stroke
				(width 0)
				(type default)
			)
			(fill no)
			(layer "F.Fab")
		)
		(fp_text user "Press Fit"
			(at 11.7856 -14.70533 180)
			(unlocked yes)
			(layer "F.SilkS")
			(effects
				(font
					(size 1.016 1.016)
					(thickness 0.1524)
				)
				(justify left)
			)
		)
		(fp_text user "Slit"
			(at 3.37947 7.258304 180)
			(unlocked yes)
			(layer "F.SilkS")
			(effects
				(font
					(size 1.016 1.016)
					(thickness 0.1524)
				)
				(justify left)
			)
		)
		(fp_text user "Can not place BGA,CSP,Wave Solder Component"
			(at -7.4168 10.2108 180)
			(unlocked yes)
			(layer "B.Fab")
			(effects
				(font
					(size 1.016 1.016)
					(thickness 0.1524)
				)
				(justify left)
			)
		)
		(fp_text user "High Limit 2mm"
			(at 8.0518 18.1229 180)
			(unlocked yes)
			(layer "F.Fab")
			(effects
				(font
					(size 1.016 1.016)
					(thickness 0.1524)
				)
				(justify left)
			)
		)
		(fp_text user "Can not place BGA,CSP,Wave Solder Component"
			(at -7.9756 21.9964 180)
			(unlocked yes)
			(layer "F.Fab")
			(effects
				(font
					(size 1.016 1.016)
					(thickness 0.1524)
				)
				(justify left)
			)
		)
		(pad "" np_thru_hole circle
			(at 17.135094 -9.344914 180)
			(size 0.254 0.254)
			(drill 2.4638)
			(layers "*.Cu" "*.Mask")
			(clearance 1.4605)
			(thermal_gap 1.4605)
		)
		(pad "" np_thru_hole circle
			(at 17.135094 -2.355088 180)
			(size 0.254 0.254)
			(drill 2.3876)
			(layers "*.Cu" "*.Mask")
			(clearance 1.4224)
			(thermal_gap 1.4224)
		)
		(pad "A1" thru_hole circle
			(at 0 0 180)
			(size 0.762 0.762)
			(drill 0.359918)
			(layers "*.Cu" "*.Mask")
			(remove_unused_layers no)
			(net "PCIE_COMP_TO_IOM_CLK_2_DN")
			(clearance 0.1651)
			(thermal_gap 0.1651)
		)
		(pad "A2" thru_hole circle
			(at 1.800098 1.199896 180)
			(size 0.762 0.762)
			(drill 0.359918)
			(layers "*.Cu" "*.Mask")
			(remove_unused_layers no)
			(net "I2C_DPB_MISC_SDA")
			(clearance 0.1651)
			(thermal_gap 0.1651)
		)
		(pad "A3" thru_hole circle
			(at 3.599942 0 180)
			(size 0.762 0.762)
			(drill 0.359918)
			(layers "*.Cu" "*.Mask")
			(remove_unused_layers no)
			(net "BMC_LOC_HEARTBEAT")
			(clearance 0.1651)
			(thermal_gap 0.1651)
		)
		(pad "A4" thru_hole circle
			(at 5.40004 1.199896 180)
			(size 0.762 0.762)
			(drill 0.359918)
			(layers "*.Cu" "*.Mask")
			(remove_unused_layers no)
			(net "SCC_RMT_FULL_PWR_EN")
			(clearance 0.1651)
			(thermal_gap 0.1651)
		)
		(pad "A5" thru_hole circle
			(at 7.199884 0 180)
			(size 0.762 0.762)
			(drill 0.359918)
			(layers "*.Cu" "*.Mask")
			(remove_unused_layers no)
			(net "PCIE_COMP_TO_IOM_CLK_3_DN")
			(clearance 0.1651)
			(thermal_gap 0.1651)
		)
		(pad "A6" thru_hole circle
			(at 8.999982 1.199896 180)
			(size 0.762 0.762)
			(drill 0.359918)
			(layers "*.Cu" "*.Mask")
			(remove_unused_layers no)
			(net "I2C_EXP_LOC_SDA")
			(clearance 0.1651)
			(thermal_gap 0.1651)
		)
		(pad "A7" thru_hole circle
			(at 10.80008 0 180)
			(size 0.762 0.762)
			(drill 0.359918)
			(layers "*.Cu" "*.Mask")
			(remove_unused_layers no)
			(net "P12V_IOM")
			(clearance 0.1651)
			(thermal_gap 0.1651)
		)
		(pad "A8" thru_hole circle
			(at 12.599924 1.199896 180)
			(size 0.762 0.762)
			(drill 0.359918)
			(layers "*.Cu" "*.Mask")
			(remove_unused_layers no)
			(net "P12V_IOM")
			(clearance 0.1651)
			(thermal_gap 0.1651)
		)
		(pad "A9" thru_hole circle
			(at 21.599906 0 180)
			(size 0.762 0.762)
			(drill 0.359918)
			(layers "*.Cu" "*.Mask")
			(remove_unused_layers no)
			(net "PCIE_COMP_TO_IOM_CLK_4_DN")
			(clearance 0.1651)
			(thermal_gap 0.1651)
		)
		(pad "A10" thru_hole circle
			(at 23.400004 1.199896 180)
			(size 0.762 0.762)
			(drill 0.359918)
			(layers "*.Cu" "*.Mask")
			(remove_unused_layers no)
			(net "SLOTID_1")
			(clearance 0.1651)
			(thermal_gap 0.1651)
		)
		(pad "A11" thru_hole circle
			(at 25.200102 0 180)
			(size 0.762 0.762)
			(drill 0.359918)
			(layers "*.Cu" "*.Mask")
			(remove_unused_layers no)
			(net "BMC_TO_EXP_RESET_N")
			(clearance 0.1651)
			(thermal_gap 0.1651)
		)
		(pad "A12" thru_hole circle
			(at 26.999946 1.199896 180)
			(size 0.762 0.762)
			(drill 0.359918)
			(layers "*.Cu" "*.Mask")
			(remove_unused_layers no)
			(net "USB_COMP_DN")
			(clearance 0.1651)
			(thermal_gap 0.1651)
		)
		(pad "A13" thru_hole circle
			(at 28.800044 0 180)
			(size 0.762 0.762)
			(drill 0.359918)
			(layers "*.Cu" "*.Mask")
			(remove_unused_layers no)
			(net "COMP_TO_BMC_RESET")
			(clearance 0.1651)
			(thermal_gap 0.1651)
		)
		(pad "A14" thru_hole circle
			(at 30.599888 1.199896 180)
			(size 0.762 0.762)
			(drill 0.359918)
			(layers "*.Cu" "*.Mask")
			(remove_unused_layers no)
			(net "I2C_DPB_SDA")
			(clearance 0.1651)
			(thermal_gap 0.1651)
		)
		(pad "A15" thru_hole circle
			(at 32.399986 0 180)
			(size 0.762 0.762)
			(drill 0.359918)
			(layers "*.Cu" "*.Mask")
			(remove_unused_layers no)
			(net "EXP_SPARE_1")
			(clearance 0.1651)
			(thermal_gap 0.1651)
		)
		(pad "A16" thru_hole circle
			(at 34.200084 1.199896 180)
			(size 0.762 0.762)
			(drill 0.359918)
			(layers "*.Cu" "*.Mask")
			(remove_unused_layers no)
			(net "COMP_SPARE_1")
			(clearance 0.1651)
			(thermal_gap 0.1651)
		)
		(pad "B1" thru_hole circle
			(at 0 -1.400048 180)
			(size 0.762 0.762)
			(drill 0.359918)
			(layers "*.Cu" "*.Mask")
			(remove_unused_layers no)
			(net "PCIE_COMP_TO_IOM_CLK_2_DP")
			(clearance 0.1651)
			(thermal_gap 0.1651)
		)
		(pad "B2" thru_hole circle
			(at 1.800098 -0.199898 180)
			(size 0.762 0.762)
			(drill 0.359918)
			(layers "*.Cu" "*.Mask")
			(remove_unused_layers no)
			(net "I2C_DPB_MISC_SCL")
			(clearance 0.1651)
			(thermal_gap 0.1651)
		)
		(pad "B3" thru_hole circle
			(at 3.599942 -1.400048 180)
			(size 0.762 0.762)
			(drill 0.359918)
			(layers "*.Cu" "*.Mask")
			(remove_unused_layers no)
			(net "BMC_RMT_HEARTBEAT")
			(clearance 0.1651)
			(thermal_gap 0.1651)
		)
		(pad "B4" thru_hole circle
			(at 5.40004 -0.199898 180)
			(size 0.762 0.762)
			(drill 0.359918)
			(layers "*.Cu" "*.Mask")
			(remove_unused_layers no)
			(net "SCC_LOC_FULL_PWR_EN")
			(clearance 0.1651)
			(thermal_gap 0.1651)
		)
		(pad "B5" thru_hole circle
			(at 7.199884 -1.400048 180)
			(size 0.762 0.762)
			(drill 0.359918)
			(layers "*.Cu" "*.Mask")
			(remove_unused_layers no)
			(net "PCIE_COMP_TO_IOM_CLK_3_DP")
			(clearance 0.1651)
			(thermal_gap 0.1651)
		)
		(pad "B6" thru_hole circle
			(at 8.999982 -0.199898 180)
			(size 0.762 0.762)
			(drill 0.359918)
			(layers "*.Cu" "*.Mask")
			(remove_unused_layers no)
			(net "I2C_EXP_LOC_SCL")
			(clearance 0.1651)
			(thermal_gap 0.1651)
		)
		(pad "B7" thru_hole circle
			(at 10.80008 -1.400048 180)
			(size 0.762 0.762)
			(drill 0.359918)
			(layers "*.Cu" "*.Mask")
			(remove_unused_layers no)
			(net "P12V_A_PGOOD")
			(clearance 0.1651)
			(thermal_gap 0.1651)
		)
		(pad "B8" thru_hole circle
			(at 12.599924 -0.199898 180)
			(size 0.762 0.762)
			(drill 0.359918)
			(layers "*.Cu" "*.Mask")
			(remove_unused_layers no)
			(net "P12V_IOM")
			(clearance 0.1651)
			(thermal_gap 0.1651)
		)
		(pad "B9" thru_hole circle
			(at 21.599906 -1.400048 180)
			(size 0.762 0.762)
			(drill 0.359918)
			(layers "*.Cu" "*.Mask")
			(remove_unused_layers no)
			(net "PCIE_COMP_TO_IOM_CLK_4_DP")
			(clearance 0.1651)
			(thermal_gap 0.1651)
		)
		(pad "B10" thru_hole circle
			(at 23.400004 -0.199898 180)
			(size 0.762 0.762)
			(drill 0.359918)
			(layers "*.Cu" "*.Mask")
			(remove_unused_layers no)
			(net "SLOTID_0")
			(clearance 0.1651)
			(thermal_gap 0.1651)
		)
		(pad "B11" thru_hole circle
			(at 25.200102 -1.400048 180)
			(size 0.762 0.762)
			(drill 0.359918)
			(layers "*.Cu" "*.Mask")
			(remove_unused_layers no)
			(net "DPB_MISC_ALERT")
			(clearance 0.1651)
			(thermal_gap 0.1651)
		)
		(pad "B12" thru_hole circle
			(at 26.999946 -0.199898 180)
			(size 0.762 0.762)
			(drill 0.359918)
			(layers "*.Cu" "*.Mask")
			(remove_unused_layers no)
			(net "USB_COMP_DP")
			(clearance 0.1651)
			(thermal_gap 0.1651)
		)
		(pad "B13" thru_hole circle
			(at 28.800044 -1.400048 180)
			(size 0.762 0.762)
			(drill 0.359918)
			(layers "*.Cu" "*.Mask")
			(remove_unused_layers no)
			(net "SYS_RESET_N")
			(clearance 0.1651)
			(thermal_gap 0.1651)
		)
		(pad "B14" thru_hole circle
			(at 30.599888 -0.199898 180)
			(size 0.762 0.762)
			(drill 0.359918)
			(layers "*.Cu" "*.Mask")
			(remove_unused_layers no)
			(net "I2C_DPB_SCL")
			(clearance 0.1651)
			(thermal_gap 0.1651)
		)
		(pad "B15" thru_hole circle
			(at 32.399986 -1.400048 180)
			(size 0.762 0.762)
			(drill 0.359918)
			(layers "*.Cu" "*.Mask")
			(remove_unused_layers no)
			(net "EXP_SPARE_0")
			(clearance 0.1651)
			(thermal_gap 0.1651)
		)
		(pad "B16" thru_hole circle
			(at 34.200084 -0.199898 180)
			(size 0.762 0.762)
			(drill 0.359918)
			(layers "*.Cu" "*.Mask")
			(remove_unused_layers no)
			(net "COMP_SPARE_0")
			(clearance 0.1651)
			(thermal_gap 0.1651)
		)
		(pad "C1" thru_hole circle
			(at 0 -3.599942 180)
			(size 0.762 0.762)
			(drill 0.359918)
			(layers "*.Cu" "*.Mask")
			(remove_unused_layers no)
			(net "IOM_MATED_N")
			(clearance 0.1651)
			(thermal_gap 0.1651)
		)
		(pad "C2" thru_hole circle
			(at 1.800098 -2.400046 180)
			(size 0.762 0.762)
			(drill 0.359918)
			(layers "*.Cu" "*.Mask")
			(remove_unused_layers no)
			(net "I2C_SCC_SDA")
			(clearance 0.1651)
			(thermal_gap 0.1651)
		)
		(pad "C3" thru_hole circle
			(at 3.599942 -3.599942 180)
			(size 0.762 0.762)
			(drill 0.359918)
			(layers "*.Cu" "*.Mask")
			(remove_unused_layers no)
			(net "SCC_RMT_HEARTBEAT")
			(clearance 0.1651)
			(thermal_gap 0.1651)
		)
		(pad "C4" thru_hole circle
			(at 5.40004 -2.400046 180)
			(size 0.762 0.762)
			(drill 0.359918)
			(layers "*.Cu" "*.Mask")
			(remove_unused_layers no)
			(net "SYS_PWR_LED")
			(clearance 0.1651)
			(thermal_gap 0.1651)
		)
		(pad "C5" thru_hole circle
			(at 7.199884 -3.599942 180)
			(size 0.762 0.762)
			(drill 0.359918)
			(layers "*.Cu" "*.Mask")
			(remove_unused_layers no)
			(net "IOM_LOC_INS_N")
			(clearance 0.1651)
			(thermal_gap 0.1651)
		)
		(pad "C6" thru_hole circle
			(at 8.999982 -2.400046 180)
			(size 0.762 0.762)
			(drill 0.359918)
			(layers "*.Cu" "*.Mask")
			(remove_unused_layers no)
			(net "I2C_EXP_RMT_SDA")
			(clearance 0.1651)
			(thermal_gap 0.1651)
		)
		(pad "C7" thru_hole circle
			(at 10.80008 -3.599942 180)
			(size 0.762 0.762)
			(drill 0.359918)
			(layers "*.Cu" "*.Mask")
			(remove_unused_layers no)
			(net "UART_SDB_RX")
			(clearance 0.1651)
			(thermal_gap 0.1651)
		)
		(pad "C8" thru_hole circle
			(at 12.599924 -2.400046 180)
			(size 0.762 0.762)
			(drill 0.359918)
			(layers "*.Cu" "*.Mask")
			(remove_unused_layers no)
			(net "P12V_IOM")
			(clearance 0.1651)
			(thermal_gap 0.1651)
		)
		(pad "C9" thru_hole circle
			(at 21.599906 -3.599942 180)
			(size 0.762 0.762)
			(drill 0.359918)
			(layers "*.Cu" "*.Mask")
			(remove_unused_layers no)
			(net "I2C_BMC_COMP_ALERT_N")
			(clearance 0.1651)
			(thermal_gap 0.1651)
		)
		(pad "C10" thru_hole circle
			(at 23.400004 -2.400046 180)
			(size 0.762 0.762)
			(drill 0.359918)
			(layers "*.Cu" "*.Mask")
			(remove_unused_layers no)
			(net "I2C_BMC_COMP_SDA")
			(clearance 0.1651)
			(thermal_gap 0.1651)
		)
		(pad "C11" thru_hole circle
			(at 25.200102 -3.599942 180)
			(size 0.762 0.762)
			(drill 0.359918)
			(layers "*.Cu" "*.Mask")
			(remove_unused_layers no)
			(net "UART_COMP_RX")
			(clearance 0.1651)
			(thermal_gap 0.1651)
		)
		(pad "C12" thru_hole circle
			(at 26.999946 -2.400046 180)
			(size 0.762 0.762)
			(drill 0.359918)
			(layers "*.Cu" "*.Mask")
			(remove_unused_layers no)
			(net "COMP_PWR_EN")
			(clearance 0.1651)
			(thermal_gap 0.1651)
		)
		(pad "C13" thru_hole circle
			(at 28.800044 -3.599942 180)
			(size 0.762 0.762)
			(drill 0.359918)
			(layers "*.Cu" "*.Mask")
			(remove_unused_layers no)
			(net "COMP_POWER_FAIL_N")
			(clearance 0.1651)
			(thermal_gap 0.1651)
		)
		(pad "C14" thru_hole circle
			(at 30.599888 -2.400046 180)
			(size 0.762 0.762)
			(drill 0.359918)
			(layers "*.Cu" "*.Mask")
			(remove_unused_layers no)
			(net "Net_86")
			(clearance 0.1651)
			(thermal_gap 0.1651)
		)
		(pad "C15" thru_hole circle
			(at 32.399986 -3.599942 180)
			(size 0.762 0.762)
			(drill 0.359918)
			(layers "*.Cu" "*.Mask")
			(remove_unused_layers no)
			(net "Net_212")
			(clearance 0.1651)
			(thermal_gap 0.1651)
		)
		(pad "C16" thru_hole circle
			(at 34.200084 -2.400046 180)
			(size 0.762 0.762)
			(drill 0.359918)
			(layers "*.Cu" "*.Mask")
			(remove_unused_layers no)
			(net "PWM_OUT_ZONE_C")
			(clearance 0.1651)
			(thermal_gap 0.1651)
		)
		(pad "D1" thru_hole circle
			(at 0 -4.99999 180)
			(size 0.762 0.762)
			(drill 0.359918)
			(layers "*.Cu" "*.Mask")
			(remove_unused_layers no)
			(net "PCIE_COMP_TO_IOM_RST_2")
			(clearance 0.1651)
			(thermal_gap 0.1651)
		)
		(pad "D2" thru_hole circle
			(at 1.800098 -3.800094 180)
			(size 0.762 0.762)
			(drill 0.359918)
			(layers "*.Cu" "*.Mask")
			(remove_unused_layers no)
			(net "I2C_SCC_SCL")
			(clearance 0.1651)
			(thermal_gap 0.1651)
		)
		(pad "D3" thru_hole circle
			(at 3.599942 -4.99999 180)
			(size 0.762 0.762)
			(drill 0.359918)
			(layers "*.Cu" "*.Mask")
			(remove_unused_layers no)
			(net "SCC_LOC_HEARTBEAT")
			(clearance 0.1651)
			(thermal_gap 0.1651)
		)
		(pad "D4" thru_hole circle
			(at 5.40004 -3.800094 180)
			(size 0.762 0.762)
			(drill 0.359918)
			(layers "*.Cu" "*.Mask")
			(remove_unused_layers no)
			(net "SCC_STBY_PWR_EN")
			(clearance 0.1651)
			(thermal_gap 0.1651)
		)
		(pad "D5" thru_hole circle
			(at 7.199884 -4.99999 180)
			(size 0.762 0.762)
			(drill 0.359918)
			(layers "*.Cu" "*.Mask")
			(remove_unused_layers no)
			(net "PCIE_COMP_TO_IOM_RST_3")
			(clearance 0.1651)
			(thermal_gap 0.1651)
		)
		(pad "D6" thru_hole circle
			(at 8.999982 -3.800094 180)
			(size 0.762 0.762)
			(drill 0.359918)
			(layers "*.Cu" "*.Mask")
			(remove_unused_layers no)
			(net "I2C_EXP_RMT_SCL")
			(clearance 0.1651)
			(thermal_gap 0.1651)
		)
		(pad "D7" thru_hole circle
			(at 10.80008 -4.99999 180)
			(size 0.762 0.762)
			(drill 0.359918)
			(layers "*.Cu" "*.Mask")
			(remove_unused_layers no)
			(net "UART_SDB_TX")
			(clearance 0.1651)
			(thermal_gap 0.1651)
		)
		(pad "D8" thru_hole circle
			(at 12.599924 -3.800094 180)
			(size 0.762 0.762)
			(drill 0.359918)
			(layers "*.Cu" "*.Mask")
			(remove_unused_layers no)
			(net "P12V_IOM")
			(clearance 0.1651)
			(thermal_gap 0.1651)
		)
		(pad "D9" thru_hole circle
			(at 21.599906 -4.99999 180)
			(size 0.762 0.762)
			(drill 0.359918)
			(layers "*.Cu" "*.Mask")
			(remove_unused_layers no)
			(net "PCIE_COMP_TO_IOM_RST_4")
			(clearance 0.1651)
			(thermal_gap 0.1651)
		)
		(pad "D10" thru_hole circle
			(at 23.400004 -3.800094 180)
			(size 0.762 0.762)
			(drill 0.359918)
			(layers "*.Cu" "*.Mask")
			(remove_unused_layers no)
			(net "I2C_BMC_COMP_SCL")
			(clearance 0.1651)
			(thermal_gap 0.1651)
		)
		(pad "D11" thru_hole circle
			(at 25.200102 -4.99999 180)
			(size 0.762 0.762)
			(drill 0.359918)
			(layers "*.Cu" "*.Mask")
			(remove_unused_layers no)
			(net "UART_COMP_TX")
			(clearance 0.1651)
			(thermal_gap 0.1651)
		)
		(pad "D12" thru_hole circle
			(at 26.999946 -3.800094 180)
			(size 0.762 0.762)
			(drill 0.359918)
			(layers "*.Cu" "*.Mask")
			(remove_unused_layers no)
			(net "SCC_RMT_TYPE_0")
			(clearance 0.1651)
			(thermal_gap 0.1651)
		)
		(pad "D13" thru_hole circle
			(at 28.800044 -4.99999 180)
			(size 0.762 0.762)
			(drill 0.359918)
			(layers "*.Cu" "*.Mask")
			(remove_unused_layers no)
			(net "COMP_FAST_THROTTLE_N")
			(clearance 0.1651)
			(thermal_gap 0.1651)
		)
		(pad "D14" thru_hole circle
			(at 30.599888 -3.800094 180)
			(size 0.762 0.762)
			(drill 0.359918)
			(layers "*.Cu" "*.Mask")
			(remove_unused_layers no)
			(net "COMP_PWR_BTN_N")
			(clearance 0.1651)
			(thermal_gap 0.1651)
		)
		(pad "D15" thru_hole circle
			(at 32.399986 -4.99999 180)
			(size 0.762 0.762)
			(drill 0.359918)
			(layers "*.Cu" "*.Mask")
			(remove_unused_layers no)
			(net "ENCL_FAULT_LED")
			(clearance 0.1651)
			(thermal_gap 0.1651)
		)
		(pad "D16" thru_hole circle
			(at 34.200084 -3.800094 180)
			(size 0.762 0.762)
			(drill 0.359918)
			(layers "*.Cu" "*.Mask")
			(remove_unused_layers no)
			(net "PWM_OUT_ZONE_D")
			(clearance 0.1651)
			(thermal_gap 0.1651)
		)
		(pad "E1" thru_hole circle
			(at 0 -7.199884 180)
			(size 0.762 0.762)
			(drill 0.359918)
			(layers "*.Cu" "*.Mask")
			(remove_unused_layers no)
			(net "PCIE_IOM_TO_COMP_8_DN")
			(clearance 0.1651)
			(thermal_gap 0.1651)
		)
		(pad "E2" thru_hole circle
			(at 1.800098 -5.999988 180)
			(size 0.762 0.762)
			(drill 0.359918)
			(layers "*.Cu" "*.Mask")
			(remove_unused_layers no)
			(net "PCIE_IOM_TO_COMP_9_DN")
			(clearance 0.1651)
			(thermal_gap 0.1651)
		)
		(pad "E3" thru_hole circle
			(at 3.599942 -7.199884 180)
			(size 0.762 0.762)
			(drill 0.359918)
			(layers "*.Cu" "*.Mask")
			(remove_unused_layers no)
			(net "PCIE_IOM_TO_COMP_10_DN")
			(clearance 0.1651)
			(thermal_gap 0.1651)
		)
		(pad "E4" thru_hole circle
			(at 5.40004 -5.999988 180)
			(size 0.762 0.762)
			(drill 0.359918)
			(layers "*.Cu" "*.Mask")
			(remove_unused_layers no)
			(net "PCIE_IOM_TO_COMP_11_DN")
			(clearance 0.1651)
			(thermal_gap 0.1651)
		)
		(pad "E5" thru_hole circle
			(at 7.199884 -7.199884 180)
			(size 0.762 0.762)
			(drill 0.359918)
			(layers "*.Cu" "*.Mask")
			(remove_unused_layers no)
			(net "PCIE_IOM_TO_COMP_12_DN")
			(clearance 0.1651)
			(thermal_gap 0.1651)
		)
		(pad "E6" thru_hole circle
			(at 8.999982 -5.999988 180)
			(size 0.762 0.762)
			(drill 0.359918)
			(layers "*.Cu" "*.Mask")
			(remove_unused_layers no)
			(net "PCIE_IOM_TO_COMP_13_DN")
			(clearance 0.1651)
			(thermal_gap 0.1651)
		)
		(pad "E7" thru_hole circle
			(at 10.80008 -7.199884 180)
			(size 0.762 0.762)
			(drill 0.359918)
			(layers "*.Cu" "*.Mask")
			(remove_unused_layers no)
			(net "PCIE_IOM_TO_COMP_14_DN")
			(clearance 0.1651)
			(thermal_gap 0.1651)
		)
		(pad "E8" thru_hole circle
			(at 12.599924 -5.999988 180)
			(size 0.762 0.762)
			(drill 0.359918)
			(layers "*.Cu" "*.Mask")
			(remove_unused_layers no)
			(net "PCIE_IOM_TO_COMP_15_DN")
			(clearance 0.1651)
			(thermal_gap 0.1651)
		)
		(pad "E9" thru_hole circle
			(at 21.599906 -7.199884 180)
			(size 0.762 0.762)
			(drill 0.359918)
			(layers "*.Cu" "*.Mask")
			(remove_unused_layers no)
			(net "PCIE_IOM_TO_COMP_16_DN")
			(clearance 0.1651)
			(thermal_gap 0.1651)
		)
		(pad "E10" thru_hole circle
			(at 23.400004 -5.999988 180)
			(size 0.762 0.762)
			(drill 0.359918)
			(layers "*.Cu" "*.Mask")
			(remove_unused_layers no)
			(net "PCIE_IOM_TO_COMP_17_DN")
			(clearance 0.1651)
			(thermal_gap 0.1651)
		)
		(pad "E11" thru_hole circle
			(at 25.200102 -7.199884 180)
			(size 0.762 0.762)
			(drill 0.359918)
			(layers "*.Cu" "*.Mask")
			(remove_unused_layers no)
			(net "PCIE_IOM_TO_COMP_18_DN")
			(clearance 0.1651)
			(thermal_gap 0.1651)
		)
		(pad "E12" thru_hole circle
			(at 26.999946 -5.999988 180)
			(size 0.762 0.762)
			(drill 0.359918)
			(layers "*.Cu" "*.Mask")
			(remove_unused_layers no)
			(net "PCIE_IOM_TO_COMP_19_DN")
			(clearance 0.1651)
			(thermal_gap 0.1651)
		)
		(pad "E13" thru_hole circle
			(at 28.800044 -7.199884 180)
			(size 0.762 0.762)
			(drill 0.359918)
			(layers "*.Cu" "*.Mask")
			(remove_unused_layers no)
			(net "PCIE_IOM_TO_COMP_20_DN")
			(clearance 0.1651)
			(thermal_gap 0.1651)
		)
		(pad "E14" thru_hole circle
			(at 30.599888 -5.999988 180)
			(size 0.762 0.762)
			(drill 0.359918)
			(layers "*.Cu" "*.Mask")
			(remove_unused_layers no)
			(net "PCIE_IOM_TO_COMP_21_DN")
			(clearance 0.1651)
			(thermal_gap 0.1651)
		)
		(pad "E15" thru_hole circle
			(at 32.399986 -7.199884 180)
			(size 0.762 0.762)
			(drill 0.359918)
			(layers "*.Cu" "*.Mask")
			(remove_unused_layers no)
			(net "PCIE_IOM_TO_COMP_22_DN")
			(clearance 0.1651)
			(thermal_gap 0.1651)
		)
		(pad "E16" thru_hole circle
			(at 34.200084 -5.999988 180)
			(size 0.762 0.762)
			(drill 0.359918)
			(layers "*.Cu" "*.Mask")
			(remove_unused_layers no)
			(net "PCIE_IOM_TO_COMP_23_DN")
			(clearance 0.1651)
			(thermal_gap 0.1651)
		)
		(pad "F1" thru_hole circle
			(at 0 -8.599932 180)
			(size 0.762 0.762)
			(drill 0.359918)
			(layers "*.Cu" "*.Mask")
			(remove_unused_layers no)
			(net "PCIE_IOM_TO_COMP_8_DP")
			(clearance 0.1651)
			(thermal_gap 0.1651)
		)
		(pad "F2" thru_hole circle
			(at 1.800098 -7.400036 180)
			(size 0.762 0.762)
			(drill 0.359918)
			(layers "*.Cu" "*.Mask")
			(remove_unused_layers no)
			(net "PCIE_IOM_TO_COMP_9_DP")
			(clearance 0.1651)
			(thermal_gap 0.1651)
		)
		(pad "F3" thru_hole circle
			(at 3.599942 -8.599932 180)
			(size 0.762 0.762)
			(drill 0.359918)
			(layers "*.Cu" "*.Mask")
			(remove_unused_layers no)
			(net "PCIE_IOM_TO_COMP_10_DP")
			(clearance 0.1651)
			(thermal_gap 0.1651)
		)
		(pad "F4" thru_hole circle
			(at 5.40004 -7.400036 180)
			(size 0.762 0.762)
			(drill 0.359918)
			(layers "*.Cu" "*.Mask")
			(remove_unused_layers no)
			(net "PCIE_IOM_TO_COMP_11_DP")
			(clearance 0.1651)
			(thermal_gap 0.1651)
		)
		(pad "F5" thru_hole circle
			(at 7.199884 -8.599932 180)
			(size 0.762 0.762)
			(drill 0.359918)
			(layers "*.Cu" "*.Mask")
			(remove_unused_layers no)
			(net "PCIE_IOM_TO_COMP_12_DP")
			(clearance 0.1651)
			(thermal_gap 0.1651)
		)
		(pad "F6" thru_hole circle
			(at 8.999982 -7.400036 180)
			(size 0.762 0.762)
			(drill 0.359918)
			(layers "*.Cu" "*.Mask")
			(remove_unused_layers no)
			(net "PCIE_IOM_TO_COMP_13_DP")
			(clearance 0.1651)
			(thermal_gap 0.1651)
		)
		(pad "F7" thru_hole circle
			(at 10.80008 -8.599932 180)
			(size 0.762 0.762)
			(drill 0.359918)
			(layers "*.Cu" "*.Mask")
			(remove_unused_layers no)
			(net "PCIE_IOM_TO_COMP_14_DP")
			(clearance 0.1651)
			(thermal_gap 0.1651)
		)
		(pad "F8" thru_hole circle
			(at 12.599924 -7.400036 180)
			(size 0.762 0.762)
			(drill 0.359918)
			(layers "*.Cu" "*.Mask")
			(remove_unused_layers no)
			(net "PCIE_IOM_TO_COMP_15_DP")
			(clearance 0.1651)
			(thermal_gap 0.1651)
		)
		(pad "F9" thru_hole circle
			(at 21.599906 -8.599932 180)
			(size 0.762 0.762)
			(drill 0.359918)
			(layers "*.Cu" "*.Mask")
			(remove_unused_layers no)
			(net "PCIE_IOM_TO_COMP_16_DP")
			(clearance 0.1651)
			(thermal_gap 0.1651)
		)
		(pad "F10" thru_hole circle
			(at 23.400004 -7.400036 180)
			(size 0.762 0.762)
			(drill 0.359918)
			(layers "*.Cu" "*.Mask")
			(remove_unused_layers no)
			(net "PCIE_IOM_TO_COMP_17_DP")
			(clearance 0.1651)
			(thermal_gap 0.1651)
		)
		(pad "F11" thru_hole circle
			(at 25.200102 -8.599932 180)
			(size 0.762 0.762)
			(drill 0.359918)
			(layers "*.Cu" "*.Mask")
			(remove_unused_layers no)
			(net "PCIE_IOM_TO_COMP_18_DP")
			(clearance 0.1651)
			(thermal_gap 0.1651)
		)
		(pad "F12" thru_hole circle
			(at 26.999946 -7.400036 180)
			(size 0.762 0.762)
			(drill 0.359918)
			(layers "*.Cu" "*.Mask")
			(remove_unused_layers no)
			(net "PCIE_IOM_TO_COMP_19_DP")
			(clearance 0.1651)
			(thermal_gap 0.1651)
		)
		(pad "F13" thru_hole circle
			(at 28.800044 -8.599932 180)
			(size 0.762 0.762)
			(drill 0.359918)
			(layers "*.Cu" "*.Mask")
			(remove_unused_layers no)
			(net "PCIE_IOM_TO_COMP_20_DP")
			(clearance 0.1651)
			(thermal_gap 0.1651)
		)
		(pad "F14" thru_hole circle
			(at 30.599888 -7.400036 180)
			(size 0.762 0.762)
			(drill 0.359918)
			(layers "*.Cu" "*.Mask")
			(remove_unused_layers no)
			(net "PCIE_IOM_TO_COMP_21_DP")
			(clearance 0.1651)
			(thermal_gap 0.1651)
		)
		(pad "F15" thru_hole circle
			(at 32.399986 -8.599932 180)
			(size 0.762 0.762)
			(drill 0.359918)
			(layers "*.Cu" "*.Mask")
			(remove_unused_layers no)
			(net "PCIE_IOM_TO_COMP_22_DP")
			(clearance 0.1651)
			(thermal_gap 0.1651)
		)
		(pad "F16" thru_hole circle
			(at 34.200084 -7.400036 180)
			(size 0.762 0.762)
			(drill 0.359918)
			(layers "*.Cu" "*.Mask")
			(remove_unused_layers no)
			(net "PCIE_IOM_TO_COMP_23_DP")
			(clearance 0.1651)
			(thermal_gap 0.1651)
		)
		(pad "G1" thru_hole circle
			(at 0 -10.80008 180)
			(size 0.762 0.762)
			(drill 0.359918)
			(layers "*.Cu" "*.Mask")
			(remove_unused_layers no)
			(net "PCIE_COMP_TO_IOM_8_DN")
			(clearance 0.1651)
			(thermal_gap 0.1651)
		)
		(pad "G2" thru_hole circle
			(at 1.800098 -9.59993 180)
			(size 0.762 0.762)
			(drill 0.359918)
			(layers "*.Cu" "*.Mask")
			(remove_unused_layers no)
			(net "PCIE_COMP_TO_IOM_9_DN")
			(clearance 0.1651)
			(thermal_gap 0.1651)
		)
		(pad "G3" thru_hole circle
			(at 3.599942 -10.80008 180)
			(size 0.762 0.762)
			(drill 0.359918)
			(layers "*.Cu" "*.Mask")
			(remove_unused_layers no)
			(net "PCIE_COMP_TO_IOM_10_DN")
			(clearance 0.1651)
			(thermal_gap 0.1651)
		)
		(pad "G4" thru_hole circle
			(at 5.40004 -9.59993 180)
			(size 0.762 0.762)
			(drill 0.359918)
			(layers "*.Cu" "*.Mask")
			(remove_unused_layers no)
			(net "PCIE_COMP_TO_IOM_11_DN")
			(clearance 0.1651)
			(thermal_gap 0.1651)
		)
		(pad "G5" thru_hole circle
			(at 7.199884 -10.80008 180)
			(size 0.762 0.762)
			(drill 0.359918)
			(layers "*.Cu" "*.Mask")
			(remove_unused_layers no)
			(net "PCIE_COMP_TO_IOM_12_DN")
			(clearance 0.1651)
			(thermal_gap 0.1651)
		)
		(pad "G6" thru_hole circle
			(at 8.999982 -9.59993 180)
			(size 0.762 0.762)
			(drill 0.359918)
			(layers "*.Cu" "*.Mask")
			(remove_unused_layers no)
			(net "PCIE_COMP_TO_IOM_13_DN")
			(clearance 0.1651)
			(thermal_gap 0.1651)
		)
		(pad "G7" thru_hole circle
			(at 10.80008 -10.80008 180)
			(size 0.762 0.762)
			(drill 0.359918)
			(layers "*.Cu" "*.Mask")
			(remove_unused_layers no)
			(net "PCIE_COMP_TO_IOM_14_DN")
			(clearance 0.1651)
			(thermal_gap 0.1651)
		)
		(pad "G8" thru_hole circle
			(at 12.599924 -9.59993 180)
			(size 0.762 0.762)
			(drill 0.359918)
			(layers "*.Cu" "*.Mask")
			(remove_unused_layers no)
			(net "PCIE_COMP_TO_IOM_15_DN")
			(clearance 0.1651)
			(thermal_gap 0.1651)
		)
		(pad "G9" thru_hole circle
			(at 21.599906 -10.80008 180)
			(size 0.762 0.762)
			(drill 0.359918)
			(layers "*.Cu" "*.Mask")
			(remove_unused_layers no)
			(net "PCIE_COMP_TO_IOM_16_DN")
			(clearance 0.1651)
			(thermal_gap 0.1651)
		)
		(pad "G10" thru_hole circle
			(at 23.400004 -9.59993 180)
			(size 0.762 0.762)
			(drill 0.359918)
			(layers "*.Cu" "*.Mask")
			(remove_unused_layers no)
			(net "PCIE_COMP_TO_IOM_17_DN")
			(clearance 0.1651)
			(thermal_gap 0.1651)
		)
		(pad "G11" thru_hole circle
			(at 25.200102 -10.80008 180)
			(size 0.762 0.762)
			(drill 0.359918)
			(layers "*.Cu" "*.Mask")
			(remove_unused_layers no)
			(net "PCIE_COMP_TO_IOM_18_DN")
			(clearance 0.1651)
			(thermal_gap 0.1651)
		)
		(pad "G12" thru_hole circle
			(at 26.999946 -9.59993 180)
			(size 0.762 0.762)
			(drill 0.359918)
			(layers "*.Cu" "*.Mask")
			(remove_unused_layers no)
			(net "PCIE_COMP_TO_IOM_19_DN")
			(clearance 0.1651)
			(thermal_gap 0.1651)
		)
		(pad "G13" thru_hole circle
			(at 28.800044 -10.80008 180)
			(size 0.762 0.762)
			(drill 0.359918)
			(layers "*.Cu" "*.Mask")
			(remove_unused_layers no)
			(net "PCIE_COMP_TO_IOM_20_DN")
			(clearance 0.1651)
			(thermal_gap 0.1651)
		)
		(pad "G14" thru_hole circle
			(at 30.599888 -9.59993 180)
			(size 0.762 0.762)
			(drill 0.359918)
			(layers "*.Cu" "*.Mask")
			(remove_unused_layers no)
			(net "PCIE_COMP_TO_IOM_21_DN")
			(clearance 0.1651)
			(thermal_gap 0.1651)
		)
		(pad "G15" thru_hole circle
			(at 32.399986 -10.80008 180)
			(size 0.762 0.762)
			(drill 0.359918)
			(layers "*.Cu" "*.Mask")
			(remove_unused_layers no)
			(net "PCIE_COMP_TO_IOM_22_DN")
			(clearance 0.1651)
			(thermal_gap 0.1651)
		)
		(pad "G16" thru_hole circle
			(at 34.200084 -9.59993 180)
			(size 0.762 0.762)
			(drill 0.359918)
			(layers "*.Cu" "*.Mask")
			(remove_unused_layers no)
			(net "PCIE_COMP_TO_IOM_23_DN")
			(clearance 0.1651)
			(thermal_gap 0.1651)
		)
		(pad "GND1" thru_hole circle
			(at 0 -2.500122 180)
			(size 0.762 0.762)
			(drill 0.359918)
			(layers "*.Cu" "*.Mask")
			(remove_unused_layers no)
			(net "GND")
			(clearance 0.1651)
			(thermal_gap 0.1651)
		)
		(pad "GND2" thru_hole circle
			(at 0 -6.100064 180)
			(size 0.762 0.762)
			(drill 0.359918)
			(layers "*.Cu" "*.Mask")
			(remove_unused_layers no)
			(net "GND")
			(clearance 0.1651)
			(thermal_gap 0.1651)
		)
		(pad "GND3" thru_hole circle
			(at 0 -9.700006 180)
			(size 0.762 0.762)
			(drill 0.359918)
			(layers "*.Cu" "*.Mask")
			(remove_unused_layers no)
			(net "GND")
			(clearance 0.1651)
			(thermal_gap 0.1651)
		)
		(pad "GND4" thru_hole circle
			(at 0 -13.299948 180)
			(size 0.762 0.762)
			(drill 0.359918)
			(layers "*.Cu" "*.Mask")
			(remove_unused_layers no)
			(net "GND")
			(clearance 0.1651)
			(thermal_gap 0.1651)
		)
		(pad "GND5" thru_hole circle
			(at 1.800098 2.29997 180)
			(size 0.762 0.762)
			(drill 0.359918)
			(layers "*.Cu" "*.Mask")
			(remove_unused_layers no)
			(net "GND")
			(clearance 0.1651)
			(thermal_gap 0.1651)
		)
		(pad "GND6" thru_hole circle
			(at 1.800098 -1.299972 180)
			(size 0.762 0.762)
			(drill 0.359918)
			(layers "*.Cu" "*.Mask")
			(remove_unused_layers no)
			(net "GND")
			(clearance 0.1651)
			(thermal_gap 0.1651)
		)
		(pad "GND7" thru_hole circle
			(at 1.800098 -4.899914 180)
			(size 0.762 0.762)
			(drill 0.359918)
			(layers "*.Cu" "*.Mask")
			(remove_unused_layers no)
			(net "GND")
			(clearance 0.1651)
			(thermal_gap 0.1651)
		)
		(pad "GND8" thru_hole circle
			(at 1.800098 -8.50011 180)
			(size 0.762 0.762)
			(drill 0.359918)
			(layers "*.Cu" "*.Mask")
			(remove_unused_layers no)
			(net "GND")
			(clearance 0.1651)
			(thermal_gap 0.1651)
		)
		(pad "GND9" thru_hole circle
			(at 1.800098 -12.100052 180)
			(size 0.762 0.762)
			(drill 0.359918)
			(layers "*.Cu" "*.Mask")
			(remove_unused_layers no)
			(net "GND")
			(clearance 0.1651)
			(thermal_gap 0.1651)
		)
		(pad "GND10" thru_hole circle
			(at 3.599942 -2.500122 180)
			(size 0.762 0.762)
			(drill 0.359918)
			(layers "*.Cu" "*.Mask")
			(remove_unused_layers no)
			(net "GND")
			(clearance 0.1651)
			(thermal_gap 0.1651)
		)
		(pad "GND11" thru_hole circle
			(at 3.599942 -6.100064 180)
			(size 0.762 0.762)
			(drill 0.359918)
			(layers "*.Cu" "*.Mask")
			(remove_unused_layers no)
			(net "GND")
			(clearance 0.1651)
			(thermal_gap 0.1651)
		)
		(pad "GND12" thru_hole circle
			(at 3.599942 -9.700006 180)
			(size 0.762 0.762)
			(drill 0.359918)
			(layers "*.Cu" "*.Mask")
			(remove_unused_layers no)
			(net "GND")
			(clearance 0.1651)
			(thermal_gap 0.1651)
		)
		(pad "GND13" thru_hole circle
			(at 3.599942 -13.299948 180)
			(size 0.762 0.762)
			(drill 0.359918)
			(layers "*.Cu" "*.Mask")
			(remove_unused_layers no)
			(net "GND")
			(clearance 0.1651)
			(thermal_gap 0.1651)
		)
		(pad "GND14" thru_hole circle
			(at 5.40004 2.29997 180)
			(size 0.762 0.762)
			(drill 0.359918)
			(layers "*.Cu" "*.Mask")
			(remove_unused_layers no)
			(net "GND")
			(clearance 0.1651)
			(thermal_gap 0.1651)
		)
		(pad "GND15" thru_hole circle
			(at 5.40004 -1.299972 180)
			(size 0.762 0.762)
			(drill 0.359918)
			(layers "*.Cu" "*.Mask")
			(remove_unused_layers no)
			(net "GND")
			(clearance 0.1651)
			(thermal_gap 0.1651)
		)
		(pad "GND16" thru_hole circle
			(at 5.40004 -4.899914 180)
			(size 0.762 0.762)
			(drill 0.359918)
			(layers "*.Cu" "*.Mask")
			(remove_unused_layers no)
			(net "GND")
			(clearance 0.1651)
			(thermal_gap 0.1651)
		)
		(pad "GND17" thru_hole circle
			(at 5.40004 -8.50011 180)
			(size 0.762 0.762)
			(drill 0.359918)
			(layers "*.Cu" "*.Mask")
			(remove_unused_layers no)
			(net "GND")
			(clearance 0.1651)
			(thermal_gap 0.1651)
		)
		(pad "GND18" thru_hole circle
			(at 5.40004 -12.100052 180)
			(size 0.762 0.762)
			(drill 0.359918)
			(layers "*.Cu" "*.Mask")
			(remove_unused_layers no)
			(net "GND")
			(clearance 0.1651)
			(thermal_gap 0.1651)
		)
		(pad "GND19" thru_hole circle
			(at 7.199884 -2.500122 180)
			(size 0.762 0.762)
			(drill 0.359918)
			(layers "*.Cu" "*.Mask")
			(remove_unused_layers no)
			(net "GND")
			(clearance 0.1651)
			(thermal_gap 0.1651)
		)
		(pad "GND20" thru_hole circle
			(at 7.199884 -6.100064 180)
			(size 0.762 0.762)
			(drill 0.359918)
			(layers "*.Cu" "*.Mask")
			(remove_unused_layers no)
			(net "GND")
			(clearance 0.1651)
			(thermal_gap 0.1651)
		)
		(pad "GND21" thru_hole circle
			(at 7.199884 -9.700006 180)
			(size 0.762 0.762)
			(drill 0.359918)
			(layers "*.Cu" "*.Mask")
			(remove_unused_layers no)
			(net "GND")
			(clearance 0.1651)
			(thermal_gap 0.1651)
		)
		(pad "GND22" thru_hole circle
			(at 7.199884 -13.299948 180)
			(size 0.762 0.762)
			(drill 0.359918)
			(layers "*.Cu" "*.Mask")
			(remove_unused_layers no)
			(net "GND")
			(clearance 0.1651)
			(thermal_gap 0.1651)
		)
		(pad "GND23" thru_hole circle
			(at 8.999982 2.29997 180)
			(size 0.762 0.762)
			(drill 0.359918)
			(layers "*.Cu" "*.Mask")
			(remove_unused_layers no)
			(net "GND")
			(clearance 0.1651)
			(thermal_gap 0.1651)
		)
		(pad "GND24" thru_hole circle
			(at 8.999982 -1.299972 180)
			(size 0.762 0.762)
			(drill 0.359918)
			(layers "*.Cu" "*.Mask")
			(remove_unused_layers no)
			(net "GND")
			(clearance 0.1651)
			(thermal_gap 0.1651)
		)
		(pad "GND25" thru_hole circle
			(at 8.999982 -4.899914 180)
			(size 0.762 0.762)
			(drill 0.359918)
			(layers "*.Cu" "*.Mask")
			(remove_unused_layers no)
			(net "GND")
			(clearance 0.1651)
			(thermal_gap 0.1651)
		)
		(pad "GND26" thru_hole circle
			(at 8.999982 -8.50011 180)
			(size 0.762 0.762)
			(drill 0.359918)
			(layers "*.Cu" "*.Mask")
			(remove_unused_layers no)
			(net "GND")
			(clearance 0.1651)
			(thermal_gap 0.1651)
		)
		(pad "GND27" thru_hole circle
			(at 8.999982 -12.100052 180)
			(size 0.762 0.762)
			(drill 0.359918)
			(layers "*.Cu" "*.Mask")
			(remove_unused_layers no)
			(net "GND")
			(clearance 0.1651)
			(thermal_gap 0.1651)
		)
		(pad "GND28" thru_hole circle
			(at 10.80008 -2.500122 180)
			(size 0.762 0.762)
			(drill 0.359918)
			(layers "*.Cu" "*.Mask")
			(remove_unused_layers no)
			(net "GND")
			(clearance 0.1651)
			(thermal_gap 0.1651)
		)
		(pad "GND29" thru_hole circle
			(at 10.80008 -6.100064 180)
			(size 0.762 0.762)
			(drill 0.359918)
			(layers "*.Cu" "*.Mask")
			(remove_unused_layers no)
			(net "GND")
			(clearance 0.1651)
			(thermal_gap 0.1651)
		)
		(pad "GND30" thru_hole circle
			(at 10.80008 -9.700006 180)
			(size 0.762 0.762)
			(drill 0.359918)
			(layers "*.Cu" "*.Mask")
			(remove_unused_layers no)
			(net "GND")
			(clearance 0.1651)
			(thermal_gap 0.1651)
		)
		(pad "GND31" thru_hole circle
			(at 10.80008 -13.299948 180)
			(size 0.762 0.762)
			(drill 0.359918)
			(layers "*.Cu" "*.Mask")
			(remove_unused_layers no)
			(net "GND")
			(clearance 0.1651)
			(thermal_gap 0.1651)
		)
		(pad "GND32" thru_hole circle
			(at 12.599924 2.29997 180)
			(size 0.762 0.762)
			(drill 0.359918)
			(layers "*.Cu" "*.Mask")
			(remove_unused_layers no)
			(net "GND")
			(clearance 0.1651)
			(thermal_gap 0.1651)
		)
		(pad "GND33" thru_hole circle
			(at 12.599924 -1.299972 180)
			(size 0.762 0.762)
			(drill 0.359918)
			(layers "*.Cu" "*.Mask")
			(remove_unused_layers no)
			(net "GND")
			(clearance 0.1651)
			(thermal_gap 0.1651)
		)
		(pad "GND34" thru_hole circle
			(at 12.599924 -4.899914 180)
			(size 0.762 0.762)
			(drill 0.359918)
			(layers "*.Cu" "*.Mask")
			(remove_unused_layers no)
			(net "GND")
			(clearance 0.1651)
			(thermal_gap 0.1651)
		)
		(pad "GND35" thru_hole circle
			(at 12.599924 -8.50011 180)
			(size 0.762 0.762)
			(drill 0.359918)
			(layers "*.Cu" "*.Mask")
			(remove_unused_layers no)
			(net "GND")
			(clearance 0.1651)
			(thermal_gap 0.1651)
		)
		(pad "GND36" thru_hole circle
			(at 12.599924 -12.100052 180)
			(size 0.762 0.762)
			(drill 0.359918)
			(layers "*.Cu" "*.Mask")
			(remove_unused_layers no)
			(net "GND")
			(clearance 0.1651)
			(thermal_gap 0.1651)
		)
		(pad "GND37" thru_hole circle
			(at 21.599906 -2.500122 180)
			(size 0.762 0.762)
			(drill 0.359918)
			(layers "*.Cu" "*.Mask")
			(remove_unused_layers no)
			(net "GND")
			(clearance 0.1651)
			(thermal_gap 0.1651)
		)
		(pad "GND38" thru_hole circle
			(at 21.599906 -6.100064 180)
			(size 0.762 0.762)
			(drill 0.359918)
			(layers "*.Cu" "*.Mask")
			(remove_unused_layers no)
			(net "GND")
			(clearance 0.1651)
			(thermal_gap 0.1651)
		)
		(pad "GND39" thru_hole circle
			(at 21.599906 -9.700006 180)
			(size 0.762 0.762)
			(drill 0.359918)
			(layers "*.Cu" "*.Mask")
			(remove_unused_layers no)
			(net "GND")
			(clearance 0.1651)
			(thermal_gap 0.1651)
		)
		(pad "GND40" thru_hole circle
			(at 21.599906 -13.299948 180)
			(size 0.762 0.762)
			(drill 0.359918)
			(layers "*.Cu" "*.Mask")
			(remove_unused_layers no)
			(net "GND")
			(clearance 0.1651)
			(thermal_gap 0.1651)
		)
		(pad "GND41" thru_hole circle
			(at 23.400004 2.29997 180)
			(size 0.762 0.762)
			(drill 0.359918)
			(layers "*.Cu" "*.Mask")
			(remove_unused_layers no)
			(net "GND")
			(clearance 0.1651)
			(thermal_gap 0.1651)
		)
		(pad "GND42" thru_hole circle
			(at 23.400004 -1.299972 180)
			(size 0.762 0.762)
			(drill 0.359918)
			(layers "*.Cu" "*.Mask")
			(remove_unused_layers no)
			(net "GND")
			(clearance 0.1651)
			(thermal_gap 0.1651)
		)
		(pad "GND43" thru_hole circle
			(at 23.400004 -4.899914 180)
			(size 0.762 0.762)
			(drill 0.359918)
			(layers "*.Cu" "*.Mask")
			(remove_unused_layers no)
			(net "GND")
			(clearance 0.1651)
			(thermal_gap 0.1651)
		)
		(pad "GND44" thru_hole circle
			(at 23.400004 -8.50011 180)
			(size 0.762 0.762)
			(drill 0.359918)
			(layers "*.Cu" "*.Mask")
			(remove_unused_layers no)
			(net "GND")
			(clearance 0.1651)
			(thermal_gap 0.1651)
		)
		(pad "GND45" thru_hole circle
			(at 23.400004 -12.100052 180)
			(size 0.762 0.762)
			(drill 0.359918)
			(layers "*.Cu" "*.Mask")
			(remove_unused_layers no)
			(net "GND")
			(clearance 0.1651)
			(thermal_gap 0.1651)
		)
		(pad "GND46" thru_hole circle
			(at 25.200102 -2.500122 180)
			(size 0.762 0.762)
			(drill 0.359918)
			(layers "*.Cu" "*.Mask")
			(remove_unused_layers no)
			(net "GND")
			(clearance 0.1651)
			(thermal_gap 0.1651)
		)
		(pad "GND47" thru_hole circle
			(at 25.200102 -6.100064 180)
			(size 0.762 0.762)
			(drill 0.359918)
			(layers "*.Cu" "*.Mask")
			(remove_unused_layers no)
			(net "GND")
			(clearance 0.1651)
			(thermal_gap 0.1651)
		)
		(pad "GND48" thru_hole circle
			(at 25.200102 -9.700006 180)
			(size 0.762 0.762)
			(drill 0.359918)
			(layers "*.Cu" "*.Mask")
			(remove_unused_layers no)
			(net "GND")
			(clearance 0.1651)
			(thermal_gap 0.1651)
		)
		(pad "GND49" thru_hole circle
			(at 25.200102 -13.299948 180)
			(size 0.762 0.762)
			(drill 0.359918)
			(layers "*.Cu" "*.Mask")
			(remove_unused_layers no)
			(net "GND")
			(clearance 0.1651)
			(thermal_gap 0.1651)
		)
		(pad "GND50" thru_hole circle
			(at 26.999946 2.29997 180)
			(size 0.762 0.762)
			(drill 0.359918)
			(layers "*.Cu" "*.Mask")
			(remove_unused_layers no)
			(net "GND")
			(clearance 0.1651)
			(thermal_gap 0.1651)
		)
		(pad "GND51" thru_hole circle
			(at 26.999946 -1.299972 180)
			(size 0.762 0.762)
			(drill 0.359918)
			(layers "*.Cu" "*.Mask")
			(remove_unused_layers no)
			(net "GND")
			(clearance 0.1651)
			(thermal_gap 0.1651)
		)
		(pad "GND52" thru_hole circle
			(at 26.999946 -4.899914 180)
			(size 0.762 0.762)
			(drill 0.359918)
			(layers "*.Cu" "*.Mask")
			(remove_unused_layers no)
			(net "GND")
			(clearance 0.1651)
			(thermal_gap 0.1651)
		)
		(pad "GND53" thru_hole circle
			(at 26.999946 -8.50011 180)
			(size 0.762 0.762)
			(drill 0.359918)
			(layers "*.Cu" "*.Mask")
			(remove_unused_layers no)
			(net "GND")
			(clearance 0.1651)
			(thermal_gap 0.1651)
		)
		(pad "GND54" thru_hole circle
			(at 26.999946 -12.100052 180)
			(size 0.762 0.762)
			(drill 0.359918)
			(layers "*.Cu" "*.Mask")
			(remove_unused_layers no)
			(net "GND")
			(clearance 0.1651)
			(thermal_gap 0.1651)
		)
		(pad "GND55" thru_hole circle
			(at 28.800044 -2.500122 180)
			(size 0.762 0.762)
			(drill 0.359918)
			(layers "*.Cu" "*.Mask")
			(remove_unused_layers no)
			(net "GND")
			(clearance 0.1651)
			(thermal_gap 0.1651)
		)
		(pad "GND56" thru_hole circle
			(at 28.800044 -6.100064 180)
			(size 0.762 0.762)
			(drill 0.359918)
			(layers "*.Cu" "*.Mask")
			(remove_unused_layers no)
			(net "GND")
			(clearance 0.1651)
			(thermal_gap 0.1651)
		)
		(pad "GND57" thru_hole circle
			(at 28.800044 -9.700006 180)
			(size 0.762 0.762)
			(drill 0.359918)
			(layers "*.Cu" "*.Mask")
			(remove_unused_layers no)
			(net "GND")
			(clearance 0.1651)
			(thermal_gap 0.1651)
		)
		(pad "GND58" thru_hole circle
			(at 28.800044 -13.299948 180)
			(size 0.762 0.762)
			(drill 0.359918)
			(layers "*.Cu" "*.Mask")
			(remove_unused_layers no)
			(net "GND")
			(clearance 0.1651)
			(thermal_gap 0.1651)
		)
		(pad "GND59" thru_hole circle
			(at 30.599888 2.29997 180)
			(size 0.762 0.762)
			(drill 0.359918)
			(layers "*.Cu" "*.Mask")
			(remove_unused_layers no)
			(net "GND")
			(clearance 0.1651)
			(thermal_gap 0.1651)
		)
		(pad "GND60" thru_hole circle
			(at 30.599888 -1.299972 180)
			(size 0.762 0.762)
			(drill 0.359918)
			(layers "*.Cu" "*.Mask")
			(remove_unused_layers no)
			(net "GND")
			(clearance 0.1651)
			(thermal_gap 0.1651)
		)
		(pad "GND61" thru_hole circle
			(at 30.599888 -4.899914 180)
			(size 0.762 0.762)
			(drill 0.359918)
			(layers "*.Cu" "*.Mask")
			(remove_unused_layers no)
			(net "GND")
			(clearance 0.1651)
			(thermal_gap 0.1651)
		)
		(pad "GND62" thru_hole circle
			(at 30.599888 -8.50011 180)
			(size 0.762 0.762)
			(drill 0.359918)
			(layers "*.Cu" "*.Mask")
			(remove_unused_layers no)
			(net "GND")
			(clearance 0.1651)
			(thermal_gap 0.1651)
		)
		(pad "GND63" thru_hole circle
			(at 30.599888 -12.100052 180)
			(size 0.762 0.762)
			(drill 0.359918)
			(layers "*.Cu" "*.Mask")
			(remove_unused_layers no)
			(net "GND")
			(clearance 0.1651)
			(thermal_gap 0.1651)
		)
		(pad "GND64" thru_hole circle
			(at 32.399986 -2.500122 180)
			(size 0.762 0.762)
			(drill 0.359918)
			(layers "*.Cu" "*.Mask")
			(remove_unused_layers no)
			(net "GND")
			(clearance 0.1651)
			(thermal_gap 0.1651)
		)
		(pad "GND65" thru_hole circle
			(at 32.399986 -6.100064 180)
			(size 0.762 0.762)
			(drill 0.359918)
			(layers "*.Cu" "*.Mask")
			(remove_unused_layers no)
			(net "GND")
			(clearance 0.1651)
			(thermal_gap 0.1651)
		)
		(pad "GND66" thru_hole circle
			(at 32.399986 -9.700006 180)
			(size 0.762 0.762)
			(drill 0.359918)
			(layers "*.Cu" "*.Mask")
			(remove_unused_layers no)
			(net "GND")
			(clearance 0.1651)
			(thermal_gap 0.1651)
		)
		(pad "GND67" thru_hole circle
			(at 32.399986 -13.299948 180)
			(size 0.762 0.762)
			(drill 0.359918)
			(layers "*.Cu" "*.Mask")
			(remove_unused_layers no)
			(net "GND")
			(clearance 0.1651)
			(thermal_gap 0.1651)
		)
		(pad "GND68" thru_hole circle
			(at 34.200084 2.29997 180)
			(size 0.762 0.762)
			(drill 0.359918)
			(layers "*.Cu" "*.Mask")
			(remove_unused_layers no)
			(net "GND")
			(clearance 0.1651)
			(thermal_gap 0.1651)
		)
		(pad "GND69" thru_hole circle
			(at 34.200084 -1.299972 180)
			(size 0.762 0.762)
			(drill 0.359918)
			(layers "*.Cu" "*.Mask")
			(remove_unused_layers no)
			(net "GND")
			(clearance 0.1651)
			(thermal_gap 0.1651)
		)
		(pad "GND70" thru_hole circle
			(at 34.200084 -4.899914 180)
			(size 0.762 0.762)
			(drill 0.359918)
			(layers "*.Cu" "*.Mask")
			(remove_unused_layers no)
			(net "GND")
			(clearance 0.1651)
			(thermal_gap 0.1651)
		)
		(pad "GND71" thru_hole circle
			(at 34.200084 -8.50011 180)
			(size 0.762 0.762)
			(drill 0.359918)
			(layers "*.Cu" "*.Mask")
			(remove_unused_layers no)
			(net "GND")
			(clearance 0.1651)
			(thermal_gap 0.1651)
		)
		(pad "GND72" thru_hole circle
			(at 34.200084 -12.100052 180)
			(size 0.762 0.762)
			(drill 0.359918)
			(layers "*.Cu" "*.Mask")
			(remove_unused_layers no)
			(net "GND")
			(clearance 0.1651)
			(thermal_gap 0.1651)
		)
		(pad "H1" thru_hole circle
			(at 0 -12.199874 180)
			(size 0.762 0.762)
			(drill 0.359918)
			(layers "*.Cu" "*.Mask")
			(remove_unused_layers no)
			(net "PCIE_COMP_TO_IOM_8_DP")
			(clearance 0.1651)
			(thermal_gap 0.1651)
		)
		(pad "H2" thru_hole circle
			(at 1.800098 -10.999978 180)
			(size 0.762 0.762)
			(drill 0.359918)
			(layers "*.Cu" "*.Mask")
			(remove_unused_layers no)
			(net "PCIE_COMP_TO_IOM_9_DP")
			(clearance 0.1651)
			(thermal_gap 0.1651)
		)
		(pad "H3" thru_hole circle
			(at 3.599942 -12.199874 180)
			(size 0.762 0.762)
			(drill 0.359918)
			(layers "*.Cu" "*.Mask")
			(remove_unused_layers no)
			(net "PCIE_COMP_TO_IOM_10_DP")
			(clearance 0.1651)
			(thermal_gap 0.1651)
		)
		(pad "H4" thru_hole circle
			(at 5.40004 -10.999978 180)
			(size 0.762 0.762)
			(drill 0.359918)
			(layers "*.Cu" "*.Mask")
			(remove_unused_layers no)
			(net "PCIE_COMP_TO_IOM_11_DP")
			(clearance 0.1651)
			(thermal_gap 0.1651)
		)
		(pad "H5" thru_hole circle
			(at 7.199884 -12.199874 180)
			(size 0.762 0.762)
			(drill 0.359918)
			(layers "*.Cu" "*.Mask")
			(remove_unused_layers no)
			(net "PCIE_COMP_TO_IOM_12_DP")
			(clearance 0.1651)
			(thermal_gap 0.1651)
		)
		(pad "H6" thru_hole circle
			(at 8.999982 -10.999978 180)
			(size 0.762 0.762)
			(drill 0.359918)
			(layers "*.Cu" "*.Mask")
			(remove_unused_layers no)
			(net "PCIE_COMP_TO_IOM_13_DP")
			(clearance 0.1651)
			(thermal_gap 0.1651)
		)
		(pad "H7" thru_hole circle
			(at 10.80008 -12.199874 180)
			(size 0.762 0.762)
			(drill 0.359918)
			(layers "*.Cu" "*.Mask")
			(remove_unused_layers no)
			(net "PCIE_COMP_TO_IOM_14_DP")
			(clearance 0.1651)
			(thermal_gap 0.1651)
		)
		(pad "H8" thru_hole circle
			(at 12.599924 -10.999978 180)
			(size 0.762 0.762)
			(drill 0.359918)
			(layers "*.Cu" "*.Mask")
			(remove_unused_layers no)
			(net "PCIE_COMP_TO_IOM_15_DP")
			(clearance 0.1651)
			(thermal_gap 0.1651)
		)
		(pad "H9" thru_hole circle
			(at 21.599906 -12.199874 180)
			(size 0.762 0.762)
			(drill 0.359918)
			(layers "*.Cu" "*.Mask")
			(remove_unused_layers no)
			(net "PCIE_COMP_TO_IOM_16_DP")
			(clearance 0.1651)
			(thermal_gap 0.1651)
		)
		(pad "H10" thru_hole circle
			(at 23.400004 -10.999978 180)
			(size 0.762 0.762)
			(drill 0.359918)
			(layers "*.Cu" "*.Mask")
			(remove_unused_layers no)
			(net "PCIE_COMP_TO_IOM_17_DP")
			(clearance 0.1651)
			(thermal_gap 0.1651)
		)
		(pad "H11" thru_hole circle
			(at 25.200102 -12.199874 180)
			(size 0.762 0.762)
			(drill 0.359918)
			(layers "*.Cu" "*.Mask")
			(remove_unused_layers no)
			(net "PCIE_COMP_TO_IOM_18_DP")
			(clearance 0.1651)
			(thermal_gap 0.1651)
		)
		(pad "H12" thru_hole circle
			(at 26.999946 -10.999978 180)
			(size 0.762 0.762)
			(drill 0.359918)
			(layers "*.Cu" "*.Mask")
			(remove_unused_layers no)
			(net "PCIE_COMP_TO_IOM_19_DP")
			(clearance 0.1651)
			(thermal_gap 0.1651)
		)
		(pad "H13" thru_hole circle
			(at 28.800044 -12.199874 180)
			(size 0.762 0.762)
			(drill 0.359918)
			(layers "*.Cu" "*.Mask")
			(remove_unused_layers no)
			(net "PCIE_COMP_TO_IOM_20_DP")
			(clearance 0.1651)
			(thermal_gap 0.1651)
		)
		(pad "H14" thru_hole circle
			(at 30.599888 -10.999978 180)
			(size 0.762 0.762)
			(drill 0.359918)
			(layers "*.Cu" "*.Mask")
			(remove_unused_layers no)
			(net "PCIE_COMP_TO_IOM_21_DP")
			(clearance 0.1651)
			(thermal_gap 0.1651)
		)
		(pad "H15" thru_hole circle
			(at 32.399986 -12.199874 180)
			(size 0.762 0.762)
			(drill 0.359918)
			(layers "*.Cu" "*.Mask")
			(remove_unused_layers no)
			(net "PCIE_COMP_TO_IOM_22_DP")
			(clearance 0.1651)
			(thermal_gap 0.1651)
		)
		(pad "H16" thru_hole circle
			(at 34.200084 -10.999978 180)
			(size 0.762 0.762)
			(drill 0.359918)
			(layers "*.Cu" "*.Mask")
			(remove_unused_layers no)
			(net "PCIE_COMP_TO_IOM_23_DP")
			(clearance 0.1651)
			(thermal_gap 0.1651)
		)
		(zone
			(layer "F.Cu")
			(hatch none 0.5)
			(connect_pads
				(clearance 0)
			)
			(min_thickness 0.25)
			(keepout
				(tracks allowed)
				(vias not_allowed)
				(pads allowed)
				(copperpour not_allowed)
				(footprints allowed)
			)
			(placement
				(enabled no)
				(sheetname "")
			)
			(fill
				(thermal_gap 0.5)
				(thermal_bridge_width 0.5)
				(island_removal_mode 0)
			)
			(polygon
				(pts
					(xy 127.294894 -48.000158) (xy 120.685052 -48.000158) (xy 120.685052 -28.720034) (xy 127.294894 -28.720034)
				)
			)
		)
		(zone
			(layer "F.Cu")
			(hatch none 0.5)
			(connect_pads
				(clearance 0)
			)
			(min_thickness 0.25)
			(keepout
				(tracks not_allowed)
				(vias allowed)
				(pads allowed)
				(copperpour not_allowed)
				(footprints allowed)
			)
			(placement
				(enabled no)
				(sheetname "")
			)
			(fill
				(thermal_gap 0.5)
				(thermal_bridge_width 0.5)
				(island_removal_mode 0)
			)
			(polygon
				(pts
					(xy 127.294894 -28.720034) (xy 127.294894 -48.000158) (xy 120.685052 -48.000158) (xy 120.685052 -28.720034)
				)
			)
		)
		(zone
			(layers "F.Cu" "B.Cu" "In1.Cu" "In2.Cu" "In3.Cu" "In4.Cu" "In5.Cu" "In6.Cu")
			(hatch none 0.5)
			(connect_pads
				(clearance 0)
			)
			(min_thickness 0.25)
			(keepout
				(tracks not_allowed)
				(vias allowed)
				(pads allowed)
				(copperpour not_allowed)
				(footprints allowed)
			)
			(placement
				(enabled no)
				(sheetname "")
			)
			(fill
				(thermal_gap 0.5)
				(thermal_bridge_width 0.5)
				(island_removal_mode 0)
			)
			(polygon
				(pts
					(arc
						(start 125.663452 -41.844976)
						(mid 122.666252 -41.844976)
						(end 125.663452 -41.844976)
					)
				)
			)
		)
		(zone
			(layers "F.Cu" "B.Cu" "In1.Cu" "In2.Cu" "In3.Cu" "In4.Cu" "In5.Cu" "In6.Cu")
			(hatch none 0.5)
			(connect_pads
				(clearance 0)
			)
			(min_thickness 0.25)
			(keepout
				(tracks not_allowed)
				(vias allowed)
				(pads allowed)
				(copperpour not_allowed)
				(footprints allowed)
			)
			(placement
				(enabled no)
				(sheetname "")
			)
			(fill
				(thermal_gap 0.5)
				(thermal_bridge_width 0.5)
				(island_removal_mode 0)
			)
			(polygon
				(pts
					(arc
						(start 125.701552 -34.85515)
						(mid 122.628152 -34.85515)
						(end 125.701552 -34.85515)
					)
				)
			)
		)
	)
	(footprint ""
		(layer "F.Cu")
		(at 176.6824 -60.1599 90)
		(property "Reference" "R579"
			(at 0 0 90)
			(layer "F.SilkS")
			(hide yes)
			(effects
				(font
					(size 1.27 1.27)
				)
			)
		)
		(property "Value" "2K2R2F-GP"
			(at 0.064008 -3.993896 90)
			(unlocked yes)
			(layer "F.Fab")
			(hide yes)
			(effects
				(font
					(size 1.016 1.016)
					(thickness 0.1524)
				)
			)
		)
		(property "Device Type" "R402H16"
			(at 0.064008 -5.517896 90)
			(unlocked yes)
			(layer "F.Fab")
			(hide yes)
			(effects
				(font
					(size 1.016 1.016)
					(thickness 0.1524)
				)
			)
		)
		(duplicate_pad_numbers_are_jumpers no)
		(fp_line
			(start 0.508 -0.9398)
			(end -0.508 -0.9398)
			(stroke
				(width 0.1524)
				(type default)
			)
			(layer "F.SilkS")
		)
		(fp_line
			(start -0.508 -0.9398)
			(end -0.508 0.9398)
			(stroke
				(width 0.1524)
				(type default)
			)
			(layer "F.SilkS")
		)
		(fp_rect
			(start -0.508 0.9398)
			(end 0.508 -0.9398)
			(stroke
				(width 0)
				(type default)
			)
			(fill no)
			(layer "F.CrtYd")
		)
		(fp_rect
			(start -0.508 0.9398)
			(end 0.508 -0.9398)
			(stroke
				(width 0)
				(type default)
			)
			(fill no)
			(layer "F.Fab")
		)
		(pad "1" smd custom
			(at 0 -0.4445 90)
			(size 0.1397 0.1397)
			(layers "F.Cu" "F.Mask" "F.Paste")
			(net "P1V8")
			(options
				(clearance outline)
				(anchor circle)
			)
			(primitives
				(gr_poly
					(pts
						(arc
							(start -0.1778 -0.2794)
							(mid -0.249642 -0.249642)
							(end -0.2794 -0.1778)
						)
						(arc
							(start -0.2794 0.1778)
							(mid -0.249642 0.249642)
							(end -0.1778 0.2794)
						)
						(arc
							(start 0.1778 0.2794)
							(mid 0.249642 0.249642)
							(end 0.2794 0.1778)
						)
						(arc
							(start 0.2794 -0.1778)
							(mid 0.249642 -0.249642)
							(end 0.1778 -0.2794)
						)
					)
					(width 0)
					(fill yes)
				)
			)
		)
		(pad "2" smd custom
			(at 0 0.4445 90)
			(size 0.1397 0.1397)
			(layers "F.Cu" "F.Mask" "F.Paste")
			(net "SBL_SDA")
			(options
				(clearance outline)
				(anchor circle)
			)
			(primitives
				(gr_poly
					(pts
						(arc
							(start -0.1778 -0.2794)
							(mid -0.249642 -0.249642)
							(end -0.2794 -0.1778)
						)
						(arc
							(start -0.2794 0.1778)
							(mid -0.249642 0.249642)
							(end -0.1778 0.2794)
						)
						(arc
							(start 0.1778 0.2794)
							(mid 0.249642 0.249642)
							(end 0.2794 0.1778)
						)
						(arc
							(start 0.2794 -0.1778)
							(mid 0.249642 -0.249642)
							(end 0.1778 -0.2794)
						)
					)
					(width 0)
					(fill yes)
				)
			)
		)
	)
	(footprint ""
		(layer "F.Cu")
		(at 93.09989 -54.526942)
		(property "Reference" "U36"
			(at 0 0 0)
			(layer "F.SilkS")
			(hide yes)
			(effects
				(font
					(size 1.27 1.27)
				)
			)
		)
		(property "Value" "SN74LVC1G08DCKR-GP"
			(at -2.3368 -8.6868 0)
			(unlocked yes)
			(layer "F.Fab")
			(hide yes)
			(effects
				(font
					(size 1.016 1.016)
					(thickness 0.1524)
				)
			)
		)
		(property "Device Type" "SC70-5H44"
			(at -2.3114 -10.414 0)
			(unlocked yes)
			(layer "F.Fab")
			(hide yes)
			(effects
				(font
					(size 1.016 1.016)
					(thickness 0.1524)
				)
			)
		)
		(duplicate_pad_numbers_are_jumpers no)
		(fp_line
			(start -1.27 -1.7018)
			(end 1.27 -1.7018)
			(stroke
				(width 0.1524)
				(type default)
			)
			(layer "F.SilkS")
		)
		(fp_line
			(start -1.27 1.7018)
			(end -1.27 -1.7018)
			(stroke
				(width 0.1524)
				(type default)
			)
			(layer "F.SilkS")
		)
		(fp_line
			(start 0.6604 -1.8034)
			(end 1.3843 -1.8034)
			(stroke
				(width 0.3302)
				(type default)
			)
			(layer "F.SilkS")
		)
		(fp_line
			(start 1.27 -1.7018)
			(end 1.27 1.7018)
			(stroke
				(width 0.1524)
				(type default)
			)
			(layer "F.SilkS")
		)
		(fp_line
			(start 1.27 1.7018)
			(end -1.27 1.7018)
			(stroke
				(width 0.1524)
				(type default)
			)
			(layer "F.SilkS")
		)
		(fp_line
			(start 1.3843 -1.8034)
			(end 1.3843 -1.1176)
			(stroke
				(width 0.3302)
				(type default)
			)
			(layer "F.SilkS")
		)
		(fp_rect
			(start -1.524 1.9558)
			(end 1.524 -1.9558)
			(stroke
				(width 0)
				(type default)
			)
			(fill no)
			(layer "F.CrtYd")
		)
		(fp_poly
			(pts
				(xy -1.524 -1.9558) (xy 1.524 -1.9558) (xy 1.524 1.9558) (xy -1.524 1.9558)
			)
			(stroke
				(width 0)
				(type default)
			)
			(fill no)
			(layer "F.Fab")
		)
		(pad "1" smd rect
			(at 0.65024 -0.8255)
			(size 0.4064 1.2192)
			(layers "F.Cu" "F.Mask" "F.Paste")
			(net "IOM_FULL_PWR_EN")
		)
		(pad "2" smd rect
			(at 0 -0.8255)
			(size 0.4064 1.2192)
			(layers "F.Cu" "F.Mask" "F.Paste")
			(net "IOM_STBY_PGOOD")
		)
		(pad "3" smd rect
			(at -0.65024 -0.8255)
			(size 0.4064 1.2192)
			(layers "F.Cu" "F.Mask" "F.Paste")
			(net "GND")
		)
		(pad "4" smd rect
			(at -0.65024 0.8255)
			(size 0.4064 1.2192)
			(layers "F.Cu" "F.Mask" "F.Paste")
			(net "P3V3_EN")
		)
		(pad "5" smd rect
			(at 0.65024 0.8255)
			(size 0.4064 1.2192)
			(layers "F.Cu" "F.Mask" "F.Paste")
			(net "P3V3_STBY")
		)
	)
	(footprint ""
		(layer "F.Cu")
		(at 185.693304 -152.051766)
		(property "Reference" "R473"
			(at 0 0 0)
			(layer "F.SilkS")
			(hide yes)
			(effects
				(font
					(size 1.27 1.27)
				)
			)
		)
		(property "Value" "10R3F-GP"
			(at -0.0254 -2.5146 0)
			(unlocked yes)
			(layer "F.Fab")
			(hide yes)
			(effects
				(font
					(size 1.016 1.016)
					(thickness 0.1524)
				)
			)
		)
		(property "Device Type" "R603H22"
			(at -0.0254 -4.0386 0)
			(unlocked yes)
			(layer "F.Fab")
			(hide yes)
			(effects
				(font
					(size 1.016 1.016)
					(thickness 0.1524)
				)
			)
		)
		(duplicate_pad_numbers_are_jumpers no)
		(fp_line
			(start -0.4826 0)
			(end -0.2032 0)
			(stroke
				(width 0.2032)
				(type default)
			)
			(layer "F.SilkS")
		)
		(fp_line
			(start 0.2032 0)
			(end 0.4826 0)
			(stroke
				(width 0.2032)
				(type default)
			)
			(layer "F.SilkS")
		)
		(fp_rect
			(start -0.5842 1.3335)
			(end 0.5842 -1.3335)
			(stroke
				(width 0)
				(type default)
			)
			(fill no)
			(layer "F.CrtYd")
		)
		(fp_rect
			(start -0.5842 1.3335)
			(end 0.5842 -1.3335)
			(stroke
				(width 0)
				(type default)
			)
			(fill no)
			(layer "F.Fab")
		)
		(pad "1" smd custom
			(at 0 -0.762)
			(size 0.2159 0.2159)
			(layers "F.Cu" "F.Mask" "F.Paste")
			(net "P5V_CC")
			(options
				(clearance outline)
				(anchor circle)
			)
			(primitives
				(gr_poly
					(pts
						(arc
							(start -0.3302 -0.4318)
							(mid -0.402042 -0.402042)
							(end -0.4318 -0.3302)
						)
						(arc
							(start -0.4318 0.3302)
							(mid -0.402042 0.402042)
							(end -0.3302 0.4318)
						)
						(arc
							(start 0.3302 0.4318)
							(mid 0.402042 0.402042)
							(end 0.4318 0.3302)
						)
						(arc
							(start 0.4318 -0.3302)
							(mid 0.402042 -0.402042)
							(end 0.3302 -0.4318)
						)
					)
					(width 0)
					(fill yes)
				)
			)
		)
		(pad "2" smd custom
			(at 0 0.762)
			(size 0.2159 0.2159)
			(layers "F.Cu" "F.Mask" "F.Paste")
			(net "P5V_VFB_R")
			(options
				(clearance outline)
				(anchor circle)
			)
			(primitives
				(gr_poly
					(pts
						(arc
							(start -0.3302 -0.4318)
							(mid -0.402042 -0.402042)
							(end -0.4318 -0.3302)
						)
						(arc
							(start -0.4318 0.3302)
							(mid -0.402042 0.402042)
							(end -0.3302 0.4318)
						)
						(arc
							(start 0.3302 0.4318)
							(mid 0.402042 0.402042)
							(end 0.4318 0.3302)
						)
						(arc
							(start 0.4318 -0.3302)
							(mid 0.402042 -0.402042)
							(end 0.3302 -0.4318)
						)
					)
					(width 0)
					(fill yes)
				)
			)
		)
	)
	(footprint ""
		(layer "F.Cu")
		(at 182.9562 -144.5514 90)
		(property "Reference" "R477"
			(at 0 0 90)
			(layer "F.SilkS")
			(hide yes)
			(effects
				(font
					(size 1.27 1.27)
				)
			)
		)
		(property "Value" "619KR2F-GP"
			(at 0.064008 -3.993896 90)
			(unlocked yes)
			(layer "F.Fab")
			(hide yes)
			(effects
				(font
					(size 1.016 1.016)
					(thickness 0.1524)
				)
			)
		)
		(property "Device Type" "R402H16"
			(at 0.064008 -5.517896 90)
			(unlocked yes)
			(layer "F.Fab")
			(hide yes)
			(effects
				(font
					(size 1.016 1.016)
					(thickness 0.1524)
				)
			)
		)
		(duplicate_pad_numbers_are_jumpers no)
		(fp_line
			(start 0.508 -0.9398)
			(end -0.508 -0.9398)
			(stroke
				(width 0.1524)
				(type default)
			)
			(layer "F.SilkS")
		)
		(fp_line
			(start -0.508 -0.9398)
			(end -0.508 0.9398)
			(stroke
				(width 0.1524)
				(type default)
			)
			(layer "F.SilkS")
		)
		(fp_rect
			(start -0.508 0.9398)
			(end 0.508 -0.9398)
			(stroke
				(width 0)
				(type default)
			)
			(fill no)
			(layer "F.CrtYd")
		)
		(fp_rect
			(start -0.508 0.9398)
			(end 0.508 -0.9398)
			(stroke
				(width 0)
				(type default)
			)
			(fill no)
			(layer "F.Fab")
		)
		(pad "1" smd custom
			(at 0 -0.4445 90)
			(size 0.1397 0.1397)
			(layers "F.Cu" "F.Mask" "F.Paste")
			(net "P5V_RF")
			(options
				(clearance outline)
				(anchor circle)
			)
			(primitives
				(gr_poly
					(pts
						(arc
							(start -0.1778 -0.2794)
							(mid -0.249642 -0.249642)
							(end -0.2794 -0.1778)
						)
						(arc
							(start -0.2794 0.1778)
							(mid -0.249642 0.249642)
							(end -0.1778 0.2794)
						)
						(arc
							(start 0.1778 0.2794)
							(mid 0.249642 0.249642)
							(end 0.2794 0.1778)
						)
						(arc
							(start 0.2794 -0.1778)
							(mid 0.249642 -0.249642)
							(end 0.1778 -0.2794)
						)
					)
					(width 0)
					(fill yes)
				)
			)
		)
		(pad "2" smd custom
			(at 0 0.4445 90)
			(size 0.1397 0.1397)
			(layers "F.Cu" "F.Mask" "F.Paste")
			(net "AGND_P5V")
			(options
				(clearance outline)
				(anchor circle)
			)
			(primitives
				(gr_poly
					(pts
						(arc
							(start -0.1778 -0.2794)
							(mid -0.249642 -0.249642)
							(end -0.2794 -0.1778)
						)
						(arc
							(start -0.2794 0.1778)
							(mid -0.249642 0.249642)
							(end -0.1778 0.2794)
						)
						(arc
							(start 0.1778 0.2794)
							(mid 0.249642 0.249642)
							(end 0.2794 0.1778)
						)
						(arc
							(start 0.2794 -0.1778)
							(mid 0.249642 -0.249642)
							(end 0.1778 -0.2794)
						)
					)
					(width 0)
					(fill yes)
				)
			)
		)
	)
	(footprint ""
		(layer "F.Cu")
		(at 122.99315 -14.9479 90)
		(property "Reference" "R432"
			(at 0 0 90)
			(layer "F.SilkS")
			(hide yes)
			(effects
				(font
					(size 1.27 1.27)
				)
			)
		)
		(property "Value" "100R2D-GP"
			(at 0.064008 -3.993896 90)
			(unlocked yes)
			(layer "F.Fab")
			(hide yes)
			(effects
				(font
					(size 1.016 1.016)
					(thickness 0.1524)
				)
			)
		)
		(property "Device Type" "R402H14"
			(at 0.064008 -5.517896 90)
			(unlocked yes)
			(layer "F.Fab")
			(hide yes)
			(effects
				(font
					(size 1.016 1.016)
					(thickness 0.1524)
				)
			)
		)
		(duplicate_pad_numbers_are_jumpers no)
		(fp_line
			(start 0.508 -0.9398)
			(end -0.508 -0.9398)
			(stroke
				(width 0.1524)
				(type default)
			)
			(layer "F.SilkS")
		)
		(fp_line
			(start -0.508 -0.9398)
			(end -0.508 0.9398)
			(stroke
				(width 0.1524)
				(type default)
			)
			(layer "F.SilkS")
		)
		(fp_rect
			(start -0.508 0.9398)
			(end 0.508 -0.9398)
			(stroke
				(width 0)
				(type default)
			)
			(fill no)
			(layer "F.CrtYd")
		)
		(fp_rect
			(start -0.508 0.9398)
			(end 0.508 -0.9398)
			(stroke
				(width 0)
				(type default)
			)
			(fill no)
			(layer "F.Fab")
		)
		(pad "1" smd custom
			(at 0 -0.4445 90)
			(size 0.1397 0.1397)
			(layers "F.Cu" "F.Mask" "F.Paste")
			(net "MB0_TEMP")
			(options
				(clearance outline)
				(anchor circle)
			)
			(primitives
				(gr_poly
					(pts
						(arc
							(start -0.1778 -0.2794)
							(mid -0.249642 -0.249642)
							(end -0.2794 -0.1778)
						)
						(arc
							(start -0.2794 0.1778)
							(mid -0.249642 0.249642)
							(end -0.1778 0.2794)
						)
						(arc
							(start 0.1778 0.2794)
							(mid 0.249642 0.249642)
							(end 0.2794 0.1778)
						)
						(arc
							(start 0.2794 -0.1778)
							(mid 0.249642 -0.249642)
							(end 0.1778 -0.2794)
						)
					)
					(width 0)
					(fill yes)
				)
			)
		)
		(pad "2" smd custom
			(at 0 0.4445 90)
			(size 0.1397 0.1397)
			(layers "F.Cu" "F.Mask" "F.Paste")
			(net "MB0_TEMP_C")
			(options
				(clearance outline)
				(anchor circle)
			)
			(primitives
				(gr_poly
					(pts
						(arc
							(start -0.1778 -0.2794)
							(mid -0.249642 -0.249642)
							(end -0.2794 -0.1778)
						)
						(arc
							(start -0.2794 0.1778)
							(mid -0.249642 0.249642)
							(end -0.1778 0.2794)
						)
						(arc
							(start 0.1778 0.2794)
							(mid 0.249642 0.249642)
							(end 0.2794 0.1778)
						)
						(arc
							(start 0.2794 -0.1778)
							(mid 0.249642 -0.249642)
							(end 0.1778 -0.2794)
						)
					)
					(width 0)
					(fill yes)
				)
			)
		)
	)
	(footprint ""
		(layer "F.Cu")
		(at 173.6598 -63.2714 90)
		(property "Reference" "R649"
			(at 0 0 90)
			(layer "F.SilkS")
			(hide yes)
			(effects
				(font
					(size 1.27 1.27)
				)
			)
		)
		(property "Value" "10KR2F-2-GP"
			(at 0.064008 -3.993896 90)
			(unlocked yes)
			(layer "F.Fab")
			(hide yes)
			(effects
				(font
					(size 1.016 1.016)
					(thickness 0.1524)
				)
			)
		)
		(property "Device Type" "R402H16"
			(at 0.064008 -5.517896 90)
			(unlocked yes)
			(layer "F.Fab")
			(hide yes)
			(effects
				(font
					(size 1.016 1.016)
					(thickness 0.1524)
				)
			)
		)
		(duplicate_pad_numbers_are_jumpers no)
		(fp_line
			(start 0.508 -0.9398)
			(end -0.508 -0.9398)
			(stroke
				(width 0.1524)
				(type default)
			)
			(layer "F.SilkS")
		)
		(fp_line
			(start -0.508 -0.9398)
			(end -0.508 0.9398)
			(stroke
				(width 0.1524)
				(type default)
			)
			(layer "F.SilkS")
		)
		(fp_rect
			(start -0.508 0.9398)
			(end 0.508 -0.9398)
			(stroke
				(width 0)
				(type default)
			)
			(fill no)
			(layer "F.CrtYd")
		)
		(fp_rect
			(start -0.508 0.9398)
			(end 0.508 -0.9398)
			(stroke
				(width 0)
				(type default)
			)
			(fill no)
			(layer "F.Fab")
		)
		(pad "1" smd custom
			(at 0 -0.4445 90)
			(size 0.1397 0.1397)
			(layers "F.Cu" "F.Mask" "F.Paste")
			(net "P1V8")
			(options
				(clearance outline)
				(anchor circle)
			)
			(primitives
				(gr_poly
					(pts
						(arc
							(start -0.1778 -0.2794)
							(mid -0.249642 -0.249642)
							(end -0.2794 -0.1778)
						)
						(arc
							(start -0.2794 0.1778)
							(mid -0.249642 0.249642)
							(end -0.1778 0.2794)
						)
						(arc
							(start 0.1778 0.2794)
							(mid 0.249642 0.249642)
							(end 0.2794 0.1778)
						)
						(arc
							(start 0.2794 -0.1778)
							(mid 0.249642 -0.249642)
							(end 0.1778 -0.2794)
						)
					)
					(width 0)
					(fill yes)
				)
			)
		)
		(pad "2" smd custom
			(at 0 0.4445 90)
			(size 0.1397 0.1397)
			(layers "F.Cu" "F.Mask" "F.Paste")
			(net "SYS_CORE_TRI#")
			(options
				(clearance outline)
				(anchor circle)
			)
			(primitives
				(gr_poly
					(pts
						(arc
							(start -0.1778 -0.2794)
							(mid -0.249642 -0.249642)
							(end -0.2794 -0.1778)
						)
						(arc
							(start -0.2794 0.1778)
							(mid -0.249642 0.249642)
							(end -0.1778 0.2794)
						)
						(arc
							(start 0.1778 0.2794)
							(mid 0.249642 0.249642)
							(end 0.2794 0.1778)
						)
						(arc
							(start 0.2794 -0.1778)
							(mid 0.249642 -0.249642)
							(end 0.1778 -0.2794)
						)
					)
					(width 0)
					(fill yes)
				)
			)
		)
	)
	(footprint ""
		(layer "F.Cu")
		(at 47.69993 -144.999964 -90)
		(property "Reference" "U2"
			(at 0 0 270)
			(layer "F.SilkS")
			(hide yes)
			(effects
				(font
					(size 1.27 1.27)
				)
			)
		)
		(property "Value" "AST2500A2-GP-GP-U"
			(at -17.0307 -8.584692 270)
			(unlocked yes)
			(layer "F.Fab")
			(hide yes)
			(effects
				(font
					(size 1.016 1.016)
					(thickness 0.1524)
				)
			)
		)
		(property "Device Type" "BGA456D19H58"
			(at -17.0307 -10.108692 270)
			(unlocked yes)
			(layer "F.Fab")
			(hide yes)
			(effects
				(font
					(size 1.016 1.016)
					(thickness 0.1524)
				)
			)
		)
		(duplicate_pad_numbers_are_jumpers no)
		(fp_line
			(start -9.500108 9.500108)
			(end 9.500108 9.500108)
			(stroke
				(width 0.1524)
				(type default)
			)
			(layer "F.SilkS")
		)
		(fp_line
			(start 9.500108 9.500108)
			(end 9.500108 -9.500108)
			(stroke
				(width 0.1524)
				(type default)
			)
			(layer "F.SilkS")
		)
		(fp_line
			(start -9.830308 -8.230108)
			(end -9.830308 -9.830308)
			(stroke
				(width 0.508)
				(type default)
			)
			(layer "F.SilkS")
		)
		(fp_line
			(start -9.500108 -9.500108)
			(end -9.500108 9.500108)
			(stroke
				(width 0.1524)
				(type default)
			)
			(layer "F.SilkS")
		)
		(fp_line
			(start 9.500108 -9.500108)
			(end -9.500108 -9.500108)
			(stroke
				(width 0.1524)
				(type default)
			)
			(layer "F.SilkS")
		)
		(fp_line
			(start -9.830308 -9.830308)
			(end -8.230108 -9.830308)
			(stroke
				(width 0.508)
				(type default)
			)
			(layer "F.SilkS")
		)
		(fp_rect
			(start -9.500108 9.500108)
			(end 9.500108 -9.500108)
			(stroke
				(width 0)
				(type default)
			)
			(fill no)
			(layer "F.CrtYd")
		)
		(fp_poly
			(pts
				(xy 10.500106 -9.500108) (xy -9.500108 -9.500108) (xy -9.500108 9.500108) (xy 9.500108 9.500108)
				(xy 9.500108 -9.487408) (xy 10.500106 -9.487408) (xy 10.500106 10.500106) (xy -10.500106 10.500106)
				(xy -10.500106 -10.500106) (xy 10.500106 -10.500106)
			)
			(stroke
				(width 0)
				(type default)
			)
			(fill no)
			(layer "F.CrtYd")
		)
		(fp_rect
			(start -11.500104 11.500104)
			(end 11.500104 -11.500104)
			(stroke
				(width 0)
				(type default)
			)
			(fill no)
			(layer "F.Fab")
		)
		(pad "A1" smd circle
			(at -8.400034 -8.400034 270)
			(size 0.4064 0.4064)
			(layers "F.Cu" "F.Mask" "F.Paste")
			(net "GND")
		)
		(pad "A2" smd circle
			(at -7.599934 -8.400034 270)
			(size 0.4064 0.4064)
			(layers "F.Cu" "F.Mask" "F.Paste")
			(net "MAC2_TXD0")
		)
		(pad "A3" smd circle
			(at -6.800088 -8.400034 270)
			(size 0.4064 0.4064)
			(layers "F.Cu" "F.Mask" "F.Paste")
			(net "NCSI_RXD0")
		)
		(pad "A4" smd circle
			(at -5.999988 -8.400034 270)
			(size 0.3556 0.3556)
			(layers "F.Cu" "F.Mask" "F.Paste")
			(net "BMC_RGMII_A4_D3")
		)
		(pad "A5" smd circle
			(at -5.199888 -8.400034 270)
			(size 0.3556 0.3556)
			(layers "F.Cu" "F.Mask" "F.Paste")
			(net "NCSI_TXD1_R")
		)
		(pad "A6" smd circle
			(at -4.400042 -8.400034 270)
			(size 0.3556 0.3556)
			(layers "F.Cu" "F.Mask" "F.Paste")
			(net "USB_P3_DN")
		)
		(pad "A7" smd circle
			(at -3.599942 -8.400034 270)
			(size 0.3556 0.3556)
			(layers "F.Cu" "F.Mask" "F.Paste")
			(net "USB_P2_DP")
		)
		(pad "A8" smd circle
			(at -2.800096 -8.400034 270)
			(size 0.3556 0.3556)
			(layers "F.Cu" "F.Mask" "F.Paste")
			(net "USB_P2_DN")
		)
		(pad "A9" smd circle
			(at -1.999996 -8.400034 270)
			(size 0.3556 0.3556)
			(layers "F.Cu" "F.Mask" "F.Paste")
			(net "BMC_SMB4_CLK")
		)
		(pad "A10" smd circle
			(at -1.199896 -8.400034 270)
			(size 0.3556 0.3556)
			(layers "F.Cu" "F.Mask" "F.Paste")
			(net "BMC_SMB3_DAT")
		)
		(pad "A11" smd circle
			(at -0.40005 -8.400034 270)
			(size 0.3556 0.3556)
			(layers "F.Cu" "F.Mask" "F.Paste")
			(net "BMC_SMB3_CLK")
		)
		(pad "A12" smd circle
			(at 0.40005 -8.400034 270)
			(size 0.3556 0.3556)
			(layers "F.Cu" "F.Mask" "F.Paste")
			(net "BMC_SMB10_DAT")
		)
		(pad "A13" smd circle
			(at 1.199896 -8.400034 270)
			(size 0.3556 0.3556)
			(layers "F.Cu" "F.Mask" "F.Paste")
			(net "BMC_SMB9_DAT")
		)
		(pad "A14" smd circle
			(at 1.999996 -8.400034 270)
			(size 0.3556 0.3556)
			(layers "F.Cu" "F.Mask" "F.Paste")
			(net "TP_BMC_GPIOI6")
		)
		(pad "A15" smd circle
			(at 2.800096 -8.400034 270)
			(size 0.3556 0.3556)
			(layers "F.Cu" "F.Mask" "F.Paste")
			(net "TP_BMC_GPIOI7")
		)
		(pad "A16" smd circle
			(at 3.599942 -8.400034 270)
			(size 0.3556 0.3556)
			(layers "F.Cu" "F.Mask" "F.Paste")
			(net "LED_POSTCODE_6")
		)
		(pad "A17" smd circle
			(at 4.400042 -8.400034 270)
			(size 0.3556 0.3556)
			(layers "F.Cu" "F.Mask" "F.Paste")
			(net "LED_POSTCODE_4")
		)
		(pad "A18" smd circle
			(at 5.199888 -8.400034 270)
			(size 0.3556 0.3556)
			(layers "F.Cu" "F.Mask" "F.Paste")
			(net "LED_POSTCODE_0")
		)
		(pad "A19" smd circle
			(at 5.999988 -8.400034 270)
			(size 0.3556 0.3556)
			(layers "F.Cu" "F.Mask" "F.Paste")
			(net "SLOTID_0")
		)
		(pad "A20" smd circle
			(at 6.800088 -8.400034 270)
			(size 0.4064 0.4064)
			(layers "F.Cu" "F.Mask" "F.Paste")
			(net "TP_BMC_EXT2_LED_B")
		)
		(pad "A21" smd circle
			(at 7.599934 -8.400034 270)
			(size 0.4064 0.4064)
			(layers "F.Cu" "F.Mask" "F.Paste")
			(net "SCC_PWR_EN_R")
		)
		(pad "A22" smd circle
			(at 8.400034 -8.400034 270)
			(size 0.4064 0.4064)
			(layers "F.Cu" "F.Mask" "F.Paste")
			(net "GND")
		)
		(pad "AA1" smd circle
			(at -8.400034 7.599934 270)
			(size 0.4064 0.4064)
			(layers "F.Cu" "F.Mask" "F.Paste")
			(net "Net_284")
		)
		(pad "AA2" smd circle
			(at -7.599934 7.599934 270)
			(size 0.4064 0.4064)
			(layers "F.Cu" "F.Mask" "F.Paste")
			(net "Net_286")
		)
		(pad "AA3" smd circle
			(at -6.800088 7.599934 270)
			(size 0.4064 0.4064)
			(layers "F.Cu" "F.Mask" "F.Paste")
			(net "TP_BMC_GPION5")
		)
		(pad "AA4" smd circle
			(at -5.999988 7.599934 270)
			(size 0.3556 0.3556)
			(layers "F.Cu" "F.Mask" "F.Paste")
			(net "COMP_POWER_FAIL_R_N")
		)
		(pad "AA5" smd circle
			(at -5.199888 7.599934 270)
			(size 0.3556 0.3556)
			(layers "F.Cu" "F.Mask" "F.Paste")
			(net "THROTTLE_N")
		)
		(pad "AA6" smd circle
			(at -4.400042 7.599934 270)
			(size 0.3556 0.3556)
			(layers "F.Cu" "F.Mask" "F.Paste")
			(net "MEMDQ_12")
		)
		(pad "AA7" smd circle
			(at -3.599942 7.599934 270)
			(size 0.3556 0.3556)
			(layers "F.Cu" "F.Mask" "F.Paste")
			(net "GND")
		)
		(pad "AA8" smd circle
			(at -2.800096 7.599934 270)
			(size 0.3556 0.3556)
			(layers "F.Cu" "F.Mask" "F.Paste")
			(net "MEMDQ_8")
		)
		(pad "AA9" smd circle
			(at -1.999996 7.599934 270)
			(size 0.3556 0.3556)
			(layers "F.Cu" "F.Mask" "F.Paste")
			(net "GND")
		)
		(pad "AA10" smd circle
			(at -1.199896 7.599934 270)
			(size 0.3556 0.3556)
			(layers "F.Cu" "F.Mask" "F.Paste")
			(net "MEMDQ_3")
		)
		(pad "AA11" smd circle
			(at -0.40005 7.599934 270)
			(size 0.3556 0.3556)
			(layers "F.Cu" "F.Mask" "F.Paste")
			(net "GND")
		)
		(pad "AA12" smd circle
			(at 0.40005 7.599934 270)
			(size 0.3556 0.3556)
			(layers "F.Cu" "F.Mask" "F.Paste")
			(net "MEMCSN")
		)
		(pad "AA13" smd circle
			(at 1.199896 7.599934 270)
			(size 0.3556 0.3556)
			(layers "F.Cu" "F.Mask" "F.Paste")
			(net "GND")
		)
		(pad "AA14" smd circle
			(at 1.999996 7.599934 270)
			(size 0.3556 0.3556)
			(layers "F.Cu" "F.Mask" "F.Paste")
			(net "MEMA_11")
		)
		(pad "AA15" smd circle
			(at 2.800096 7.599934 270)
			(size 0.3556 0.3556)
			(layers "F.Cu" "F.Mask" "F.Paste")
			(net "GND")
		)
		(pad "AA16" smd circle
			(at 3.599942 7.599934 270)
			(size 0.3556 0.3556)
			(layers "F.Cu" "F.Mask" "F.Paste")
			(net "MEMA_7")
		)
		(pad "AA17" smd circle
			(at 4.400042 7.599934 270)
			(size 0.3556 0.3556)
			(layers "F.Cu" "F.Mask" "F.Paste")
			(net "P1V15_STBY")
		)
		(pad "AA18" smd circle
			(at 5.199888 7.599934 270)
			(size 0.3556 0.3556)
			(layers "F.Cu" "F.Mask" "F.Paste")
			(net "BMC_SPI_CLK")
		)
		(pad "AA19" smd circle
			(at 5.999988 7.599934 270)
			(size 0.3556 0.3556)
			(layers "F.Cu" "F.Mask" "F.Paste")
			(net "FLA_CS_1")
		)
		(pad "AA20" smd circle
			(at 6.800088 7.599934 270)
			(size 0.4064 0.4064)
			(layers "F.Cu" "F.Mask" "F.Paste")
			(net "BMC_GPIOS7")
		)
		(pad "AA21" smd circle
			(at 7.599934 7.599934 270)
			(size 0.4064 0.4064)
			(layers "F.Cu" "F.Mask" "F.Paste")
			(net "PLTRST_R")
		)
		(pad "AA22" smd circle
			(at 8.400034 7.599934 270)
			(size 0.4064 0.4064)
			(layers "F.Cu" "F.Mask" "F.Paste")
			(net "TPM_PRSNT_N_R")
		)
		(pad "AB1" smd circle
			(at -8.400034 8.400034 270)
			(size 0.4064 0.4064)
			(layers "F.Cu" "F.Mask" "F.Paste")
			(net "GND")
		)
		(pad "AB2" smd circle
			(at -7.599934 8.400034 270)
			(size 0.4064 0.4064)
			(layers "F.Cu" "F.Mask" "F.Paste")
			(net "Net_283")
		)
		(pad "AB3" smd circle
			(at -6.800088 8.400034 270)
			(size 0.4064 0.4064)
			(layers "F.Cu" "F.Mask" "F.Paste")
			(net "SCC_A_HB_IN_R")
		)
		(pad "AB4" smd circle
			(at -5.999988 8.400034 270)
			(size 0.3556 0.3556)
			(layers "F.Cu" "F.Mask" "F.Paste")
			(net "ENCL_FAULT_LED_R")
		)
		(pad "AB5" smd circle
			(at -5.199888 8.400034 270)
			(size 0.3556 0.3556)
			(layers "F.Cu" "F.Mask" "F.Paste")
			(net "DEBUG_GPIO_BMC_R_1")
		)
		(pad "AB6" smd circle
			(at -4.400042 8.400034 270)
			(size 0.3556 0.3556)
			(layers "F.Cu" "F.Mask" "F.Paste")
			(net "MEMDQS_N1")
		)
		(pad "AB7" smd circle
			(at -3.599942 8.400034 270)
			(size 0.3556 0.3556)
			(layers "F.Cu" "F.Mask" "F.Paste")
			(net "MEMDQS_P1")
		)
		(pad "AB8" smd circle
			(at -2.800096 8.400034 270)
			(size 0.3556 0.3556)
			(layers "F.Cu" "F.Mask" "F.Paste")
			(net "MEMDM_1")
		)
		(pad "AB9" smd circle
			(at -1.999996 8.400034 270)
			(size 0.3556 0.3556)
			(layers "F.Cu" "F.Mask" "F.Paste")
			(net "MEMDQS_P0")
		)
		(pad "AB10" smd circle
			(at -1.199896 8.400034 270)
			(size 0.3556 0.3556)
			(layers "F.Cu" "F.Mask" "F.Paste")
			(net "MEMDQS_N0")
		)
		(pad "AB11" smd circle
			(at -0.40005 8.400034 270)
			(size 0.3556 0.3556)
			(layers "F.Cu" "F.Mask" "F.Paste")
			(net "MEMCK_P")
		)
		(pad "AB12" smd circle
			(at 0.40005 8.400034 270)
			(size 0.3556 0.3556)
			(layers "F.Cu" "F.Mask" "F.Paste")
			(net "MEMCK_N")
		)
		(pad "AB13" smd circle
			(at 1.199896 8.400034 270)
			(size 0.3556 0.3556)
			(layers "F.Cu" "F.Mask" "F.Paste")
			(net "MEMCASN")
		)
		(pad "AB14" smd circle
			(at 1.999996 8.400034 270)
			(size 0.3556 0.3556)
			(layers "F.Cu" "F.Mask" "F.Paste")
			(net "MEMA_1")
		)
		(pad "AB15" smd circle
			(at 2.800096 8.400034 270)
			(size 0.3556 0.3556)
			(layers "F.Cu" "F.Mask" "F.Paste")
			(net "MEMA_13")
		)
		(pad "AB16" smd circle
			(at 3.599942 8.400034 270)
			(size 0.3556 0.3556)
			(layers "F.Cu" "F.Mask" "F.Paste")
			(net "MEMA_6")
		)
		(pad "AB17" smd circle
			(at 4.400042 8.400034 270)
			(size 0.3556 0.3556)
			(layers "F.Cu" "F.Mask" "F.Paste")
			(net "DDR4_RST_N")
		)
		(pad "AB18" smd circle
			(at 5.199888 8.400034 270)
			(size 0.3556 0.3556)
			(layers "F.Cu" "F.Mask" "F.Paste")
			(net "PECI")
		)
		(pad "AB19" smd circle
			(at 5.999988 8.400034 270)
			(size 0.3556 0.3556)
			(layers "F.Cu" "F.Mask" "F.Paste")
			(net "FLA_CS_0")
		)
		(pad "AB20" smd circle
			(at 6.800088 8.400034 270)
			(size 0.4064 0.4064)
			(layers "F.Cu" "F.Mask" "F.Paste")
			(net "BMC_ML_PWR_YELLOW_LED")
		)
		(pad "AB21" smd circle
			(at 7.599934 8.400034 270)
			(size 0.4064 0.4064)
			(layers "F.Cu" "F.Mask" "F.Paste")
			(net "BMC_ML_PWR_BLUE_LED")
		)
		(pad "AB22" smd circle
			(at 8.400034 8.400034 270)
			(size 0.4064 0.4064)
			(layers "F.Cu" "F.Mask" "F.Paste")
			(net "GND")
		)
		(pad "B1" smd circle
			(at -8.400034 -7.599934 270)
			(size 0.4064 0.4064)
			(layers "F.Cu" "F.Mask" "F.Paste")
			(net "MAC2_TXCTL")
		)
		(pad "B2" smd circle
			(at -7.599934 -7.599934 270)
			(size 0.4064 0.4064)
			(layers "F.Cu" "F.Mask" "F.Paste")
			(net "TP_BMC_GPIOT6")
		)
		(pad "B3" smd circle
			(at -6.800088 -7.599934 270)
			(size 0.4064 0.4064)
			(layers "F.Cu" "F.Mask" "F.Paste")
			(net "MAC2_TXD1")
		)
		(pad "B4" smd circle
			(at -5.999988 -7.599934 270)
			(size 0.3556 0.3556)
			(layers "F.Cu" "F.Mask" "F.Paste")
			(net "CLK_50M_BMC_NCSI")
		)
		(pad "B5" smd circle
			(at -5.199888 -7.599934 270)
			(size 0.3556 0.3556)
			(layers "F.Cu" "F.Mask" "F.Paste")
			(net "TP_BMC_GPIOT0")
		)
		(pad "B6" smd circle
			(at -4.400042 -7.599934 270)
			(size 0.3556 0.3556)
			(layers "F.Cu" "F.Mask" "F.Paste")
			(net "USB_P3_DP")
		)
		(pad "B7" smd circle
			(at -3.599942 -7.599934 270)
			(size 0.3556 0.3556)
			(layers "F.Cu" "F.Mask" "F.Paste")
			(net "PD_USB2BVRES")
		)
		(pad "B8" smd circle
			(at -2.800096 -7.599934 270)
			(size 0.3556 0.3556)
			(layers "F.Cu" "F.Mask" "F.Paste")
			(net "PD_USB2AVRES")
		)
		(pad "B9" smd circle
			(at -1.999996 -7.599934 270)
			(size 0.3556 0.3556)
			(layers "F.Cu" "F.Mask" "F.Paste")
			(net "BMC_SMB4_DAT")
		)
		(pad "B10" smd circle
			(at -1.199896 -7.599934 270)
			(size 0.3556 0.3556)
			(layers "F.Cu" "F.Mask" "F.Paste")
			(net "DB_PRSNT_BMC_N")
		)
		(pad "B11" smd circle
			(at -0.40005 -7.599934 270)
			(size 0.3556 0.3556)
			(layers "F.Cu" "F.Mask" "F.Paste")
			(net "BMC_SMB13_DAT")
		)
		(pad "B12" smd circle
			(at 0.40005 -7.599934 270)
			(size 0.3556 0.3556)
			(layers "F.Cu" "F.Mask" "F.Paste")
			(net "BMC_SMB11_CLK")
		)
		(pad "B13" smd circle
			(at 1.199896 -7.599934 270)
			(size 0.3556 0.3556)
			(layers "F.Cu" "F.Mask" "F.Paste")
			(net "TP_BMC_GPIOA7")
		)
		(pad "B14" smd circle
			(at 1.999996 -7.599934 270)
			(size 0.3556 0.3556)
			(layers "F.Cu" "F.Mask" "F.Paste")
			(net "TP_BMC_GPIOA0")
		)
		(pad "B15" smd circle
			(at 2.800096 -7.599934 270)
			(size 0.3556 0.3556)
			(layers "F.Cu" "F.Mask" "F.Paste")
			(net "TP_BMC_GPIOI4")
		)
		(pad "B16" smd circle
			(at 3.599942 -7.599934 270)
			(size 0.3556 0.3556)
			(layers "F.Cu" "F.Mask" "F.Paste")
			(net "TP_BMC_GPIOI2")
		)
		(pad "B17" smd circle
			(at 4.400042 -7.599934 270)
			(size 0.3556 0.3556)
			(layers "F.Cu" "F.Mask" "F.Paste")
			(net "LED_POSTCODE_5")
		)
		(pad "B18" smd circle
			(at 5.199888 -7.599934 270)
			(size 0.3556 0.3556)
			(layers "F.Cu" "F.Mask" "F.Paste")
			(net "LED_POSTCODE_1")
		)
		(pad "B19" smd circle
			(at 5.999988 -7.599934 270)
			(size 0.3556 0.3556)
			(layers "F.Cu" "F.Mask" "F.Paste")
			(net "BMC_EXT2_LED_Y")
		)
		(pad "B20" smd circle
			(at 6.800088 -7.599934 270)
			(size 0.4064 0.4064)
			(layers "F.Cu" "F.Mask" "F.Paste")
			(net "Net_288")
		)
		(pad "B21" smd circle
			(at 7.599934 -7.599934 270)
			(size 0.4064 0.4064)
			(layers "F.Cu" "F.Mask" "F.Paste")
			(net "EXP_SPARE_1_R")
		)
		(pad "B22" smd circle
			(at 8.400034 -7.599934 270)
			(size 0.4064 0.4064)
			(layers "F.Cu" "F.Mask" "F.Paste")
			(net "EXP_SPARE_0_R")
		)
		(pad "C1" smd circle
			(at -8.400034 -6.800088 270)
			(size 0.4064 0.4064)
			(layers "F.Cu" "F.Mask" "F.Paste")
			(net "BMC_RGMII_A4_D3")
		)
		(pad "C2" smd circle
			(at -7.599934 -6.800088 270)
			(size 0.4064 0.4064)
			(layers "F.Cu" "F.Mask" "F.Paste")
			(net "BMC_RGMII_C2_C3_D1_D2_E6")
		)
		(pad "C3" smd circle
			(at -6.800088 -6.800088 270)
			(size 0.4064 0.4064)
			(layers "F.Cu" "F.Mask" "F.Paste")
			(net "BMC_RGMII_C2_C3_D1_D2_E6")
		)
		(pad "C4" smd circle
			(at -5.999988 -6.800088 270)
			(size 0.3556 0.3556)
			(layers "F.Cu" "F.Mask" "F.Paste")
			(net "NCSI_RX_ER")
		)
		(pad "C5" smd circle
			(at -5.199888 -6.800088 270)
			(size 0.3556 0.3556)
			(layers "F.Cu" "F.Mask" "F.Paste")
			(net "NCSI_RCSDV")
		)
		(pad "C6" smd circle
			(at -4.400042 -6.800088 270)
			(size 0.3556 0.3556)
			(layers "F.Cu" "F.Mask" "F.Paste")
			(net "GND")
		)
		(pad "C7" smd circle
			(at -3.599942 -6.800088 270)
			(size 0.3556 0.3556)
			(layers "F.Cu" "F.Mask" "F.Paste")
			(net "P3V3_STBY")
		)
		(pad "C8" smd circle
			(at -2.800096 -6.800088 270)
			(size 0.3556 0.3556)
			(layers "F.Cu" "F.Mask" "F.Paste")
			(net "JTAG_BMC_TMS")
		)
		(pad "C9" smd circle
			(at -1.999996 -6.800088 270)
			(size 0.3556 0.3556)
			(layers "F.Cu" "F.Mask" "F.Paste")
			(net "BMC0_JTAG_RTCK")
		)
		(pad "C10" smd circle
			(at -1.199896 -6.800088 270)
			(size 0.3556 0.3556)
			(layers "F.Cu" "F.Mask" "F.Paste")
			(net "JTAG_BMC_TCK")
		)
		(pad "C11" smd circle
			(at -0.40005 -6.800088 270)
			(size 0.3556 0.3556)
			(layers "F.Cu" "F.Mask" "F.Paste")
			(net "BMC_SMB13_CLK")
		)
		(pad "C12" smd circle
			(at 0.40005 -6.800088 270)
			(size 0.3556 0.3556)
			(layers "F.Cu" "F.Mask" "F.Paste")
			(net "BMC_SMB10_CLK")
		)
		(pad "C13" smd circle
			(at 1.199896 -6.800088 270)
			(size 0.3556 0.3556)
			(layers "F.Cu" "F.Mask" "F.Paste")
			(net "TP_BMC_GPIOA6")
		)
		(pad "C14" smd circle
			(at 1.999996 -6.800088 270)
			(size 0.3556 0.3556)
			(layers "F.Cu" "F.Mask" "F.Paste")
			(net "BMC_SMB9_CLK")
		)
		(pad "C15" smd circle
			(at 2.800096 -6.800088 270)
			(size 0.3556 0.3556)
			(layers "F.Cu" "F.Mask" "F.Paste")
			(net "TP_BMC_GPIOI5")
		)
		(pad "C16" smd circle
			(at 3.599942 -6.800088 270)
			(size 0.3556 0.3556)
			(layers "F.Cu" "F.Mask" "F.Paste")
			(net "TP_BMC_GPIOI3")
		)
		(pad "C17" smd circle
			(at 4.400042 -6.800088 270)
			(size 0.3556 0.3556)
			(layers "F.Cu" "F.Mask" "F.Paste")
			(net "LED_POSTCODE_3")
		)
		(pad "C18" smd circle
			(at 5.199888 -6.800088 270)
			(size 0.3556 0.3556)
			(layers "F.Cu" "F.Mask" "F.Paste")
			(net "TP_BMC_GPIOI0")
		)
		(pad "C19" smd circle
			(at 5.999988 -6.800088 270)
			(size 0.3556 0.3556)
			(layers "F.Cu" "F.Mask" "F.Paste")
			(net "COMP_SPARE_0_R")
		)
		(pad "C20" smd circle
			(at 6.800088 -6.800088 270)
			(size 0.4064 0.4064)
			(layers "F.Cu" "F.Mask" "F.Paste")
			(net "Net_289")
		)
		(pad "C21" smd circle
			(at 7.599934 -6.800088 270)
			(size 0.4064 0.4064)
			(layers "F.Cu" "F.Mask" "F.Paste")
			(net "Net_646")
		)
		(pad "C22" smd circle
			(at 8.400034 -6.800088 270)
			(size 0.4064 0.4064)
			(layers "F.Cu" "F.Mask" "F.Paste")
			(net "LPC_CPU_CLKOUT0")
		)
		(pad "D1" smd circle
			(at -8.400034 -5.999988 270)
			(size 0.3556 0.3556)
			(layers "F.Cu" "F.Mask" "F.Paste")
			(net "BMC_RGMII_C2_C3_D1_D2_E6")
		)
		(pad "D2" smd circle
			(at -7.599934 -5.999988 270)
			(size 0.3556 0.3556)
			(layers "F.Cu" "F.Mask" "F.Paste")
			(net "BMC_RGMII_C2_C3_D1_D2_E6")
		)
		(pad "D3" smd circle
			(at -6.800088 -5.999988 270)
			(size 0.3556 0.3556)
			(layers "F.Cu" "F.Mask" "F.Paste")
			(net "BMC_RGMII_A4_D3")
		)
		(pad "D4" smd circle
			(at -5.999988 -5.999988 270)
			(size 0.3556 0.3556)
			(layers "F.Cu" "F.Mask" "F.Paste")
			(net "MAC2_TXD3")
		)
		(pad "D5" smd circle
			(at -5.199888 -5.999988 270)
			(size 0.3556 0.3556)
			(layers "F.Cu" "F.Mask" "F.Paste")
			(net "MAC2_TXD2")
		)
		(pad "D6" smd circle
			(at -4.400042 -5.999988 270)
			(size 0.3556 0.3556)
			(layers "F.Cu" "F.Mask" "F.Paste")
			(net "NCSI_RXD1")
		)
		(pad "D7" smd circle
			(at -3.599942 -5.999988 270)
			(size 0.3556 0.3556)
			(layers "F.Cu" "F.Mask" "F.Paste")
			(net "MAC1_TXD3")
		)
		(pad "D8" smd circle
			(at -2.800096 -5.999988 270)
			(size 0.3556 0.3556)
			(layers "F.Cu" "F.Mask" "F.Paste")
			(net "RMII_BMC_MDC_R")
		)
		(pad "D9" smd circle
			(at -1.999996 -5.999988 270)
			(size 0.3556 0.3556)
			(layers "F.Cu" "F.Mask" "F.Paste")
			(net "BMC_SMB11_DAT")
		)
		(pad "D10" smd circle
			(at -1.199896 -5.999988 270)
			(size 0.3556 0.3556)
			(layers "F.Cu" "F.Mask" "F.Paste")
			(net "BMC_SMB12_CLK")
		)
		(pad "D11" smd circle
			(at -0.40005 -5.999988 270)
			(size 0.3556 0.3556)
			(layers "F.Cu" "F.Mask" "F.Paste")
			(net "JTAG_BMC_TDO")
		)
		(pad "D12" smd circle
			(at 0.40005 -5.999988 270)
			(size 0.3556 0.3556)
			(layers "F.Cu" "F.Mask" "F.Paste")
			(net "JTAG_BMC_TDI")
		)
		(pad "D13" smd circle
			(at 1.199896 -5.999988 270)
			(size 0.3556 0.3556)
			(layers "F.Cu" "F.Mask" "F.Paste")
			(net "BMC_TO_EXP_RESET_OUT")
		)
		(pad "D14" smd circle
			(at 1.999996 -5.999988 270)
			(size 0.3556 0.3556)
			(layers "F.Cu" "F.Mask" "F.Paste")
			(net "USB_OCS_N1")
		)
		(pad "D15" smd circle
			(at 2.800096 -5.999988 270)
			(size 0.3556 0.3556)
			(layers "F.Cu" "F.Mask" "F.Paste")
			(net "TP_BMC_GPIOG6")
		)
		(pad "D16" smd circle
			(at 3.599942 -5.999988 270)
			(size 0.3556 0.3556)
			(layers "F.Cu" "F.Mask" "F.Paste")
			(net "TP_BMC_GPIOG5")
		)
		(pad "D17" smd circle
			(at 4.400042 -5.999988 270)
			(size 0.3556 0.3556)
			(layers "F.Cu" "F.Mask" "F.Paste")
			(net "LED_POSTCODE_2")
		)
		(pad "D18" smd circle
			(at 5.199888 -5.999988 270)
			(size 0.3556 0.3556)
			(layers "F.Cu" "F.Mask" "F.Paste")
			(net "LED_POSTCODE_7")
		)
		(pad "D19" smd circle
			(at 5.999988 -5.999988 270)
			(size 0.3556 0.3556)
			(layers "F.Cu" "F.Mask" "F.Paste")
			(net "BMC_EXT1_LED_Y")
		)
		(pad "D20" smd circle
			(at 6.800088 -5.999988 270)
			(size 0.3556 0.3556)
			(layers "F.Cu" "F.Mask" "F.Paste")
			(net "COMP_PWR_BTN_R_N")
		)
		(pad "D21" smd circle
			(at 7.599934 -5.999988 270)
			(size 0.3556 0.3556)
			(layers "F.Cu" "F.Mask" "F.Paste")
			(net "RSTBTN_OUT_N_R")
		)
		(pad "D22" smd circle
			(at 8.400034 -5.999988 270)
			(size 0.3556 0.3556)
			(layers "F.Cu" "F.Mask" "F.Paste")
			(net "TP_BMC0_LPC_LAD2")
		)
		(pad "E1" smd circle
			(at -8.400034 -5.199888 270)
			(size 0.3556 0.3556)
			(layers "F.Cu" "F.Mask" "F.Paste")
			(net "ADC_P1V8_STBY")
		)
		(pad "E2" smd circle
			(at -7.599934 -5.199888 270)
			(size 0.3556 0.3556)
			(layers "F.Cu" "F.Mask" "F.Paste")
			(net "ADC_P3V3_STBY")
		)
		(pad "E3" smd circle
			(at -6.800088 -5.199888 270)
			(size 0.3556 0.3556)
			(layers "F.Cu" "F.Mask" "F.Paste")
			(net "ADC_P1V2_STBY")
		)
		(pad "E4" smd circle
			(at -5.999988 -5.199888 270)
			(size 0.3556 0.3556)
			(layers "F.Cu" "F.Mask" "F.Paste")
			(net "P3V3_STBY")
		)
		(pad "E5" smd circle
			(at -5.199888 -5.199888 270)
			(size 0.3556 0.3556)
			(layers "F.Cu" "F.Mask" "F.Paste")
			(net "GND")
		)
		(pad "E6" smd circle
			(at -4.400042 -5.199888 270)
			(size 0.3556 0.3556)
			(layers "F.Cu" "F.Mask" "F.Paste")
			(net "BMC_RGMII_C2_C3_D1_D2_E6")
		)
		(pad "E7" smd circle
			(at -3.599942 -5.199888 270)
			(size 0.3556 0.3556)
			(layers "F.Cu" "F.Mask" "F.Paste")
			(net "MAC1_TXD2")
		)
		(pad "E8" smd circle
			(at -2.800096 -5.199888 270)
			(size 0.3556 0.3556)
			(layers "F.Cu" "F.Mask" "F.Paste")
			(net "GND")
		)
		(pad "E9" smd circle
			(at -1.999996 -5.199888 270)
			(size 0.3556 0.3556)
			(layers "F.Cu" "F.Mask" "F.Paste")
			(net "NCSI_TXEN")
		)
		(pad "E10" smd circle
			(at -1.199896 -5.199888 270)
			(size 0.3556 0.3556)
			(layers "F.Cu" "F.Mask" "F.Paste")
			(net "RMII_BMC_MDIO_R")
		)
		(pad "E11" smd circle
			(at -0.40005 -5.199888 270)
			(size 0.3556 0.3556)
			(layers "F.Cu" "F.Mask" "F.Paste")
			(net "JTAG_BMC_TRST_N")
		)
		(pad "E12" smd circle
			(at 0.40005 -5.199888 270)
			(size 0.3556 0.3556)
			(layers "F.Cu" "F.Mask" "F.Paste")
			(net "BMC_SMB12_DAT")
		)
		(pad "E13" smd circle
			(at 1.199896 -5.199888 270)
			(size 0.3556 0.3556)
			(layers "F.Cu" "F.Mask" "F.Paste")
			(net "SYS_PWR_LED")
		)
		(pad "E14" smd circle
			(at 1.999996 -5.199888 270)
			(size 0.3556 0.3556)
			(layers "F.Cu" "F.Mask" "F.Paste")
			(net "I2C_COMP_ALERT_N")
		)
		(pad "E15" smd circle
			(at 2.800096 -5.199888 270)
			(size 0.3556 0.3556)
			(layers "F.Cu" "F.Mask" "F.Paste")
			(net "TP_BMC_GPIOI1")
		)
		(pad "E16" smd circle
			(at 3.599942 -5.199888 270)
			(size 0.3556 0.3556)
			(layers "F.Cu" "F.Mask" "F.Paste")
			(net "COMP_SPARE_1_R")
		)
		(pad "E17" smd circle
			(at 4.400042 -5.199888 270)
			(size 0.3556 0.3556)
			(layers "F.Cu" "F.Mask" "F.Paste")
			(net "SYS_RST_EN")
		)
		(pad "E18" smd circle
			(at 5.199888 -5.199888 270)
			(size 0.3556 0.3556)
			(layers "F.Cu" "F.Mask" "F.Paste")
			(net "TP_BMC_EXT1_LED_B")
		)
		(pad "E19" smd circle
			(at 5.999988 -5.199888 270)
			(size 0.3556 0.3556)
			(layers "F.Cu" "F.Mask" "F.Paste")
			(net "SLOTID_1")
		)
		(pad "E20" smd circle
			(at 6.800088 -5.199888 270)
			(size 0.3556 0.3556)
			(layers "F.Cu" "F.Mask" "F.Paste")
			(net "SYS_RESET_N_OUT_R")
		)
		(pad "E21" smd circle
			(at 7.599934 -5.199888 270)
			(size 0.3556 0.3556)
			(layers "F.Cu" "F.Mask" "F.Paste")
			(net "Net_645")
		)
		(pad "E22" smd circle
			(at 8.400034 -5.199888 270)
			(size 0.3556 0.3556)
			(layers "F.Cu" "F.Mask" "F.Paste")
			(net "TP_BMC0_LPC_LAD3")
		)
		(pad "F1" smd circle
			(at -8.400034 -4.400042 270)
			(size 0.3556 0.3556)
			(layers "F.Cu" "F.Mask" "F.Paste")
			(net "GND")
		)
		(pad "F2" smd circle
			(at -7.599934 -4.400042 270)
			(size 0.3556 0.3556)
			(layers "F.Cu" "F.Mask" "F.Paste")
			(net "ADC_P1V8")
		)
		(pad "F3" smd circle
			(at -6.800088 -4.400042 270)
			(size 0.3556 0.3556)
			(layers "F.Cu" "F.Mask" "F.Paste")
			(net "ADC_P2V5_STBY")
		)
		(pad "F4" smd circle
			(at -5.999988 -4.400042 270)
			(size 0.3556 0.3556)
			(layers "F.Cu" "F.Mask" "F.Paste")
			(net "ADC_12V")
		)
		(pad "F5" smd circle
			(at -5.199888 -4.400042 270)
			(size 0.3556 0.3556)
			(layers "F.Cu" "F.Mask" "F.Paste")
			(net "ADC_P5V_STBY")
		)
		(pad "F6" smd circle
			(at -4.400042 -4.400042 270)
			(size 0.3556 0.3556)
			(layers "F.Cu" "F.Mask" "F.Paste")
			(net "P1V15_STBY")
		)
		(pad "F7" smd circle
			(at -3.599942 -4.400042 270)
			(size 0.3556 0.3556)
			(layers "F.Cu" "F.Mask" "F.Paste")
			(net "P3V3_STBY")
		)
		(pad "F8" smd circle
			(at -2.800096 -4.400042 270)
			(size 0.3556 0.3556)
			(layers "F.Cu" "F.Mask" "F.Paste")
			(net "P3V3_STBY")
		)
		(pad "F9" smd circle
			(at -1.999996 -4.400042 270)
			(size 0.3556 0.3556)
			(layers "F.Cu" "F.Mask" "F.Paste")
			(net "NCSI_TXD0_R")
		)
		(pad "F10" smd circle
			(at -1.199896 -4.400042 270)
			(size 0.3556 0.3556)
			(layers "F.Cu" "F.Mask" "F.Paste")
			(net "P3V3_STBY")
		)
		(pad "F11" smd circle
			(at -0.40005 -4.400042 270)
			(size 0.3556 0.3556)
			(layers "F.Cu" "F.Mask" "F.Paste")
			(net "P3V3_STBY")
		)
		(pad "F12" smd circle
			(at 0.40005 -4.400042 270)
			(size 0.3556 0.3556)
			(layers "F.Cu" "F.Mask" "F.Paste")
			(net "P3V3_STBY")
		)
		(pad "F13" smd circle
			(at 1.199896 -4.400042 270)
			(size 0.3556 0.3556)
			(layers "F.Cu" "F.Mask" "F.Paste")
			(net "P3V3_STBY")
		)
		(pad "F14" smd circle
			(at 1.999996 -4.400042 270)
			(size 0.3556 0.3556)
			(layers "F.Cu" "F.Mask" "F.Paste")
			(net "P3V3_STBY")
		)
		(pad "F15" smd circle
			(at 2.800096 -4.400042 270)
			(size 0.3556 0.3556)
			(layers "F.Cu" "F.Mask" "F.Paste")
			(net "P3V3_STBY")
		)
		(pad "F16" smd circle
			(at 3.599942 -4.400042 270)
			(size 0.3556 0.3556)
			(layers "F.Cu" "F.Mask" "F.Paste")
			(net "GND")
		)
		(pad "F17" smd circle
			(at 4.400042 -4.400042 270)
			(size 0.3556 0.3556)
			(layers "F.Cu" "F.Mask" "F.Paste")
			(net "Net_153")
		)
		(pad "F18" smd circle
			(at 5.199888 -4.400042 270)
			(size 0.3556 0.3556)
			(layers "F.Cu" "F.Mask" "F.Paste")
			(net "Net_281")
		)
		(pad "F19" smd circle
			(at 5.999988 -4.400042 270)
			(size 0.3556 0.3556)
			(layers "F.Cu" "F.Mask" "F.Paste")
			(net "Net_644")
		)
		(pad "F20" smd circle
			(at 6.800088 -4.400042 270)
			(size 0.3556 0.3556)
			(layers "F.Cu" "F.Mask" "F.Paste")
			(net "PWRBTN_OUT_N_R")
		)
		(pad "F21" smd circle
			(at 7.599934 -4.400042 270)
			(size 0.3556 0.3556)
			(layers "F.Cu" "F.Mask" "F.Paste")
			(net "LPC_CPU_FRAME_N")
		)
		(pad "F22" smd circle
			(at 8.400034 -4.400042 270)
			(size 0.3556 0.3556)
			(layers "F.Cu" "F.Mask" "F.Paste")
			(net "IRQ_CPU_SERIAL")
		)
		(pad "G1" smd circle
			(at -8.400034 -3.599942 270)
			(size 0.3556 0.3556)
			(layers "F.Cu" "F.Mask" "F.Paste")
			(net "GND")
		)
		(pad "G2" smd circle
			(at -7.599934 -3.599942 270)
			(size 0.3556 0.3556)
			(layers "F.Cu" "F.Mask" "F.Paste")
			(net "ADC_P0V975")
		)
		(pad "G3" smd circle
			(at -6.800088 -3.599942 270)
			(size 0.3556 0.3556)
			(layers "F.Cu" "F.Mask" "F.Paste")
			(net "ADC_P1V5")
		)
		(pad "G4" smd circle
			(at -5.999988 -3.599942 270)
			(size 0.3556 0.3556)
			(layers "F.Cu" "F.Mask" "F.Paste")
			(net "ADC_P3V3")
		)
		(pad "G5" smd circle
			(at -5.199888 -3.599942 270)
			(size 0.3556 0.3556)
			(layers "F.Cu" "F.Mask" "F.Paste")
			(net "ADC_P1V15_STBY")
		)
		(pad "G6" smd circle
			(at -4.400042 -3.599942 270)
			(size 0.3556 0.3556)
			(layers "F.Cu" "F.Mask" "F.Paste")
			(net "GND")
		)
		(pad "G7" smd circle
			(at -3.599942 -3.599942 270)
			(size 0.3556 0.3556)
			(layers "F.Cu" "F.Mask" "F.Paste")
			(net "P1V15_STBY")
		)
		(pad "G8" smd circle
			(at -2.800096 -3.599942 270)
			(size 0.3556 0.3556)
			(layers "F.Cu" "F.Mask" "F.Paste")
			(net "P1V15_STBY")
		)
		(pad "G9" smd circle
			(at -1.999996 -3.599942 270)
			(size 0.3556 0.3556)
			(layers "F.Cu" "F.Mask" "F.Paste")
			(net "P1V15_STBY")
		)
		(pad "G10" smd circle
			(at -1.199896 -3.599942 270)
			(size 0.3556 0.3556)
			(layers "F.Cu" "F.Mask" "F.Paste")
			(net "P1V15_STBY")
		)
		(pad "G11" smd circle
			(at -0.40005 -3.599942 270)
			(size 0.3556 0.3556)
			(layers "F.Cu" "F.Mask" "F.Paste")
			(net "P1V15_STBY")
		)
		(pad "G12" smd circle
			(at 0.40005 -3.599942 270)
			(size 0.3556 0.3556)
			(layers "F.Cu" "F.Mask" "F.Paste")
			(net "P1V15_STBY")
		)
		(pad "G13" smd circle
			(at 1.199896 -3.599942 270)
			(size 0.3556 0.3556)
			(layers "F.Cu" "F.Mask" "F.Paste")
			(net "P1V15_STBY")
		)
		(pad "G14" smd circle
			(at 1.999996 -3.599942 270)
			(size 0.3556 0.3556)
			(layers "F.Cu" "F.Mask" "F.Paste")
			(net "P1V15_STBY")
		)
		(pad "G15" smd circle
			(at 2.800096 -3.599942 270)
			(size 0.3556 0.3556)
			(layers "F.Cu" "F.Mask" "F.Paste")
			(net "P1V15_STBY")
		)
		(pad "G16" smd circle
			(at 3.599942 -3.599942 270)
			(size 0.3556 0.3556)
			(layers "F.Cu" "F.Mask" "F.Paste")
			(net "P3V3_STBY")
		)
		(pad "G17" smd circle
			(at 4.400042 -3.599942 270)
			(size 0.3556 0.3556)
			(layers "F.Cu" "F.Mask" "F.Paste")
			(net "P12V_A_PGOOD_R")
		)
		(pad "G18" smd circle
			(at 5.199888 -3.599942 270)
			(size 0.3556 0.3556)
			(layers "F.Cu" "F.Mask" "F.Paste")
			(net "Net_643")
		)
		(pad "G19" smd circle
			(at 5.999988 -3.599942 270)
			(size 0.3556 0.3556)
			(layers "F.Cu" "F.Mask" "F.Paste")
			(net "GND")
		)
		(pad "G20" smd circle
			(at 6.800088 -3.599942 270)
			(size 0.3556 0.3556)
			(layers "F.Cu" "F.Mask" "F.Paste")
			(net "TP_BMC0_LPC_LAD1")
		)
		(pad "G21" smd circle
			(at 7.599934 -3.599942 270)
			(size 0.3556 0.3556)
			(layers "F.Cu" "F.Mask" "F.Paste")
			(net "TP_BMC0_LPC_LAD0")
		)
		(pad "G22" smd circle
			(at 8.400034 -3.599942 270)
			(size 0.3556 0.3556)
			(layers "F.Cu" "F.Mask" "F.Paste")
			(net "LPCRST0_N")
		)
		(pad "H1" smd circle
			(at -8.400034 -2.800096 270)
			(size 0.3556 0.3556)
			(layers "F.Cu" "F.Mask" "F.Paste")
			(net "ADCVREFFN")
		)
		(pad "H2" smd circle
			(at -7.599934 -2.800096 270)
			(size 0.3556 0.3556)
			(layers "F.Cu" "F.Mask" "F.Paste")
			(net "ADCVREFFP")
		)
		(pad "H3" smd circle
			(at -6.800088 -2.800096 270)
			(size 0.3556 0.3556)
			(layers "F.Cu" "F.Mask" "F.Paste")
			(net "GND")
		)
		(pad "H4" smd circle
			(at -5.999988 -2.800096 270)
			(size 0.3556 0.3556)
			(layers "F.Cu" "F.Mask" "F.Paste")
			(net "GND")
		)
		(pad "H5" smd circle
			(at -5.199888 -2.800096 270)
			(size 0.3556 0.3556)
			(layers "F.Cu" "F.Mask" "F.Paste")
			(net "GND")
		)
		(pad "H6" smd circle
			(at -4.400042 -2.800096 270)
			(size 0.3556 0.3556)
			(layers "F.Cu" "F.Mask" "F.Paste")
			(net "GND")
		)
		(pad "H7" smd circle
			(at -3.599942 -2.800096 270)
			(size 0.3556 0.3556)
			(layers "F.Cu" "F.Mask" "F.Paste")
			(net "VPLLAV33")
		)
		(pad "H16" smd circle
			(at 3.599942 -2.800096 270)
			(size 0.3556 0.3556)
			(layers "F.Cu" "F.Mask" "F.Paste")
			(net "P1V15_STBY")
		)
		(pad "H17" smd circle
			(at 4.400042 -2.800096 270)
			(size 0.3556 0.3556)
			(layers "F.Cu" "F.Mask" "F.Paste")
			(net "P3V3_STBY")
		)
		(pad "H18" smd circle
			(at 5.199888 -2.800096 270)
			(size 0.3556 0.3556)
			(layers "F.Cu" "F.Mask" "F.Paste")
			(net "SCC_RMT_TYPE_0_R")
		)
		(pad "H19" smd circle
			(at 5.999988 -2.800096 270)
			(size 0.3556 0.3556)
			(layers "F.Cu" "F.Mask" "F.Paste")
			(net "DPB_MISC_ALERT_O_R")
		)
		(pad "H20" smd circle
			(at 6.800088 -2.800096 270)
			(size 0.3556 0.3556)
			(layers "F.Cu" "F.Mask" "F.Paste")
			(net "Net_642")
		)
		(pad "H21" smd circle
			(at 7.599934 -2.800096 270)
			(size 0.3556 0.3556)
			(layers "F.Cu" "F.Mask" "F.Paste")
			(net "TP_M2_2_ALERT#")
		)
		(pad "H22" smd circle
			(at 8.400034 -2.800096 270)
			(size 0.3556 0.3556)
			(layers "F.Cu" "F.Mask" "F.Paste")
			(net "Net_641")
		)
		(pad "J1" smd circle
			(at -8.400034 -1.999996 270)
			(size 0.3556 0.3556)
			(layers "F.Cu" "F.Mask" "F.Paste")
			(net "ADCVREXT")
		)
		(pad "J2" smd circle
			(at -7.599934 -1.999996 270)
			(size 0.3556 0.3556)
			(layers "F.Cu" "F.Mask" "F.Paste")
			(net "Net_657")
		)
		(pad "J3" smd circle
			(at -6.800088 -1.999996 270)
			(size 0.3556 0.3556)
			(layers "F.Cu" "F.Mask" "F.Paste")
			(net "Net_656")
		)
		(pad "J4" smd circle
			(at -5.999988 -1.999996 270)
			(size 0.3556 0.3556)
			(layers "F.Cu" "F.Mask" "F.Paste")
			(net "Net_655")
		)
		(pad "J5" smd circle
			(at -5.199888 -1.999996 270)
			(size 0.3556 0.3556)
			(layers "F.Cu" "F.Mask" "F.Paste")
			(net "GND")
		)
		(pad "J6" smd circle
			(at -4.400042 -1.999996 270)
			(size 0.3556 0.3556)
			(layers "F.Cu" "F.Mask" "F.Paste")
			(net "ADCAV33")
		)
		(pad "J7" smd circle
			(at -3.599942 -1.999996 270)
			(size 0.3556 0.3556)
			(layers "F.Cu" "F.Mask" "F.Paste")
			(net "VPLLAV33")
		)
		(pad "J9" smd circle
			(at -1.999996 -1.999996 270)
			(size 0.3556 0.3556)
			(layers "F.Cu" "F.Mask" "F.Paste")
			(net "GND")
		)
		(pad "J10" smd circle
			(at -1.199896 -1.999996 270)
			(size 0.3556 0.3556)
			(layers "F.Cu" "F.Mask" "F.Paste")
			(net "GND")
		)
		(pad "J11" smd circle
			(at -0.40005 -1.999996 270)
			(size 0.3556 0.3556)
			(layers "F.Cu" "F.Mask" "F.Paste")
			(net "GND")
		)
		(pad "J12" smd circle
			(at 0.40005 -1.999996 270)
			(size 0.3556 0.3556)
			(layers "F.Cu" "F.Mask" "F.Paste")
			(net "GND")
		)
		(pad "J13" smd circle
			(at 1.199896 -1.999996 270)
			(size 0.3556 0.3556)
			(layers "F.Cu" "F.Mask" "F.Paste")
			(net "GND")
		)
		(pad "J14" smd circle
			(at 1.999996 -1.999996 270)
			(size 0.3556 0.3556)
			(layers "F.Cu" "F.Mask" "F.Paste")
			(net "GND")
		)
		(pad "J16" smd circle
			(at 3.599942 -1.999996 270)
			(size 0.3556 0.3556)
			(layers "F.Cu" "F.Mask" "F.Paste")
			(net "P1V15_STBY")
		)
		(pad "J17" smd circle
			(at 4.400042 -1.999996 270)
			(size 0.3556 0.3556)
			(layers "F.Cu" "F.Mask" "F.Paste")
			(net "P1V8_STBY")
		)
		(pad "J18" smd circle
			(at 5.199888 -1.999996 270)
			(size 0.3556 0.3556)
			(layers "F.Cu" "F.Mask" "F.Paste")
			(net "SCC_RMT_FULLPWR_EN")
		)
		(pad "J19" smd circle
			(at 5.999988 -1.999996 270)
			(size 0.3556 0.3556)
			(layers "F.Cu" "F.Mask" "F.Paste")
			(net "SCC_LOC_FULLPWR_EN")
		)
		(pad "J20" smd circle
			(at 6.800088 -1.999996 270)
			(size 0.3556 0.3556)
			(layers "F.Cu" "F.Mask" "F.Paste")
			(net "TP_M2_1_ALERT#")
		)
		(pad "J21" smd circle
			(at 7.599934 -1.999996 270)
			(size 0.3556 0.3556)
			(layers "F.Cu" "F.Mask" "F.Paste")
			(net "GND")
		)
		(pad "J22" smd circle
			(at 8.400034 -1.999996 270)
			(size 0.3556 0.3556)
			(layers "F.Cu" "F.Mask" "F.Paste")
			(net "GND")
		)
		(pad "K1" smd circle
			(at -8.400034 -1.199896 270)
			(size 0.3556 0.3556)
			(layers "F.Cu" "F.Mask" "F.Paste")
			(net "UART_BMC_R_TX")
		)
		(pad "K2" smd circle
			(at -7.599934 -1.199896 270)
			(size 0.3556 0.3556)
			(layers "F.Cu" "F.Mask" "F.Paste")
			(net "UART_BMC_R_RX")
		)
		(pad "K3" smd circle
			(at -6.800088 -1.199896 270)
			(size 0.3556 0.3556)
			(layers "F.Cu" "F.Mask" "F.Paste")
			(net "BMC_ENTEST")
		)
		(pad "K4" smd circle
			(at -5.999988 -1.199896 270)
			(size 0.3556 0.3556)
			(layers "F.Cu" "F.Mask" "F.Paste")
			(net "DACRSET")
		)
		(pad "K5" smd circle
			(at -5.199888 -1.199896 270)
			(size 0.3556 0.3556)
			(layers "F.Cu" "F.Mask" "F.Paste")
			(net "DACAV33")
		)
		(pad "K6" smd circle
			(at -4.400042 -1.199896 270)
			(size 0.3556 0.3556)
			(layers "F.Cu" "F.Mask" "F.Paste")
			(net "DACAV33")
		)
		(pad "K7" smd circle
			(at -3.599942 -1.199896 270)
			(size 0.3556 0.3556)
			(layers "F.Cu" "F.Mask" "F.Paste")
			(net "P3V3_STBY")
		)
		(pad "K9" smd circle
			(at -1.999996 -1.199896 270)
			(size 0.3556 0.3556)
			(layers "F.Cu" "F.Mask" "F.Paste")
			(net "GND")
		)
		(pad "K10" smd circle
			(at -1.199896 -1.199896 270)
			(size 0.3556 0.3556)
			(layers "F.Cu" "F.Mask" "F.Paste")
			(net "GND")
		)
		(pad "K11" smd circle
			(at -0.40005 -1.199896 270)
			(size 0.3556 0.3556)
			(layers "F.Cu" "F.Mask" "F.Paste")
			(net "GND")
		)
		(pad "K12" smd circle
			(at 0.40005 -1.199896 270)
			(size 0.3556 0.3556)
			(layers "F.Cu" "F.Mask" "F.Paste")
			(net "GND")
		)
		(pad "K13" smd circle
			(at 1.199896 -1.199896 270)
			(size 0.3556 0.3556)
			(layers "F.Cu" "F.Mask" "F.Paste")
			(net "GND")
		)
		(pad "K14" smd circle
			(at 1.999996 -1.199896 270)
			(size 0.3556 0.3556)
			(layers "F.Cu" "F.Mask" "F.Paste")
			(net "GND")
		)
		(pad "K16" smd circle
			(at 3.599942 -1.199896 270)
			(size 0.3556 0.3556)
			(layers "F.Cu" "F.Mask" "F.Paste")
			(net "GND")
		)
		(pad "K17" smd circle
			(at 4.400042 -1.199896 270)
			(size 0.3556 0.3556)
			(layers "F.Cu" "F.Mask" "F.Paste")
			(net "P1V8_STBY")
		)
		(pad "K18" smd circle
			(at 5.199888 -1.199896 270)
			(size 0.3556 0.3556)
			(layers "F.Cu" "F.Mask" "F.Paste")
			(net "Net_653")
		)
		(pad "K19" smd circle
			(at 5.999988 -1.199896 270)
			(size 0.3556 0.3556)
			(layers "F.Cu" "F.Mask" "F.Paste")
			(net "Net_652")
		)
		(pad "K20" smd circle
			(at 6.800088 -1.199896 270)
			(size 0.3556 0.3556)
			(layers "F.Cu" "F.Mask" "F.Paste")
			(net "BMC_PEREXT")
		)
		(pad "K21" smd circle
			(at 7.599934 -1.199896 270)
			(size 0.3556 0.3556)
			(layers "F.Cu" "F.Mask" "F.Paste")
			(net "GND")
		)
		(pad "K22" smd circle
			(at 8.400034 -1.199896 270)
			(size 0.3556 0.3556)
			(layers "F.Cu" "F.Mask" "F.Paste")
			(net "GND")
		)
		(pad "L1" smd circle
			(at -8.400034 -0.40005 270)
			(size 0.3556 0.3556)
			(layers "F.Cu" "F.Mask" "F.Paste")
			(net "BMC_SMB6_CLK")
		)
		(pad "L2" smd circle
			(at -7.599934 -0.40005 270)
			(size 0.3556 0.3556)
			(layers "F.Cu" "F.Mask" "F.Paste")
			(net "BOARD_REV_1")
		)
		(pad "L3" smd circle
			(at -6.800088 -0.40005 270)
			(size 0.3556 0.3556)
			(layers "F.Cu" "F.Mask" "F.Paste")
			(net "BMC_SMB5_CLK")
		)
		(pad "L4" smd circle
			(at -5.999988 -0.40005 270)
			(size 0.3556 0.3556)
			(layers "F.Cu" "F.Mask" "F.Paste")
			(net "BMC_SMB5_DAT")
		)
		(pad "L5" smd circle
			(at -5.199888 -0.40005 270)
			(size 0.3556 0.3556)
			(layers "F.Cu" "F.Mask" "F.Paste")
			(net "V1PLLAV11")
		)
		(pad "L6" smd circle
			(at -4.400042 -0.40005 270)
			(size 0.3556 0.3556)
			(layers "F.Cu" "F.Mask" "F.Paste")
			(net "V1PLLAV11")
		)
		(pad "L7" smd circle
			(at -3.599942 -0.40005 270)
			(size 0.3556 0.3556)
			(layers "F.Cu" "F.Mask" "F.Paste")
			(net "P1V15_STBY")
		)
		(pad "L9" smd circle
			(at -1.999996 -0.40005 270)
			(size 0.3556 0.3556)
			(layers "F.Cu" "F.Mask" "F.Paste")
			(net "GND")
		)
		(pad "L10" smd circle
			(at -1.199896 -0.40005 270)
			(size 0.3556 0.3556)
			(layers "F.Cu" "F.Mask" "F.Paste")
			(net "GND")
		)
		(pad "L11" smd circle
			(at -0.40005 -0.40005 270)
			(size 0.3556 0.3556)
			(layers "F.Cu" "F.Mask" "F.Paste")
			(net "GND")
		)
		(pad "L12" smd circle
			(at 0.40005 -0.40005 270)
			(size 0.3556 0.3556)
			(layers "F.Cu" "F.Mask" "F.Paste")
			(net "GND")
		)
		(pad "L13" smd circle
			(at 1.199896 -0.40005 270)
			(size 0.3556 0.3556)
			(layers "F.Cu" "F.Mask" "F.Paste")
			(net "GND")
		)
		(pad "L14" smd circle
			(at 1.999996 -0.40005 270)
			(size 0.3556 0.3556)
			(layers "F.Cu" "F.Mask" "F.Paste")
			(net "GND")
		)
		(pad "L16" smd circle
			(at 3.599942 -0.40005 270)
			(size 0.3556 0.3556)
			(layers "F.Cu" "F.Mask" "F.Paste")
			(net "P3V3_STBY")
		)
		(pad "L17" smd circle
			(at 4.400042 -0.40005 270)
			(size 0.3556 0.3556)
			(layers "F.Cu" "F.Mask" "F.Paste")
			(net "P1V15_STBY")
		)
		(pad "L18" smd circle
			(at 5.199888 -0.40005 270)
			(size 0.3556 0.3556)
			(layers "F.Cu" "F.Mask" "F.Paste")
			(net "Net_651")
		)
		(pad "L19" smd circle
			(at 5.999988 -0.40005 270)
			(size 0.3556 0.3556)
			(layers "F.Cu" "F.Mask" "F.Paste")
			(net "Net_650")
		)
		(pad "L20" smd circle
			(at 6.800088 -0.40005 270)
			(size 0.3556 0.3556)
			(layers "F.Cu" "F.Mask" "F.Paste")
			(net "PD_PERST_N")
		)
		(pad "L21" smd circle
			(at 7.599934 -0.40005 270)
			(size 0.3556 0.3556)
			(layers "F.Cu" "F.Mask" "F.Paste")
			(net "Net_649")
		)
		(pad "L22" smd circle
			(at 8.400034 -0.40005 270)
			(size 0.3556 0.3556)
			(layers "F.Cu" "F.Mask" "F.Paste")
			(net "Net_648")
		)
		(pad "M1" smd circle
			(at -8.400034 0.40005 270)
			(size 0.3556 0.3556)
			(layers "F.Cu" "F.Mask" "F.Paste")
			(net "GND")
		)
		(pad "M2" smd circle
			(at -7.599934 0.40005 270)
			(size 0.3556 0.3556)
			(layers "F.Cu" "F.Mask" "F.Paste")
			(net "GND")
		)
		(pad "M3" smd circle
			(at -6.800088 0.40005 270)
			(size 0.3556 0.3556)
			(layers "F.Cu" "F.Mask" "F.Paste")
			(net "GND")
		)
		(pad "M4" smd circle
			(at -5.999988 0.40005 270)
			(size 0.3556 0.3556)
			(layers "F.Cu" "F.Mask" "F.Paste")
			(net "GND")
		)
		(pad "M5" smd circle
			(at -5.199888 0.40005 270)
			(size 0.3556 0.3556)
			(layers "F.Cu" "F.Mask" "F.Paste")
			(net "GND")
		)
		(pad "M6" smd circle
			(at -4.400042 0.40005 270)
			(size 0.3556 0.3556)
			(layers "F.Cu" "F.Mask" "F.Paste")
			(net "GND")
		)
		(pad "M7" smd circle
			(at -3.599942 0.40005 270)
			(size 0.3556 0.3556)
			(layers "F.Cu" "F.Mask" "F.Paste")
			(net "GND")
		)
		(pad "M9" smd circle
			(at -1.999996 0.40005 270)
			(size 0.3556 0.3556)
			(layers "F.Cu" "F.Mask" "F.Paste")
			(net "GND")
		)
		(pad "M10" smd circle
			(at -1.199896 0.40005 270)
			(size 0.3556 0.3556)
			(layers "F.Cu" "F.Mask" "F.Paste")
			(net "GND")
		)
		(pad "M11" smd circle
			(at -0.40005 0.40005 270)
			(size 0.3556 0.3556)
			(layers "F.Cu" "F.Mask" "F.Paste")
			(net "GND")
		)
		(pad "M12" smd circle
			(at 0.40005 0.40005 270)
			(size 0.3556 0.3556)
			(layers "F.Cu" "F.Mask" "F.Paste")
			(net "GND")
		)
		(pad "M13" smd circle
			(at 1.199896 0.40005 270)
			(size 0.3556 0.3556)
			(layers "F.Cu" "F.Mask" "F.Paste")
			(net "GND")
		)
		(pad "M14" smd circle
			(at 1.999996 0.40005 270)
			(size 0.3556 0.3556)
			(layers "F.Cu" "F.Mask" "F.Paste")
			(net "GND")
		)
		(pad "M16" smd circle
			(at 3.599942 0.40005 270)
			(size 0.3556 0.3556)
			(layers "F.Cu" "F.Mask" "F.Paste")
			(net "GND")
		)
		(pad "M17" smd circle
			(at 4.400042 0.40005 270)
			(size 0.3556 0.3556)
			(layers "F.Cu" "F.Mask" "F.Paste")
			(net "GND")
		)
		(pad "M18" smd circle
			(at 5.199888 0.40005 270)
			(size 0.3556 0.3556)
			(layers "F.Cu" "F.Mask" "F.Paste")
			(net "BMC_SMB1_CLK")
		)
		(pad "M19" smd circle
			(at 5.999988 0.40005 270)
			(size 0.3556 0.3556)
			(layers "F.Cu" "F.Mask" "F.Paste")
			(net "BMC_SMB1_DAT")
		)
		(pad "M20" smd circle
			(at 6.800088 0.40005 270)
			(size 0.3556 0.3556)
			(layers "F.Cu" "F.Mask" "F.Paste")
			(net "BMC_SMB2_CLK")
		)
		(pad "M21" smd circle
			(at 7.599934 0.40005 270)
			(size 0.3556 0.3556)
			(layers "F.Cu" "F.Mask" "F.Paste")
			(net "GND")
		)
		(pad "M22" smd circle
			(at 8.400034 0.40005 270)
			(size 0.3556 0.3556)
			(layers "F.Cu" "F.Mask" "F.Paste")
			(net "GND")
		)
		(pad "N1" smd circle
			(at -8.400034 1.199896 270)
			(size 0.3556 0.3556)
			(layers "F.Cu" "F.Mask" "F.Paste")
			(net "BMC_SMB7_CLK")
		)
		(pad "N2" smd circle
			(at -7.599934 1.199896 270)
			(size 0.3556 0.3556)
			(layers "F.Cu" "F.Mask" "F.Paste")
			(net "BMC_SMB6_DAT")
		)
		(pad "N3" smd circle
			(at -6.800088 1.199896 270)
			(size 0.3556 0.3556)
			(layers "F.Cu" "F.Mask" "F.Paste")
			(net "BOARD_REV_2")
		)
		(pad "N4" smd circle
			(at -5.999988 1.199896 270)
			(size 0.3556 0.3556)
			(layers "F.Cu" "F.Mask" "F.Paste")
			(net "PCIE_WAKE_N")
		)
		(pad "N5" smd circle
			(at -5.199888 1.199896 270)
			(size 0.3556 0.3556)
			(layers "F.Cu" "F.Mask" "F.Paste")
			(net "IOM_TYPE0")
		)
		(pad "N6" smd circle
			(at -4.400042 1.199896 270)
			(size 0.3556 0.3556)
			(layers "F.Cu" "F.Mask" "F.Paste")
			(net "P3V3_STBY")
		)
		(pad "N7" smd circle
			(at -3.599942 1.199896 270)
			(size 0.3556 0.3556)
			(layers "F.Cu" "F.Mask" "F.Paste")
			(net "P1V15_STBY")
		)
		(pad "N9" smd circle
			(at -1.999996 1.199896 270)
			(size 0.3556 0.3556)
			(layers "F.Cu" "F.Mask" "F.Paste")
			(net "GND")
		)
		(pad "N10" smd circle
			(at -1.199896 1.199896 270)
			(size 0.3556 0.3556)
			(layers "F.Cu" "F.Mask" "F.Paste")
			(net "GND")
		)
		(pad "N11" smd circle
			(at -0.40005 1.199896 270)
			(size 0.3556 0.3556)
			(layers "F.Cu" "F.Mask" "F.Paste")
			(net "GND")
		)
		(pad "N12" smd circle
			(at 0.40005 1.199896 270)
			(size 0.3556 0.3556)
			(layers "F.Cu" "F.Mask" "F.Paste")
			(net "GND")
		)
		(pad "N13" smd circle
			(at 1.199896 1.199896 270)
			(size 0.3556 0.3556)
			(layers "F.Cu" "F.Mask" "F.Paste")
			(net "GND")
		)
		(pad "N14" smd circle
			(at 1.999996 1.199896 270)
			(size 0.3556 0.3556)
			(layers "F.Cu" "F.Mask" "F.Paste")
			(net "GND")
		)
		(pad "N16" smd circle
			(at 3.599942 1.199896 270)
			(size 0.3556 0.3556)
			(layers "F.Cu" "F.Mask" "F.Paste")
			(net "P1V15_STBY")
		)
		(pad "N17" smd circle
			(at 4.400042 1.199896 270)
			(size 0.3556 0.3556)
			(layers "F.Cu" "F.Mask" "F.Paste")
			(net "P3V3_STBY")
		)
		(pad "N18" smd circle
			(at 5.199888 1.199896 270)
			(size 0.3556 0.3556)
			(layers "F.Cu" "F.Mask" "F.Paste")
			(net "I2C_MEZZ_ALERT_N")
		)
		(pad "N19" smd circle
			(at 5.999988 1.199896 270)
			(size 0.3556 0.3556)
			(layers "F.Cu" "F.Mask" "F.Paste")
			(net "IOM_LOC_INS_N")
		)
		(pad "N20" smd circle
			(at 6.800088 1.199896 270)
			(size 0.3556 0.3556)
			(layers "F.Cu" "F.Mask" "F.Paste")
			(net "Net_647")
		)
		(pad "N21" smd circle
			(at 7.599934 1.199896 270)
			(size 0.3556 0.3556)
			(layers "F.Cu" "F.Mask" "F.Paste")
			(net "BMC_SMB14_CLK")
		)
		(pad "N22" smd circle
			(at 8.400034 1.199896 270)
			(size 0.3556 0.3556)
			(layers "F.Cu" "F.Mask" "F.Paste")
			(net "BMC_SMB14_DAT")
		)
		(pad "P1" smd circle
			(at -8.400034 1.999996 270)
			(size 0.3556 0.3556)
			(layers "F.Cu" "F.Mask" "F.Paste")
			(net "BMC_SMB7_DAT")
		)
		(pad "P2" smd circle
			(at -7.599934 1.999996 270)
			(size 0.3556 0.3556)
			(layers "F.Cu" "F.Mask" "F.Paste")
			(net "BMC_SMB8_CLK")
		)
		(pad "P3" smd circle
			(at -6.800088 1.999996 270)
			(size 0.3556 0.3556)
			(layers "F.Cu" "F.Mask" "F.Paste")
			(net "TP_BMC_GPIOL5")
		)
		(pad "P4" smd circle
			(at -5.999988 1.999996 270)
			(size 0.3556 0.3556)
			(layers "F.Cu" "F.Mask" "F.Paste")
			(net "TP_BMC_GPIOL4")
		)
		(pad "P5" smd circle
			(at -5.199888 1.999996 270)
			(size 0.3556 0.3556)
			(layers "F.Cu" "F.Mask" "F.Paste")
			(net "Net_287")
		)
		(pad "P6" smd circle
			(at -4.400042 1.999996 270)
			(size 0.3556 0.3556)
			(layers "F.Cu" "F.Mask" "F.Paste")
			(net "P3V3_STBY")
		)
		(pad "P7" smd circle
			(at -3.599942 1.999996 270)
			(size 0.3556 0.3556)
			(layers "F.Cu" "F.Mask" "F.Paste")
			(net "P1V15_STBY")
		)
		(pad "P9" smd circle
			(at -1.999996 1.999996 270)
			(size 0.3556 0.3556)
			(layers "F.Cu" "F.Mask" "F.Paste")
			(net "P1V15_STBY")
		)
		(pad "P10" smd circle
			(at -1.199896 1.999996 270)
			(size 0.3556 0.3556)
			(layers "F.Cu" "F.Mask" "F.Paste")
			(net "P1V15_STBY")
		)
		(pad "P11" smd circle
			(at -0.40005 1.999996 270)
			(size 0.3556 0.3556)
			(layers "F.Cu" "F.Mask" "F.Paste")
			(net "P1V15_STBY")
		)
		(pad "P12" smd circle
			(at 0.40005 1.999996 270)
			(size 0.3556 0.3556)
			(layers "F.Cu" "F.Mask" "F.Paste")
			(net "P1V15_STBY")
		)
		(pad "P13" smd circle
			(at 1.199896 1.999996 270)
			(size 0.3556 0.3556)
			(layers "F.Cu" "F.Mask" "F.Paste")
			(net "P1V15_STBY")
		)
		(pad "P14" smd circle
			(at 1.999996 1.999996 270)
			(size 0.3556 0.3556)
			(layers "F.Cu" "F.Mask" "F.Paste")
			(net "P1V15_STBY")
		)
		(pad "P16" smd circle
			(at 3.599942 1.999996 270)
			(size 0.3556 0.3556)
			(layers "F.Cu" "F.Mask" "F.Paste")
			(net "P1V15_STBY")
		)
		(pad "P17" smd circle
			(at 4.400042 1.999996 270)
			(size 0.3556 0.3556)
			(layers "F.Cu" "F.Mask" "F.Paste")
			(net "P3V3_STBY")
		)
		(pad "P18" smd circle
			(at 5.199888 1.999996 270)
			(size 0.3556 0.3556)
			(layers "F.Cu" "F.Mask" "F.Paste")
			(net "Net_20")
		)
		(pad "P19" smd circle
			(at 5.999988 1.999996 270)
			(size 0.3556 0.3556)
			(layers "F.Cu" "F.Mask" "F.Paste")
			(net "IOM_FULL_PWR_EN_R")
		)
		(pad "P20" smd circle
			(at 6.800088 1.999996 270)
			(size 0.3556 0.3556)
			(layers "F.Cu" "F.Mask" "F.Paste")
			(net "BMC_SMB2_DAT")
		)
		(pad "P21" smd circle
			(at 7.599934 1.999996 270)
			(size 0.3556 0.3556)
			(layers "F.Cu" "F.Mask" "F.Paste")
			(net "BMC_GPIOY3")
		)
		(pad "P22" smd circle
			(at 8.400034 1.999996 270)
			(size 0.3556 0.3556)
			(layers "F.Cu" "F.Mask" "F.Paste")
			(net "BMC_GPIOY2")
		)
		(pad "R1" smd circle
			(at -8.400034 2.800096 270)
			(size 0.3556 0.3556)
			(layers "F.Cu" "F.Mask" "F.Paste")
			(net "BMC_SMB8_DAT")
		)
		(pad "R2" smd circle
			(at -7.599934 2.800096 270)
			(size 0.3556 0.3556)
			(layers "F.Cu" "F.Mask" "F.Paste")
			(net "BOARD_REV_0")
		)
		(pad "R3" smd circle
			(at -6.800088 2.800096 270)
			(size 0.3556 0.3556)
			(layers "F.Cu" "F.Mask" "F.Paste")
			(net "IOM_TYPE2")
		)
		(pad "R4" smd circle
			(at -5.999988 2.800096 270)
			(size 0.3556 0.3556)
			(layers "F.Cu" "F.Mask" "F.Paste")
			(net "IOM_TYPE1")
		)
		(pad "R5" smd circle
			(at -5.199888 2.800096 270)
			(size 0.3556 0.3556)
			(layers "F.Cu" "F.Mask" "F.Paste")
			(net "UART_EXP_BMC_RX_R")
		)
		(pad "R6" smd circle
			(at -4.400042 2.800096 270)
			(size 0.3556 0.3556)
			(layers "F.Cu" "F.Mask" "F.Paste")
			(net "P3V3_STBY")
		)
		(pad "R7" smd circle
			(at -3.599942 2.800096 270)
			(size 0.3556 0.3556)
			(layers "F.Cu" "F.Mask" "F.Paste")
			(net "P1V15_STBY")
		)
		(pad "R16" smd circle
			(at 3.599942 2.800096 270)
			(size 0.3556 0.3556)
			(layers "F.Cu" "F.Mask" "F.Paste")
			(net "P1V15_STBY")
		)
		(pad "R17" smd circle
			(at 4.400042 2.800096 270)
			(size 0.3556 0.3556)
			(layers "F.Cu" "F.Mask" "F.Paste")
			(net "P3V3_STBY")
		)
		(pad "R18" smd circle
			(at 5.199888 2.800096 270)
			(size 0.3556 0.3556)
			(layers "F.Cu" "F.Mask" "F.Paste")
			(net "BMC_UART_SEL_IN")
		)
		(pad "R19" smd circle
			(at 5.999988 2.800096 270)
			(size 0.3556 0.3556)
			(layers "F.Cu" "F.Mask" "F.Paste")
			(net "BMC_GPIOS4")
		)
		(pad "R20" smd circle
			(at 6.800088 2.800096 270)
			(size 0.3556 0.3556)
			(layers "F.Cu" "F.Mask" "F.Paste")
			(net "Net_121")
		)
		(pad "R21" smd circle
			(at 7.599934 2.800096 270)
			(size 0.3556 0.3556)
			(layers "F.Cu" "F.Mask" "F.Paste")
			(net "BMC_GPIOY1")
		)
		(pad "R22" smd circle
			(at 8.400034 2.800096 270)
			(size 0.3556 0.3556)
			(layers "F.Cu" "F.Mask" "F.Paste")
			(net "BMC_GPIOY0")
		)
		(pad "T1" smd circle
			(at -8.400034 3.599942 270)
			(size 0.3556 0.3556)
			(layers "F.Cu" "F.Mask" "F.Paste")
			(net "TP_BMC_GPIOL1")
		)
		(pad "T2" smd circle
			(at -7.599934 3.599942 270)
			(size 0.3556 0.3556)
			(layers "F.Cu" "F.Mask" "F.Paste")
			(net "TP_BMC_GPIOL0")
		)
		(pad "T3" smd circle
			(at -6.800088 3.599942 270)
			(size 0.3556 0.3556)
			(layers "F.Cu" "F.Mask" "F.Paste")
			(net "IOM_TYPE3")
		)
		(pad "T4" smd circle
			(at -5.999988 3.599942 270)
			(size 0.3556 0.3556)
			(layers "F.Cu" "F.Mask" "F.Paste")
			(net "TP_BMC_GPION7")
		)
		(pad "T5" smd circle
			(at -5.199888 3.599942 270)
			(size 0.3556 0.3556)
			(layers "F.Cu" "F.Mask" "F.Paste")
			(net "UART_EXP_BMC_TX_R")
		)
		(pad "T6" smd circle
			(at -4.400042 3.599942 270)
			(size 0.3556 0.3556)
			(layers "F.Cu" "F.Mask" "F.Paste")
			(net "GND")
		)
		(pad "T7" smd circle
			(at -3.599942 3.599942 270)
			(size 0.3556 0.3556)
			(layers "F.Cu" "F.Mask" "F.Paste")
			(net "GND")
		)
		(pad "T8" smd circle
			(at -2.800096 3.599942 270)
			(size 0.3556 0.3556)
			(layers "F.Cu" "F.Mask" "F.Paste")
			(net "P1V2_STBY")
		)
		(pad "T9" smd circle
			(at -1.999996 3.599942 270)
			(size 0.3556 0.3556)
			(layers "F.Cu" "F.Mask" "F.Paste")
			(net "DDR_VREF")
		)
		(pad "T10" smd circle
			(at -1.199896 3.599942 270)
			(size 0.3556 0.3556)
			(layers "F.Cu" "F.Mask" "F.Paste")
			(net "P1V2_STBY")
		)
		(pad "T11" smd circle
			(at -0.40005 3.599942 270)
			(size 0.3556 0.3556)
			(layers "F.Cu" "F.Mask" "F.Paste")
			(net "MPLLAV33")
		)
		(pad "T12" smd circle
			(at 0.40005 3.599942 270)
			(size 0.3556 0.3556)
			(layers "F.Cu" "F.Mask" "F.Paste")
			(net "P1V2_STBY")
		)
		(pad "T13" smd circle
			(at 1.199896 3.599942 270)
			(size 0.3556 0.3556)
			(layers "F.Cu" "F.Mask" "F.Paste")
			(net "P1V2_STBY")
		)
		(pad "T14" smd circle
			(at 1.999996 3.599942 270)
			(size 0.3556 0.3556)
			(layers "F.Cu" "F.Mask" "F.Paste")
			(net "P1V2_STBY")
		)
		(pad "T15" smd circle
			(at 2.800096 3.599942 270)
			(size 0.3556 0.3556)
			(layers "F.Cu" "F.Mask" "F.Paste")
			(net "P3V3_STBY")
		)
		(pad "T16" smd circle
			(at 3.599942 3.599942 270)
			(size 0.3556 0.3556)
			(layers "F.Cu" "F.Mask" "F.Paste")
			(net "GND")
		)
		(pad "T17" smd circle
			(at 4.400042 3.599942 270)
			(size 0.3556 0.3556)
			(layers "F.Cu" "F.Mask" "F.Paste")
			(net "TP_BMC_GPIOR2")
		)
		(pad "T18" smd circle
			(at 5.199888 3.599942 270)
			(size 0.3556 0.3556)
			(layers "F.Cu" "F.Mask" "F.Paste")
			(net "BMC_SPI_MISO")
		)
		(pad "T19" smd circle
			(at 5.999988 3.599942 270)
			(size 0.3556 0.3556)
			(layers "F.Cu" "F.Mask" "F.Paste")
			(net "TP_BMC_GPIOR1")
		)
		(pad "T20" smd circle
			(at 6.800088 3.599942 270)
			(size 0.3556 0.3556)
			(layers "F.Cu" "F.Mask" "F.Paste")
			(net "Net_98")
		)
		(pad "T21" smd circle
			(at 7.599934 3.599942 270)
			(size 0.3556 0.3556)
			(layers "F.Cu" "F.Mask" "F.Paste")
			(net "IOM_FULL_PGOOD")
		)
		(pad "T22" smd circle
			(at 8.400034 3.599942 270)
			(size 0.3556 0.3556)
			(layers "F.Cu" "F.Mask" "F.Paste")
			(net "BMC_SELF_HW_RST")
		)
		(pad "U1" smd circle
			(at -8.400034 4.400042 270)
			(size 0.3556 0.3556)
			(layers "F.Cu" "F.Mask" "F.Paste")
			(net "TP_BMC_GPIOL2")
		)
		(pad "U2" smd circle
			(at -7.599934 4.400042 270)
			(size 0.3556 0.3556)
			(layers "F.Cu" "F.Mask" "F.Paste")
			(net "TP_BMC_GPIOL3")
		)
		(pad "U3" smd circle
			(at -6.800088 4.400042 270)
			(size 0.3556 0.3556)
			(layers "F.Cu" "F.Mask" "F.Paste")
			(net "TP_BMC_GPION3")
		)
		(pad "U4" smd circle
			(at -5.999988 4.400042 270)
			(size 0.3556 0.3556)
			(layers "F.Cu" "F.Mask" "F.Paste")
			(net "BMC_LOC_HB")
		)
		(pad "U5" smd circle
			(at -5.199888 4.400042 270)
			(size 0.3556 0.3556)
			(layers "F.Cu" "F.Mask" "F.Paste")
			(net "BMC_RMT_HB")
		)
		(pad "U6" smd circle
			(at -4.400042 4.400042 270)
			(size 0.3556 0.3556)
			(layers "F.Cu" "F.Mask" "F.Paste")
			(net "GND")
		)
		(pad "U7" smd circle
			(at -3.599942 4.400042 270)
			(size 0.3556 0.3556)
			(layers "F.Cu" "F.Mask" "F.Paste")
			(net "MEMDQ_15")
		)
		(pad "U8" smd circle
			(at -2.800096 4.400042 270)
			(size 0.3556 0.3556)
			(layers "F.Cu" "F.Mask" "F.Paste")
			(net "MEMDM_0")
		)
		(pad "U9" smd circle
			(at -1.999996 4.400042 270)
			(size 0.3556 0.3556)
			(layers "F.Cu" "F.Mask" "F.Paste")
			(net "MEMDQ_4")
		)
		(pad "U10" smd circle
			(at -1.199896 4.400042 270)
			(size 0.3556 0.3556)
			(layers "F.Cu" "F.Mask" "F.Paste")
			(net "MEMDQ_0")
		)
		(pad "U11" smd circle
			(at -0.40005 4.400042 270)
			(size 0.3556 0.3556)
			(layers "F.Cu" "F.Mask" "F.Paste")
			(net "GND")
		)
		(pad "U12" smd circle
			(at 0.40005 4.400042 270)
			(size 0.3556 0.3556)
			(layers "F.Cu" "F.Mask" "F.Paste")
			(net "MEMBA_0")
		)
		(pad "U13" smd circle
			(at 1.199896 4.400042 270)
			(size 0.3556 0.3556)
			(layers "F.Cu" "F.Mask" "F.Paste")
			(net "MEMA_10")
		)
		(pad "U14" smd circle
			(at 1.999996 4.400042 270)
			(size 0.3556 0.3556)
			(layers "F.Cu" "F.Mask" "F.Paste")
			(net "MEMA_3")
		)
		(pad "U15" smd circle
			(at 2.800096 4.400042 270)
			(size 0.3556 0.3556)
			(layers "F.Cu" "F.Mask" "F.Paste")
			(net "Net_654")
		)
		(pad "U16" smd circle
			(at 3.599942 4.400042 270)
			(size 0.3556 0.3556)
			(layers "F.Cu" "F.Mask" "F.Paste")
			(net "DDR4_ALERT")
		)
		(pad "U17" smd circle
			(at 4.400042 4.400042 270)
			(size 0.3556 0.3556)
			(layers "F.Cu" "F.Mask" "F.Paste")
			(net "BMC_SPI_MOSI")
		)
		(pad "U18" smd circle
			(at 5.199888 4.400042 270)
			(size 0.3556 0.3556)
			(layers "F.Cu" "F.Mask" "F.Paste")
			(net "BMC0_SRST_N")
		)
		(pad "U19" smd circle
			(at 5.999988 4.400042 270)
			(size 0.3556 0.3556)
			(layers "F.Cu" "F.Mask" "F.Paste")
			(net "BMC_UART_SEL_OUT")
		)
		(pad "U20" smd circle
			(at 6.800088 4.400042 270)
			(size 0.3556 0.3556)
			(layers "F.Cu" "F.Mask" "F.Paste")
			(net "BMC_GPIOS6")
		)
		(pad "U21" smd circle
			(at 7.599934 4.400042 270)
			(size 0.3556 0.3556)
			(layers "F.Cu" "F.Mask" "F.Paste")
			(net "BMC_GPIOZ4")
		)
		(pad "U22" smd circle
			(at 8.400034 4.400042 270)
			(size 0.3556 0.3556)
			(layers "F.Cu" "F.Mask" "F.Paste")
			(net "Net_22")
		)
		(pad "V1" smd circle
			(at -8.400034 5.199888 270)
			(size 0.3556 0.3556)
			(layers "F.Cu" "F.Mask" "F.Paste")
			(net "UART_BMC_COMP_IN_RX")
		)
		(pad "V2" smd circle
			(at -7.599934 5.199888 270)
			(size 0.3556 0.3556)
			(layers "F.Cu" "F.Mask" "F.Paste")
			(net "FAN_PWM0_BMC")
		)
		(pad "V3" smd circle
			(at -6.800088 5.199888 270)
			(size 0.3556 0.3556)
			(layers "F.Cu" "F.Mask" "F.Paste")
			(net "TP_BMC_GPION2")
		)
		(pad "V4" smd circle
			(at -5.999988 5.199888 270)
			(size 0.3556 0.3556)
			(layers "F.Cu" "F.Mask" "F.Paste")
			(net "DEBUG_GPIO_BMC_R_6")
		)
		(pad "V5" smd circle
			(at -5.199888 5.199888 270)
			(size 0.3556 0.3556)
			(layers "F.Cu" "F.Mask" "F.Paste")
			(net "FLA0_WP_N_R")
		)
		(pad "V6" smd circle
			(at -4.400042 5.199888 270)
			(size 0.3556 0.3556)
			(layers "F.Cu" "F.Mask" "F.Paste")
			(net "DEBUG_GPIO_BMC_R_5")
		)
		(pad "V7" smd circle
			(at -3.599942 5.199888 270)
			(size 0.3556 0.3556)
			(layers "F.Cu" "F.Mask" "F.Paste")
			(net "MEMDQ_14")
		)
		(pad "V8" smd circle
			(at -2.800096 5.199888 270)
			(size 0.3556 0.3556)
			(layers "F.Cu" "F.Mask" "F.Paste")
			(net "GND")
		)
		(pad "V9" smd circle
			(at -1.999996 5.199888 270)
			(size 0.3556 0.3556)
			(layers "F.Cu" "F.Mask" "F.Paste")
			(net "MEMDQ_7")
		)
		(pad "V10" smd circle
			(at -1.199896 5.199888 270)
			(size 0.3556 0.3556)
			(layers "F.Cu" "F.Mask" "F.Paste")
			(net "GND")
		)
		(pad "V11" smd circle
			(at -0.40005 5.199888 270)
			(size 0.3556 0.3556)
			(layers "F.Cu" "F.Mask" "F.Paste")
			(net "MEMODT")
		)
		(pad "V12" smd circle
			(at 0.40005 5.199888 270)
			(size 0.3556 0.3556)
			(layers "F.Cu" "F.Mask" "F.Paste")
			(net "GND")
		)
		(pad "V13" smd circle
			(at 1.199896 5.199888 270)
			(size 0.3556 0.3556)
			(layers "F.Cu" "F.Mask" "F.Paste")
			(net "MEMA_0")
		)
		(pad "V14" smd circle
			(at 1.999996 5.199888 270)
			(size 0.3556 0.3556)
			(layers "F.Cu" "F.Mask" "F.Paste")
			(net "GND")
		)
		(pad "V15" smd circle
			(at 2.800096 5.199888 270)
			(size 0.3556 0.3556)
			(layers "F.Cu" "F.Mask" "F.Paste")
			(net "MEMA_5")
		)
		(pad "V16" smd circle
			(at 3.599942 5.199888 270)
			(size 0.3556 0.3556)
			(layers "F.Cu" "F.Mask" "F.Paste")
			(net "GND")
		)
		(pad "V17" smd circle
			(at 4.400042 5.199888 270)
			(size 0.3556 0.3556)
			(layers "F.Cu" "F.Mask" "F.Paste")
			(net "P1V15_STBY")
		)
		(pad "V18" smd circle
			(at 5.199888 5.199888 270)
			(size 0.3556 0.3556)
			(layers "F.Cu" "F.Mask" "F.Paste")
			(net "BMC_EXTRST_N")
		)
		(pad "V19" smd circle
			(at 5.999988 5.199888 270)
			(size 0.3556 0.3556)
			(layers "F.Cu" "F.Mask" "F.Paste")
			(net "TP_BMC_GPIOR5")
		)
		(pad "V20" smd circle
			(at 6.800088 5.199888 270)
			(size 0.3556 0.3556)
			(layers "F.Cu" "F.Mask" "F.Paste")
			(net "EXP_UART_EN")
		)
		(pad "V21" smd circle
			(at 7.599934 5.199888 270)
			(size 0.3556 0.3556)
			(layers "F.Cu" "F.Mask" "F.Paste")
			(net "CONN_A_PRSNTA")
		)
		(pad "V22" smd circle
			(at 8.400034 5.199888 270)
			(size 0.3556 0.3556)
			(layers "F.Cu" "F.Mask" "F.Paste")
			(net "BMC_GPIOZ6")
		)
		(pad "W1" smd circle
			(at -8.400034 5.999988 270)
			(size 0.3556 0.3556)
			(layers "F.Cu" "F.Mask" "F.Paste")
			(net "UART_COMP_OUT_TX_R")
		)
		(pad "W2" smd circle
			(at -7.599934 5.999988 270)
			(size 0.3556 0.3556)
			(layers "F.Cu" "F.Mask" "F.Paste")
			(net "FAN_PWM1_BMC")
		)
		(pad "W3" smd circle
			(at -6.800088 5.999988 270)
			(size 0.3556 0.3556)
			(layers "F.Cu" "F.Mask" "F.Paste")
			(net "TP_BMC_GPION4")
		)
		(pad "W4" smd circle
			(at -5.999988 5.999988 270)
			(size 0.3556 0.3556)
			(layers "F.Cu" "F.Mask" "F.Paste")
			(net "COMP_PWR_EN_R")
		)
		(pad "W5" smd circle
			(at -5.199888 5.999988 270)
			(size 0.3556 0.3556)
			(layers "F.Cu" "F.Mask" "F.Paste")
			(net "Net_134")
		)
		(pad "W6" smd circle
			(at -4.400042 5.999988 270)
			(size 0.3556 0.3556)
			(layers "F.Cu" "F.Mask" "F.Paste")
			(net "DEBUG_GPIO_BMC_R_4")
		)
		(pad "W7" smd circle
			(at -3.599942 5.999988 270)
			(size 0.3556 0.3556)
			(layers "F.Cu" "F.Mask" "F.Paste")
			(net "MEMDQ_13")
		)
		(pad "W8" smd circle
			(at -2.800096 5.999988 270)
			(size 0.3556 0.3556)
			(layers "F.Cu" "F.Mask" "F.Paste")
			(net "MEMDQ_11")
		)
		(pad "W9" smd circle
			(at -1.999996 5.999988 270)
			(size 0.3556 0.3556)
			(layers "F.Cu" "F.Mask" "F.Paste")
			(net "MEMDQ_6")
		)
		(pad "W10" smd circle
			(at -1.199896 5.999988 270)
			(size 0.3556 0.3556)
			(layers "F.Cu" "F.Mask" "F.Paste")
			(net "MEMDQ_1")
		)
		(pad "W11" smd circle
			(at -0.40005 5.999988 270)
			(size 0.3556 0.3556)
			(layers "F.Cu" "F.Mask" "F.Paste")
			(net "MIOZ")
		)
		(pad "W12" smd circle
			(at 0.40005 5.999988 270)
			(size 0.3556 0.3556)
			(layers "F.Cu" "F.Mask" "F.Paste")
			(net "MEMRASN")
		)
		(pad "W13" smd circle
			(at 1.199896 5.999988 270)
			(size 0.3556 0.3556)
			(layers "F.Cu" "F.Mask" "F.Paste")
			(net "MEMBG_0")
		)
		(pad "W14" smd circle
			(at 1.999996 5.999988 270)
			(size 0.3556 0.3556)
			(layers "F.Cu" "F.Mask" "F.Paste")
			(net "MEMA_2")
		)
		(pad "W15" smd circle
			(at 2.800096 5.999988 270)
			(size 0.3556 0.3556)
			(layers "F.Cu" "F.Mask" "F.Paste")
			(net "MEMA_4")
		)
		(pad "W16" smd circle
			(at 3.599942 5.999988 270)
			(size 0.3556 0.3556)
			(layers "F.Cu" "F.Mask" "F.Paste")
			(net "MEMA_8")
		)
		(pad "W17" smd circle
			(at 4.400042 5.999988 270)
			(size 0.3556 0.3556)
			(layers "F.Cu" "F.Mask" "F.Paste")
			(net "MPLLAV33")
		)
		(pad "W18" smd circle
			(at 5.199888 5.999988 270)
			(size 0.3556 0.3556)
			(layers "F.Cu" "F.Mask" "F.Paste")
			(net "CLKIN_24M_BMC")
		)
		(pad "W19" smd circle
			(at 5.999988 5.999988 270)
			(size 0.3556 0.3556)
			(layers "F.Cu" "F.Mask" "F.Paste")
			(net "TP_BMC_GPIOR4")
		)
		(pad "W20" smd circle
			(at 6.800088 5.999988 270)
			(size 0.3556 0.3556)
			(layers "F.Cu" "F.Mask" "F.Paste")
			(net "BMC_GPIOS5")
		)
		(pad "W21" smd circle
			(at 7.599934 5.999988 270)
			(size 0.3556 0.3556)
			(layers "F.Cu" "F.Mask" "F.Paste")
			(net "BMC_GPIOZ7")
		)
		(pad "W22" smd circle
			(at 8.400034 5.999988 270)
			(size 0.3556 0.3556)
			(layers "F.Cu" "F.Mask" "F.Paste")
			(net "BMC_GPIOZ5")
		)
		(pad "Y1" smd circle
			(at -8.400034 6.800088 270)
			(size 0.4064 0.4064)
			(layers "F.Cu" "F.Mask" "F.Paste")
			(net "Net_282")
		)
		(pad "Y2" smd circle
			(at -7.599934 6.800088 270)
			(size 0.4064 0.4064)
			(layers "F.Cu" "F.Mask" "F.Paste")
			(net "Net_285")
		)
		(pad "Y3" smd circle
			(at -6.800088 6.800088 270)
			(size 0.4064 0.4064)
			(layers "F.Cu" "F.Mask" "F.Paste")
			(net "TP_BMC_GPION6")
		)
		(pad "Y4" smd circle
			(at -5.999988 6.800088 270)
			(size 0.3556 0.3556)
			(layers "F.Cu" "F.Mask" "F.Paste")
			(net "SCC_B_HB_IN_R")
		)
		(pad "Y5" smd circle
			(at -5.199888 6.800088 270)
			(size 0.3556 0.3556)
			(layers "F.Cu" "F.Mask" "F.Paste")
			(net "DEBUG_GPIO_BMC_R_3")
		)
		(pad "Y6" smd circle
			(at -4.400042 6.800088 270)
			(size 0.3556 0.3556)
			(layers "F.Cu" "F.Mask" "F.Paste")
			(net "DEBUG_GPIO_BMC_R_2")
		)
		(pad "Y7" smd circle
			(at -3.599942 6.800088 270)
			(size 0.3556 0.3556)
			(layers "F.Cu" "F.Mask" "F.Paste")
			(net "MEMDQ_10")
		)
		(pad "Y8" smd circle
			(at -2.800096 6.800088 270)
			(size 0.3556 0.3556)
			(layers "F.Cu" "F.Mask" "F.Paste")
			(net "MEMDQ_9")
		)
		(pad "Y9" smd circle
			(at -1.999996 6.800088 270)
			(size 0.3556 0.3556)
			(layers "F.Cu" "F.Mask" "F.Paste")
			(net "MEMDQ_5")
		)
		(pad "Y10" smd circle
			(at -1.199896 6.800088 270)
			(size 0.3556 0.3556)
			(layers "F.Cu" "F.Mask" "F.Paste")
			(net "MEMDQ_2")
		)
		(pad "Y11" smd circle
			(at -0.40005 6.800088 270)
			(size 0.3556 0.3556)
			(layers "F.Cu" "F.Mask" "F.Paste")
			(net "MEMCKE")
		)
		(pad "Y12" smd circle
			(at 0.40005 6.800088 270)
			(size 0.3556 0.3556)
			(layers "F.Cu" "F.Mask" "F.Paste")
			(net "MEMWEN")
		)
		(pad "Y13" smd circle
			(at 1.199896 6.800088 270)
			(size 0.3556 0.3556)
			(layers "F.Cu" "F.Mask" "F.Paste")
			(net "MEMBA_1")
		)
		(pad "Y14" smd circle
			(at 1.999996 6.800088 270)
			(size 0.3556 0.3556)
			(layers "F.Cu" "F.Mask" "F.Paste")
			(net "MEMA_12")
		)
		(pad "Y15" smd circle
			(at 2.800096 6.800088 270)
			(size 0.3556 0.3556)
			(layers "F.Cu" "F.Mask" "F.Paste")
			(net "DDR4_ACT")
		)
		(pad "Y16" smd circle
			(at 3.599942 6.800088 270)
			(size 0.3556 0.3556)
			(layers "F.Cu" "F.Mask" "F.Paste")
			(net "MEMA_9")
		)
		(pad "Y17" smd circle
			(at 4.400042 6.800088 270)
			(size 0.3556 0.3556)
			(layers "F.Cu" "F.Mask" "F.Paste")
			(net "MPLLAV33")
		)
		(pad "Y18" smd circle
			(at 5.199888 6.800088 270)
			(size 0.3556 0.3556)
			(layers "F.Cu" "F.Mask" "F.Paste")
			(net "BMC_HBLED")
		)
		(pad "Y19" smd circle
			(at 5.999988 6.800088 270)
			(size 0.3556 0.3556)
			(layers "F.Cu" "F.Mask" "F.Paste")
			(net "TP_BMC_GPIOR3")
		)
		(pad "Y20" smd circle
			(at 6.800088 6.800088 270)
			(size 0.4064 0.4064)
			(layers "F.Cu" "F.Mask" "F.Paste")
			(net "DEBUG_RST_BTN_N")
		)
		(pad "Y21" smd circle
			(at 7.599934 6.800088 270)
			(size 0.4064 0.4064)
			(layers "F.Cu" "F.Mask" "F.Paste")
			(net "Net_87")
		)
		(pad "Y22" smd circle
			(at 8.400034 6.800088 270)
			(size 0.4064 0.4064)
			(layers "F.Cu" "F.Mask" "F.Paste")
			(net "Net_21")
		)
	)
	(footprint ""
		(layer "F.Cu")
		(at 50.11801 -158.520638 180)
		(property "Reference" "R298"
			(at 0 0 180)
			(layer "F.SilkS")
			(hide yes)
			(effects
				(font
					(size 1.27 1.27)
				)
			)
		)
		(property "Value" "0R2J-2-GP"
			(at 0.064008 -3.993896 180)
			(unlocked yes)
			(layer "F.Fab")
			(hide yes)
			(effects
				(font
					(size 1.016 1.016)
					(thickness 0.1524)
				)
			)
		)
		(property "Device Type" "R402H16"
			(at 0.064008 -5.517896 180)
			(unlocked yes)
			(layer "F.Fab")
			(hide yes)
			(effects
				(font
					(size 1.016 1.016)
					(thickness 0.1524)
				)
			)
		)
		(duplicate_pad_numbers_are_jumpers no)
		(fp_line
			(start 0.508 -0.9398)
			(end -0.508 -0.9398)
			(stroke
				(width 0.1524)
				(type default)
			)
			(layer "F.SilkS")
		)
		(fp_line
			(start -0.508 -0.9398)
			(end -0.508 0.9398)
			(stroke
				(width 0.1524)
				(type default)
			)
			(layer "F.SilkS")
		)
		(fp_rect
			(start -0.508 0.9398)
			(end 0.508 -0.9398)
			(stroke
				(width 0)
				(type default)
			)
			(fill no)
			(layer "F.CrtYd")
		)
		(fp_rect
			(start -0.508 0.9398)
			(end 0.508 -0.9398)
			(stroke
				(width 0)
				(type default)
			)
			(fill no)
			(layer "F.Fab")
		)
		(pad "1" smd custom
			(at 0 -0.4445 180)
			(size 0.1397 0.1397)
			(layers "F.Cu" "F.Mask" "F.Paste")
			(net "UART_BMC_R_RX")
			(options
				(clearance outline)
				(anchor circle)
			)
			(primitives
				(gr_poly
					(pts
						(arc
							(start -0.1778 -0.2794)
							(mid -0.249642 -0.249642)
							(end -0.2794 -0.1778)
						)
						(arc
							(start -0.2794 0.1778)
							(mid -0.249642 0.249642)
							(end -0.1778 0.2794)
						)
						(arc
							(start 0.1778 0.2794)
							(mid 0.249642 0.249642)
							(end 0.2794 0.1778)
						)
						(arc
							(start 0.2794 -0.1778)
							(mid 0.249642 -0.249642)
							(end 0.1778 -0.2794)
						)
					)
					(width 0)
					(fill yes)
				)
			)
		)
		(pad "2" smd custom
			(at 0 0.4445 180)
			(size 0.1397 0.1397)
			(layers "F.Cu" "F.Mask" "F.Paste")
			(net "UART_BMC_RX")
			(options
				(clearance outline)
				(anchor circle)
			)
			(primitives
				(gr_poly
					(pts
						(arc
							(start -0.1778 -0.2794)
							(mid -0.249642 -0.249642)
							(end -0.2794 -0.1778)
						)
						(arc
							(start -0.2794 0.1778)
							(mid -0.249642 0.249642)
							(end -0.1778 0.2794)
						)
						(arc
							(start 0.1778 0.2794)
							(mid 0.249642 0.249642)
							(end 0.2794 0.1778)
						)
						(arc
							(start 0.2794 -0.1778)
							(mid 0.249642 -0.249642)
							(end 0.1778 -0.2794)
						)
					)
					(width 0)
					(fill yes)
				)
			)
		)
	)
	(footprint ""
		(layer "F.Cu")
		(at 88.107774 -167.71747)
		(property "Reference" "Q11"
			(at 0 0 0)
			(layer "F.SilkS")
			(hide yes)
			(effects
				(font
					(size 1.27 1.27)
				)
			)
		)
		(property "Value" "2N7002K-1-GP"
			(at 0.127 -8.9662 0)
			(unlocked yes)
			(layer "F.Fab")
			(hide yes)
			(effects
				(font
					(size 1.016 1.016)
					(thickness 0.1524)
				)
			)
		)
		(property "Device Type" "SOT23DGS2D4H44"
			(at 0.127 -10.4902 0)
			(unlocked yes)
			(layer "F.Fab")
			(hide yes)
			(effects
				(font
					(size 1.016 1.016)
					(thickness 0.1524)
				)
			)
		)
		(duplicate_pad_numbers_are_jumpers no)
		(fp_line
			(start -1.651 -1.778)
			(end -1.651 1.778)
			(stroke
				(width 0.1524)
				(type default)
			)
			(layer "F.SilkS")
		)
		(fp_line
			(start -1.651 1.778)
			(end 1.651 1.778)
			(stroke
				(width 0.1524)
				(type default)
			)
			(layer "F.SilkS")
		)
		(fp_line
			(start 1.651 -1.778)
			(end -1.651 -1.778)
			(stroke
				(width 0.1524)
				(type default)
			)
			(layer "F.SilkS")
		)
		(fp_line
			(start 1.651 1.778)
			(end 1.651 -1.778)
			(stroke
				(width 0.1524)
				(type default)
			)
			(layer "F.SilkS")
		)
		(fp_poly
			(pts
				(xy -1.778 1.8796) (xy -1.778 -1.8796) (xy 1.778 -1.8796) (xy 1.778 1.8796)
			)
			(stroke
				(width 0)
				(type default)
			)
			(fill no)
			(layer "F.CrtYd")
		)
		(fp_poly
			(pts
				(xy -1.778 1.8796) (xy -1.778 -1.8796) (xy 1.778 -1.8796) (xy 1.778 1.8796)
			)
			(stroke
				(width 0)
				(type default)
			)
			(fill no)
			(layer "F.Fab")
		)
		(pad "D" smd custom
			(at 0 -0.9525)
			(size 0.1905 0.1905)
			(layers "F.Cu" "F.Mask" "F.Paste")
			(net "P1V15_STBY_PG_G")
			(options
				(clearance outline)
				(anchor circle)
			)
			(primitives
				(gr_poly
					(pts
						(arc
							(start -0.1778 0.5715)
							(mid -0.321484 0.511984)
							(end -0.381 0.3683)
						)
						(arc
							(start -0.381 -0.3683)
							(mid -0.321484 -0.511984)
							(end -0.1778 -0.5715)
						)
						(arc
							(start 0.1778 -0.5715)
							(mid 0.321484 -0.511984)
							(end 0.381 -0.3683)
						)
						(arc
							(start 0.381 0.3683)
							(mid 0.321484 0.511984)
							(end 0.1778 0.5715)
						)
					)
					(width 0)
					(fill yes)
				)
			)
		)
		(pad "G" smd custom
			(at -0.98425 0.9525)
			(size 0.1905 0.1905)
			(layers "F.Cu" "F.Mask" "F.Paste")
			(net "P1V15_STBY_PG")
			(options
				(clearance outline)
				(anchor circle)
			)
			(primitives
				(gr_poly
					(pts
						(arc
							(start -0.1778 0.5715)
							(mid -0.321484 0.511984)
							(end -0.381 0.3683)
						)
						(arc
							(start -0.381 -0.3683)
							(mid -0.321484 -0.511984)
							(end -0.1778 -0.5715)
						)
						(arc
							(start 0.1778 -0.5715)
							(mid 0.321484 -0.511984)
							(end 0.381 -0.3683)
						)
						(arc
							(start 0.381 0.3683)
							(mid 0.321484 0.511984)
							(end 0.1778 0.5715)
						)
					)
					(width 0)
					(fill yes)
				)
			)
		)
		(pad "S" smd custom
			(at 0.98425 0.9525)
			(size 0.1905 0.1905)
			(layers "F.Cu" "F.Mask" "F.Paste")
			(net "GND")
			(options
				(clearance outline)
				(anchor circle)
			)
			(primitives
				(gr_poly
					(pts
						(arc
							(start -0.1778 0.5715)
							(mid -0.321484 0.511984)
							(end -0.381 0.3683)
						)
						(arc
							(start -0.381 -0.3683)
							(mid -0.321484 -0.511984)
							(end -0.1778 -0.5715)
						)
						(arc
							(start 0.1778 -0.5715)
							(mid 0.321484 -0.511984)
							(end 0.381 -0.3683)
						)
						(arc
							(start 0.381 0.3683)
							(mid 0.321484 0.511984)
							(end 0.1778 0.5715)
						)
					)
					(width 0)
					(fill yes)
				)
			)
		)
	)
	(footprint ""
		(layer "F.Cu")
		(at 40.2209 -159.77616)
		(property "Reference" "TP188"
			(at 0 0 0)
			(layer "F.SilkS")
			(hide yes)
			(effects
				(font
					(size 1.27 1.27)
				)
			)
		)
		(property "Value" "TPAD28-2-GP"
			(at -0.0127 -1.6637 0)
			(unlocked yes)
			(layer "F.Fab")
			(hide yes)
			(effects
				(font
					(size 1.016 1.016)
					(thickness 0.1524)
				)
			)
		)
		(property "Device Type" "TPAD28"
			(at -0.0127 -3.1877 0)
			(unlocked yes)
			(layer "F.Fab")
			(hide yes)
			(effects
				(font
					(size 1.016 1.016)
					(thickness 0.1524)
				)
			)
		)
		(duplicate_pad_numbers_are_jumpers no)
		(fp_poly
			(pts
				(arc
					(start 0.3556 0)
					(mid -0.3556 0)
					(end 0.3556 0)
				)
			)
			(stroke
				(width 0)
				(type default)
			)
			(fill no)
			(layer "F.CrtYd")
		)
		(fp_poly
			(pts
				(arc
					(start 0.6096 0)
					(mid -0.6096 0)
					(end 0.6096 0)
				)
			)
			(stroke
				(width 0)
				(type default)
			)
			(fill no)
			(layer "F.Fab")
		)
		(pad "1" smd circle
			(at 0 0)
			(size 0.7112 0.7112)
			(layers "F.Cu" "F.Mask" "F.Paste")
			(net "TP_BMC_GPIOL2")
		)
	)
	(footprint ""
		(layer "F.Cu")
		(at 182.7022 -153.3398 90)
		(property "Reference" "C156"
			(at 0 0 90)
			(layer "F.SilkS")
			(hide yes)
			(effects
				(font
					(size 1.27 1.27)
				)
			)
		)
		(property "Value" "SC1U16V3KX-5GP"
			(at 0 -2.8194 90)
			(unlocked yes)
			(layer "F.Fab")
			(hide yes)
			(effects
				(font
					(size 1.016 1.016)
					(thickness 0.1524)
				)
			)
		)
		(property "Device Type" "C603H36"
			(at 0 -4.3434 90)
			(unlocked yes)
			(layer "F.Fab")
			(hide yes)
			(effects
				(font
					(size 1.016 1.016)
					(thickness 0.1524)
				)
			)
		)
		(duplicate_pad_numbers_are_jumpers no)
		(fp_line
			(start 0.508 0)
			(end -0.508 0)
			(stroke
				(width 0.2032)
				(type default)
			)
			(layer "F.SilkS")
		)
		(fp_rect
			(start -0.5842 1.3335)
			(end 0.5842 -1.3335)
			(stroke
				(width 0)
				(type default)
			)
			(fill no)
			(layer "F.CrtYd")
		)
		(fp_rect
			(start -0.5842 1.3335)
			(end 0.5842 -1.3335)
			(stroke
				(width 0)
				(type default)
			)
			(fill no)
			(layer "F.Fab")
		)
		(pad "1" smd custom
			(at 0 -0.762 90)
			(size 0.2159 0.2159)
			(layers "F.Cu" "F.Mask" "F.Paste")
			(net "P5V_EN_R")
			(options
				(clearance outline)
				(anchor circle)
			)
			(primitives
				(gr_poly
					(pts
						(arc
							(start -0.3302 -0.4318)
							(mid -0.402042 -0.402042)
							(end -0.4318 -0.3302)
						)
						(arc
							(start -0.4318 0.3302)
							(mid -0.402042 0.402042)
							(end -0.3302 0.4318)
						)
						(arc
							(start 0.3302 0.4318)
							(mid 0.402042 0.402042)
							(end 0.4318 0.3302)
						)
						(arc
							(start 0.4318 -0.3302)
							(mid 0.402042 -0.402042)
							(end 0.3302 -0.4318)
						)
					)
					(width 0)
					(fill yes)
				)
			)
		)
		(pad "2" smd custom
			(at 0 0.762 90)
			(size 0.2159 0.2159)
			(layers "F.Cu" "F.Mask" "F.Paste")
			(net "GND")
			(options
				(clearance outline)
				(anchor circle)
			)
			(primitives
				(gr_poly
					(pts
						(arc
							(start -0.3302 -0.4318)
							(mid -0.402042 -0.402042)
							(end -0.4318 -0.3302)
						)
						(arc
							(start -0.4318 0.3302)
							(mid -0.402042 0.402042)
							(end -0.3302 0.4318)
						)
						(arc
							(start 0.3302 0.4318)
							(mid 0.402042 0.402042)
							(end 0.4318 0.3302)
						)
						(arc
							(start 0.4318 -0.3302)
							(mid 0.402042 -0.402042)
							(end 0.3302 -0.4318)
						)
					)
					(width 0)
					(fill yes)
				)
			)
		)
	)
	(footprint ""
		(layer "F.Cu")
		(at 70.3961 -153.0858 -90)
		(property "Reference" "R780"
			(at 0 0 270)
			(layer "F.SilkS")
			(hide yes)
			(effects
				(font
					(size 1.27 1.27)
				)
			)
		)
		(property "Value" "33R2J-2-GP"
			(at 0.064008 -3.993896 270)
			(unlocked yes)
			(layer "F.Fab")
			(hide yes)
			(effects
				(font
					(size 1.016 1.016)
					(thickness 0.1524)
				)
			)
		)
		(property "Device Type" "R402H16"
			(at 0.064008 -5.517896 270)
			(unlocked yes)
			(layer "F.Fab")
			(hide yes)
			(effects
				(font
					(size 1.016 1.016)
					(thickness 0.1524)
				)
			)
		)
		(duplicate_pad_numbers_are_jumpers no)
		(fp_line
			(start -0.508 -0.9398)
			(end -0.508 0.9398)
			(stroke
				(width 0.1524)
				(type default)
			)
			(layer "F.SilkS")
		)
		(fp_line
			(start 0.508 -0.9398)
			(end -0.508 -0.9398)
			(stroke
				(width 0.1524)
				(type default)
			)
			(layer "F.SilkS")
		)
		(fp_rect
			(start -0.508 0.9398)
			(end 0.508 -0.9398)
			(stroke
				(width 0)
				(type default)
			)
			(fill no)
			(layer "F.CrtYd")
		)
		(fp_rect
			(start -0.508 0.9398)
			(end 0.508 -0.9398)
			(stroke
				(width 0)
				(type default)
			)
			(fill no)
			(layer "F.Fab")
		)
		(pad "1" smd custom
			(at 0 -0.4445 270)
			(size 0.1397 0.1397)
			(layers "F.Cu" "F.Mask" "F.Paste")
			(net "U30_Q1")
			(options
				(clearance outline)
				(anchor circle)
			)
			(primitives
				(gr_poly
					(pts
						(arc
							(start -0.1778 -0.2794)
							(mid -0.249642 -0.249642)
							(end -0.2794 -0.1778)
						)
						(arc
							(start -0.2794 0.1778)
							(mid -0.249642 0.249642)
							(end -0.1778 0.2794)
						)
						(arc
							(start 0.1778 0.2794)
							(mid 0.249642 0.249642)
							(end 0.2794 0.1778)
						)
						(arc
							(start 0.2794 -0.1778)
							(mid 0.249642 -0.249642)
							(end 0.1778 -0.2794)
						)
					)
					(width 0)
					(fill yes)
				)
			)
		)
		(pad "2" smd custom
			(at 0 0.4445 270)
			(size 0.1397 0.1397)
			(layers "F.Cu" "F.Mask" "F.Paste")
			(net "CLK_50M_BMC_NCSI")
			(options
				(clearance outline)
				(anchor circle)
			)
			(primitives
				(gr_poly
					(pts
						(arc
							(start -0.1778 -0.2794)
							(mid -0.249642 -0.249642)
							(end -0.2794 -0.1778)
						)
						(arc
							(start -0.2794 0.1778)
							(mid -0.249642 0.249642)
							(end -0.1778 0.2794)
						)
						(arc
							(start 0.1778 0.2794)
							(mid 0.249642 0.249642)
							(end 0.2794 0.1778)
						)
						(arc
							(start 0.2794 -0.1778)
							(mid 0.249642 -0.249642)
							(end 0.1778 -0.2794)
						)
					)
					(width 0)
					(fill yes)
				)
			)
		)
	)
	(footprint ""
		(layer "F.Cu")
		(at 185.053986 -120.928892)
		(property "Reference" "C276"
			(at 0 0 0)
			(layer "F.SilkS")
			(hide yes)
			(effects
				(font
					(size 1.27 1.27)
				)
			)
		)
		(property "Value" "SC4700P25V2KX-3-GP"
			(at 1.1811 -2.7051 0)
			(unlocked yes)
			(layer "F.Fab")
			(hide yes)
			(effects
				(font
					(size 1.016 1.016)
					(thickness 0.1524)
				)
			)
		)
		(property "Device Type" "C402H24"
			(at 1.1811 -4.2291 0)
			(unlocked yes)
			(layer "F.Fab")
			(hide yes)
			(effects
				(font
					(size 1.016 1.016)
					(thickness 0.1524)
				)
			)
		)
		(duplicate_pad_numbers_are_jumpers no)
		(fp_rect
			(start -0.4318 0.9525)
			(end 0.4318 -0.9525)
			(stroke
				(width 0)
				(type default)
			)
			(fill no)
			(layer "F.CrtYd")
		)
		(fp_rect
			(start -0.4318 0.9525)
			(end 0.4318 -0.9525)
			(stroke
				(width 0)
				(type default)
			)
			(fill no)
			(layer "F.Fab")
		)
		(pad "1" smd custom
			(at 0 -0.4445)
			(size 0.1524 0.1524)
			(layers "F.Cu" "F.Mask" "F.Paste")
			(net "VT235_VDDH")
			(options
				(clearance outline)
				(anchor circle)
			)
			(primitives
				(gr_poly
					(pts
						(arc
							(start 0.3048 -0.2032)
							(mid 0.275042 -0.275042)
							(end 0.2032 -0.3048)
						)
						(arc
							(start -0.2032 -0.3048)
							(mid -0.275042 -0.275042)
							(end -0.3048 -0.2032)
						)
						(arc
							(start -0.3048 0.2032)
							(mid -0.275042 0.275042)
							(end -0.2032 0.3048)
						)
						(arc
							(start 0.2032 0.3048)
							(mid 0.275042 0.275042)
							(end 0.3048 0.2032)
						)
					)
					(width 0)
					(fill yes)
				)
			)
		)
		(pad "2" smd custom
			(at 0 0.4445)
			(size 0.1524 0.1524)
			(layers "F.Cu" "F.Mask" "F.Paste")
			(net "GND")
			(options
				(clearance outline)
				(anchor circle)
			)
			(primitives
				(gr_poly
					(pts
						(arc
							(start 0.3048 -0.2032)
							(mid 0.275042 -0.275042)
							(end 0.2032 -0.3048)
						)
						(arc
							(start -0.2032 -0.3048)
							(mid -0.275042 -0.275042)
							(end -0.3048 -0.2032)
						)
						(arc
							(start -0.3048 0.2032)
							(mid -0.275042 0.275042)
							(end -0.2032 0.3048)
						)
						(arc
							(start 0.2032 0.3048)
							(mid 0.275042 0.275042)
							(end 0.3048 0.2032)
						)
					)
					(width 0)
					(fill yes)
				)
			)
		)
	)
	(footprint ""
		(layer "F.Cu")
		(at 46.56328 -121.868692 180)
		(property "Reference" "R90"
			(at 0 0 180)
			(layer "F.SilkS")
			(hide yes)
			(effects
				(font
					(size 1.27 1.27)
				)
			)
		)
		(property "Value" "2K2R2J-2-GP"
			(at 0.064008 -3.993896 180)
			(unlocked yes)
			(layer "F.Fab")
			(hide yes)
			(effects
				(font
					(size 1.016 1.016)
					(thickness 0.1524)
				)
			)
		)
		(property "Device Type" "R402H16"
			(at 0.064008 -5.517896 180)
			(unlocked yes)
			(layer "F.Fab")
			(hide yes)
			(effects
				(font
					(size 1.016 1.016)
					(thickness 0.1524)
				)
			)
		)
		(duplicate_pad_numbers_are_jumpers no)
		(fp_line
			(start 0.508 -0.9398)
			(end -0.508 -0.9398)
			(stroke
				(width 0.1524)
				(type default)
			)
			(layer "F.SilkS")
		)
		(fp_line
			(start -0.508 -0.9398)
			(end -0.508 0.9398)
			(stroke
				(width 0.1524)
				(type default)
			)
			(layer "F.SilkS")
		)
		(fp_rect
			(start -0.508 0.9398)
			(end 0.508 -0.9398)
			(stroke
				(width 0)
				(type default)
			)
			(fill no)
			(layer "F.CrtYd")
		)
		(fp_rect
			(start -0.508 0.9398)
			(end 0.508 -0.9398)
			(stroke
				(width 0)
				(type default)
			)
			(fill no)
			(layer "F.Fab")
		)
		(pad "1" smd custom
			(at 0 -0.4445 180)
			(size 0.1397 0.1397)
			(layers "F.Cu" "F.Mask" "F.Paste")
			(net "P3V3_STBY")
			(options
				(clearance outline)
				(anchor circle)
			)
			(primitives
				(gr_poly
					(pts
						(arc
							(start -0.1778 -0.2794)
							(mid -0.249642 -0.249642)
							(end -0.2794 -0.1778)
						)
						(arc
							(start -0.2794 0.1778)
							(mid -0.249642 0.249642)
							(end -0.1778 0.2794)
						)
						(arc
							(start 0.1778 0.2794)
							(mid 0.249642 0.249642)
							(end 0.2794 0.1778)
						)
						(arc
							(start 0.2794 -0.1778)
							(mid 0.249642 -0.249642)
							(end 0.1778 -0.2794)
						)
					)
					(width 0)
					(fill yes)
				)
			)
		)
		(pad "2" smd custom
			(at 0 0.4445 180)
			(size 0.1397 0.1397)
			(layers "F.Cu" "F.Mask" "F.Paste")
			(net "BMC_CPU_EN")
			(options
				(clearance outline)
				(anchor circle)
			)
			(primitives
				(gr_poly
					(pts
						(arc
							(start -0.1778 -0.2794)
							(mid -0.249642 -0.249642)
							(end -0.2794 -0.1778)
						)
						(arc
							(start -0.2794 0.1778)
							(mid -0.249642 0.249642)
							(end -0.1778 0.2794)
						)
						(arc
							(start 0.1778 0.2794)
							(mid 0.249642 0.249642)
							(end 0.2794 0.1778)
						)
						(arc
							(start 0.2794 -0.1778)
							(mid 0.249642 -0.249642)
							(end 0.1778 -0.2794)
						)
					)
					(width 0)
					(fill yes)
				)
			)
		)
	)
	(footprint ""
		(layer "F.Cu")
		(at 8.65378 -12.97178)
		(property "Reference" "D3"
			(at 0 0 0)
			(layer "F.SilkS")
			(hide yes)
			(effects
				(font
					(size 1.27 1.27)
				)
			)
		)
		(property "Value" "PESD5V0X1UAB-GP"
			(at 0 -4.690618 0)
			(unlocked yes)
			(layer "F.Fab")
			(hide yes)
			(effects
				(font
					(size 1.016 1.016)
					(thickness 0.1524)
				)
			)
		)
		(property "Device Type" "SOD523AKH26"
			(at 0 -6.214618 0)
			(unlocked yes)
			(layer "F.Fab")
			(hide yes)
			(effects
				(font
					(size 1.016 1.016)
					(thickness 0.1524)
				)
			)
		)
		(duplicate_pad_numbers_are_jumpers no)
		(fp_line
			(start -0.5334 -1.4478)
			(end 0.5334 -1.4478)
			(stroke
				(width 0.1524)
				(type default)
			)
			(layer "F.SilkS")
		)
		(fp_line
			(start -0.5334 1.524)
			(end -0.5334 -1.4478)
			(stroke
				(width 0.1524)
				(type default)
			)
			(layer "F.SilkS")
		)
		(fp_line
			(start 0.4064 1.651)
			(end -0.4064 1.651)
			(stroke
				(width 0.4064)
				(type default)
			)
			(layer "F.SilkS")
		)
		(fp_line
			(start 0.5334 -1.4478)
			(end 0.5334 1.524)
			(stroke
				(width 0.1524)
				(type default)
			)
			(layer "F.SilkS")
		)
		(fp_line
			(start 0.5334 1.524)
			(end -0.5334 1.524)
			(stroke
				(width 0.1524)
				(type default)
			)
			(layer "F.SilkS")
		)
		(fp_rect
			(start -0.6096 1.8542)
			(end 0.6096 -1.524)
			(stroke
				(width 0)
				(type default)
			)
			(fill no)
			(layer "F.CrtYd")
		)
		(fp_poly
			(pts
				(xy -0.6096 -1.524) (xy 0.6096 -1.524) (xy 0.6096 1.8542) (xy -0.6096 1.8542)
			)
			(stroke
				(width 0)
				(type default)
			)
			(fill no)
			(layer "F.Fab")
		)
		(pad "A" smd rect
			(at 0 -0.762)
			(size 0.5588 1.016)
			(layers "F.Cu" "F.Mask" "F.Paste")
			(net "GND")
		)
		(pad "K" smd rect
			(at 0 0.762)
			(size 0.5588 1.016)
			(layers "F.Cu" "F.Mask" "F.Paste")
			(net "SYS_RST_BTN_IN_N")
		)
	)
	(footprint ""
		(layer "F.Cu")
		(at 168.6052 -110.9726 -90)
		(property "Reference" "C220"
			(at 0 0 270)
			(layer "F.SilkS")
			(hide yes)
			(effects
				(font
					(size 1.27 1.27)
				)
			)
		)
		(property "Value" "SC10U6D3V5KX-4GP"
			(at -0.0762 -6.1214 270)
			(unlocked yes)
			(layer "F.Fab")
			(hide yes)
			(effects
				(font
					(size 1.016 1.016)
					(thickness 0.1524)
				)
			)
		)
		(property "Device Type" "C805H58"
			(at -0.0762 -8.1534 270)
			(unlocked yes)
			(layer "F.Fab")
			(hide yes)
			(effects
				(font
					(size 1.016 1.016)
					(thickness 0.1524)
				)
			)
		)
		(duplicate_pad_numbers_are_jumpers no)
		(fp_line
			(start 0.635 0)
			(end -0.635 0)
			(stroke
				(width 0.508)
				(type default)
			)
			(layer "F.SilkS")
		)
		(fp_rect
			(start -0.9652 1.778)
			(end 0.9652 -1.778)
			(stroke
				(width 0)
				(type default)
			)
			(fill no)
			(layer "F.CrtYd")
		)
		(fp_poly
			(pts
				(xy -0.9652 -1.778) (xy 0.9652 -1.778) (xy 0.9652 1.778) (xy -0.9652 1.778)
			)
			(stroke
				(width 0)
				(type default)
			)
			(fill no)
			(layer "F.Fab")
		)
		(pad "1" smd rect
			(at 0 -0.9652 270)
			(size 1.397 1.143)
			(layers "F.Cu" "F.Mask" "F.Paste")
			(net "P1V8")
		)
		(pad "2" smd rect
			(at 0 0.9652 270)
			(size 1.397 1.143)
			(layers "F.Cu" "F.Mask" "F.Paste")
			(net "GND")
		)
	)
	(footprint ""
		(layer "F.Cu")
		(at 125.23089 -10.682478 -90)
		(property "Reference" "P1"
			(at 0 0 270)
			(layer "F.SilkS")
			(hide yes)
			(effects
				(font
					(size 1.27 1.27)
				)
			)
		)
		(property "Value" "0R0603-PAD-2-GP-U"
			(at 2.1209 -0.1397 270)
			(unlocked yes)
			(layer "F.Fab")
			(hide yes)
			(effects
				(font
					(size 1.016 1.016)
					(thickness 0.1524)
				)
			)
		)
		(property "Device Type" "0R0603-PAD-1-U"
			(at 2.1209 -1.6637 270)
			(unlocked yes)
			(layer "F.Fab")
			(hide yes)
			(effects
				(font
					(size 1.016 1.016)
					(thickness 0.1524)
				)
			)
		)
		(duplicate_pad_numbers_are_jumpers no)
		(fp_rect
			(start -0.5842 1.3335)
			(end 0.5842 -1.3335)
			(stroke
				(width 0)
				(type default)
			)
			(fill no)
			(layer "F.CrtYd")
		)
		(fp_rect
			(start -0.5842 1.3335)
			(end 0.5842 -1.3335)
			(stroke
				(width 0)
				(type default)
			)
			(fill no)
			(layer "F.Fab")
		)
		(pad "1" smd custom
			(at 0 -0.762 270)
			(size 0.2159 0.2159)
			(layers "F.Cu" "F.Mask" "F.Paste")
			(net "AGND_CURRENT_MON")
			(options
				(clearance outline)
				(anchor circle)
			)
			(primitives
				(gr_poly
					(pts
						(arc
							(start -0.3302 -0.5842)
							(mid -0.402042 -0.554442)
							(end -0.4318 -0.4826)
						)
						(arc
							(start -0.4318 0.4826)
							(mid -0.402042 0.554442)
							(end -0.3302 0.5842)
						)
						(arc
							(start 0.3302 0.5842)
							(mid 0.402042 0.554442)
							(end 0.4318 0.4826)
						)
						(arc
							(start 0.4318 -0.4826)
							(mid 0.402042 -0.554442)
							(end 0.3302 -0.5842)
						)
					)
					(width 0)
					(fill yes)
				)
			)
		)
		(pad "2" smd custom
			(at 0 0.762 270)
			(size 0.2159 0.2159)
			(layers "F.Cu" "F.Mask" "F.Paste")
			(net "GND")
			(options
				(clearance outline)
				(anchor circle)
			)
			(primitives
				(gr_poly
					(pts
						(arc
							(start -0.4318 0.4826)
							(mid -0.402042 0.554442)
							(end -0.3302 0.5842)
						)
						(arc
							(start 0.3302 0.5842)
							(mid 0.402042 0.554442)
							(end 0.4318 0.4826)
						)
						(arc
							(start 0.4318 -0.4826)
							(mid 0.402042 -0.554442)
							(end 0.3302 -0.5842)
						)
						(arc
							(start -0.3302 -0.5842)
							(mid -0.402042 -0.554442)
							(end -0.4318 -0.4826)
						)
					)
					(width 0)
					(fill yes)
				)
			)
		)
	)
	(footprint ""
		(layer "F.Cu")
		(at 98.552 -145.415 -90)
		(property "Reference" "R427"
			(at 0 0 270)
			(layer "F.SilkS")
			(hide yes)
			(effects
				(font
					(size 1.27 1.27)
				)
			)
		)
		(property "Value" "0R2J-2-GP"
			(at 0.064008 -3.993896 270)
			(unlocked yes)
			(layer "F.Fab")
			(hide yes)
			(effects
				(font
					(size 1.016 1.016)
					(thickness 0.1524)
				)
			)
		)
		(property "Device Type" "R402H16"
			(at 0.064008 -5.517896 270)
			(unlocked yes)
			(layer "F.Fab")
			(hide yes)
			(effects
				(font
					(size 1.016 1.016)
					(thickness 0.1524)
				)
			)
		)
		(duplicate_pad_numbers_are_jumpers no)
		(fp_line
			(start -0.508 -0.9398)
			(end -0.508 0.9398)
			(stroke
				(width 0.1524)
				(type default)
			)
			(layer "F.SilkS")
		)
		(fp_line
			(start 0.508 -0.9398)
			(end -0.508 -0.9398)
			(stroke
				(width 0.1524)
				(type default)
			)
			(layer "F.SilkS")
		)
		(fp_rect
			(start -0.508 0.9398)
			(end 0.508 -0.9398)
			(stroke
				(width 0)
				(type default)
			)
			(fill no)
			(layer "F.CrtYd")
		)
		(fp_rect
			(start -0.508 0.9398)
			(end 0.508 -0.9398)
			(stroke
				(width 0)
				(type default)
			)
			(fill no)
			(layer "F.Fab")
		)
		(pad "1" smd custom
			(at 0 -0.4445 270)
			(size 0.1397 0.1397)
			(layers "F.Cu" "F.Mask" "F.Paste")
			(net "I2C_DEBUG_SCL_L")
			(options
				(clearance outline)
				(anchor circle)
			)
			(primitives
				(gr_poly
					(pts
						(arc
							(start -0.1778 -0.2794)
							(mid -0.249642 -0.249642)
							(end -0.2794 -0.1778)
						)
						(arc
							(start -0.2794 0.1778)
							(mid -0.249642 0.249642)
							(end -0.1778 0.2794)
						)
						(arc
							(start 0.1778 0.2794)
							(mid 0.249642 0.249642)
							(end 0.2794 0.1778)
						)
						(arc
							(start 0.2794 -0.1778)
							(mid 0.249642 -0.249642)
							(end 0.1778 -0.2794)
						)
					)
					(width 0)
					(fill yes)
				)
			)
		)
		(pad "2" smd custom
			(at 0 0.4445 270)
			(size 0.1397 0.1397)
			(layers "F.Cu" "F.Mask" "F.Paste")
			(net "I2C_DEBUG_SCL_R")
			(options
				(clearance outline)
				(anchor circle)
			)
			(primitives
				(gr_poly
					(pts
						(arc
							(start -0.1778 -0.2794)
							(mid -0.249642 -0.249642)
							(end -0.2794 -0.1778)
						)
						(arc
							(start -0.2794 0.1778)
							(mid -0.249642 0.249642)
							(end -0.1778 0.2794)
						)
						(arc
							(start 0.1778 0.2794)
							(mid 0.249642 0.249642)
							(end 0.2794 0.1778)
						)
						(arc
							(start 0.2794 -0.1778)
							(mid 0.249642 -0.249642)
							(end 0.1778 -0.2794)
						)
					)
					(width 0)
					(fill yes)
				)
			)
		)
	)
	(footprint ""
		(layer "F.Cu")
		(at 196.977 -48.26 180)
		(property "Reference" "R636"
			(at 0 0 180)
			(layer "F.SilkS")
			(hide yes)
			(effects
				(font
					(size 1.27 1.27)
				)
			)
		)
		(property "Value" "4K7R2F-GP"
			(at 0.064008 -3.993896 180)
			(unlocked yes)
			(layer "F.Fab")
			(hide yes)
			(effects
				(font
					(size 1.016 1.016)
					(thickness 0.1524)
				)
			)
		)
		(property "Device Type" "R402H16"
			(at 0.064008 -5.517896 180)
			(unlocked yes)
			(layer "F.Fab")
			(hide yes)
			(effects
				(font
					(size 1.016 1.016)
					(thickness 0.1524)
				)
			)
		)
		(duplicate_pad_numbers_are_jumpers no)
		(fp_line
			(start 0.508 -0.9398)
			(end -0.508 -0.9398)
			(stroke
				(width 0.1524)
				(type default)
			)
			(layer "F.SilkS")
		)
		(fp_line
			(start -0.508 -0.9398)
			(end -0.508 0.9398)
			(stroke
				(width 0.1524)
				(type default)
			)
			(layer "F.SilkS")
		)
		(fp_rect
			(start -0.508 0.9398)
			(end 0.508 -0.9398)
			(stroke
				(width 0)
				(type default)
			)
			(fill no)
			(layer "F.CrtYd")
		)
		(fp_rect
			(start -0.508 0.9398)
			(end 0.508 -0.9398)
			(stroke
				(width 0)
				(type default)
			)
			(fill no)
			(layer "F.Fab")
		)
		(pad "1" smd custom
			(at 0 -0.4445 180)
			(size 0.1397 0.1397)
			(layers "F.Cu" "F.Mask" "F.Paste")
			(net "P1V8")
			(options
				(clearance outline)
				(anchor circle)
			)
			(primitives
				(gr_poly
					(pts
						(arc
							(start -0.1778 -0.2794)
							(mid -0.249642 -0.249642)
							(end -0.2794 -0.1778)
						)
						(arc
							(start -0.2794 0.1778)
							(mid -0.249642 0.249642)
							(end -0.1778 0.2794)
						)
						(arc
							(start 0.1778 0.2794)
							(mid 0.249642 0.249642)
							(end 0.2794 0.1778)
						)
						(arc
							(start 0.2794 -0.1778)
							(mid 0.249642 -0.249642)
							(end 0.1778 -0.2794)
						)
					)
					(width 0)
					(fill yes)
				)
			)
		)
		(pad "2" smd custom
			(at 0 0.4445 180)
			(size 0.1397 0.1397)
			(layers "F.Cu" "F.Mask" "F.Paste")
			(net "ICE0_TCK")
			(options
				(clearance outline)
				(anchor circle)
			)
			(primitives
				(gr_poly
					(pts
						(arc
							(start -0.1778 -0.2794)
							(mid -0.249642 -0.249642)
							(end -0.2794 -0.1778)
						)
						(arc
							(start -0.2794 0.1778)
							(mid -0.249642 0.249642)
							(end -0.1778 0.2794)
						)
						(arc
							(start 0.1778 0.2794)
							(mid 0.249642 0.249642)
							(end 0.2794 0.1778)
						)
						(arc
							(start 0.2794 -0.1778)
							(mid 0.249642 -0.249642)
							(end 0.1778 -0.2794)
						)
					)
					(width 0)
					(fill yes)
				)
			)
		)
	)
	(footprint ""
		(layer "F.Cu")
		(at 24.042116 -164.3507 90)
		(property "Reference" "C226"
			(at 0 0 90)
			(layer "F.SilkS")
			(hide yes)
			(effects
				(font
					(size 1.27 1.27)
				)
			)
		)
		(property "Value" "SC10U6D3V5KX-4GP"
			(at -0.0762 -6.1214 90)
			(unlocked yes)
			(layer "F.Fab")
			(hide yes)
			(effects
				(font
					(size 1.016 1.016)
					(thickness 0.1524)
				)
			)
		)
		(property "Device Type" "C805H58"
			(at -0.0762 -8.1534 90)
			(unlocked yes)
			(layer "F.Fab")
			(hide yes)
			(effects
				(font
					(size 1.016 1.016)
					(thickness 0.1524)
				)
			)
		)
		(duplicate_pad_numbers_are_jumpers no)
		(fp_line
			(start 0.635 0)
			(end -0.635 0)
			(stroke
				(width 0.508)
				(type default)
			)
			(layer "F.SilkS")
		)
		(fp_rect
			(start -0.9652 1.778)
			(end 0.9652 -1.778)
			(stroke
				(width 0)
				(type default)
			)
			(fill no)
			(layer "F.CrtYd")
		)
		(fp_poly
			(pts
				(xy -0.9652 -1.778) (xy 0.9652 -1.778) (xy 0.9652 1.778) (xy -0.9652 1.778)
			)
			(stroke
				(width 0)
				(type default)
			)
			(fill no)
			(layer "F.Fab")
		)
		(pad "1" smd rect
			(at 0 -0.9652 90)
			(size 1.397 1.143)
			(layers "F.Cu" "F.Mask" "F.Paste")
			(net "TPS74801_P1V2_STBY_OUT")
		)
		(pad "2" smd rect
			(at 0 0.9652 90)
			(size 1.397 1.143)
			(layers "F.Cu" "F.Mask" "F.Paste")
			(net "GND")
		)
	)
	(footprint ""
		(layer "F.Cu")
		(at 176.6824 -59.0296 90)
		(property "Reference" "R664"
			(at 0 0 90)
			(layer "F.SilkS")
			(hide yes)
			(effects
				(font
					(size 1.27 1.27)
				)
			)
		)
		(property "Value" "10KR2F-2-GP"
			(at 0.064008 -3.993896 90)
			(unlocked yes)
			(layer "F.Fab")
			(hide yes)
			(effects
				(font
					(size 1.016 1.016)
					(thickness 0.1524)
				)
			)
		)
		(property "Device Type" "R402H16"
			(at 0.064008 -5.517896 90)
			(unlocked yes)
			(layer "F.Fab")
			(hide yes)
			(effects
				(font
					(size 1.016 1.016)
					(thickness 0.1524)
				)
			)
		)
		(duplicate_pad_numbers_are_jumpers no)
		(fp_line
			(start 0.508 -0.9398)
			(end -0.508 -0.9398)
			(stroke
				(width 0.1524)
				(type default)
			)
			(layer "F.SilkS")
		)
		(fp_line
			(start -0.508 -0.9398)
			(end -0.508 0.9398)
			(stroke
				(width 0.1524)
				(type default)
			)
			(layer "F.SilkS")
		)
		(fp_rect
			(start -0.508 0.9398)
			(end 0.508 -0.9398)
			(stroke
				(width 0)
				(type default)
			)
			(fill no)
			(layer "F.CrtYd")
		)
		(fp_rect
			(start -0.508 0.9398)
			(end 0.508 -0.9398)
			(stroke
				(width 0)
				(type default)
			)
			(fill no)
			(layer "F.Fab")
		)
		(pad "1" smd custom
			(at 0 -0.4445 90)
			(size 0.1397 0.1397)
			(layers "F.Cu" "F.Mask" "F.Paste")
			(net "P1V8")
			(options
				(clearance outline)
				(anchor circle)
			)
			(primitives
				(gr_poly
					(pts
						(arc
							(start -0.1778 -0.2794)
							(mid -0.249642 -0.249642)
							(end -0.2794 -0.1778)
						)
						(arc
							(start -0.2794 0.1778)
							(mid -0.249642 0.249642)
							(end -0.1778 0.2794)
						)
						(arc
							(start 0.1778 0.2794)
							(mid 0.249642 0.249642)
							(end 0.2794 0.1778)
						)
						(arc
							(start 0.2794 -0.1778)
							(mid 0.249642 -0.249642)
							(end 0.1778 -0.2794)
						)
					)
					(width 0)
					(fill yes)
				)
			)
		)
		(pad "2" smd custom
			(at 0 0.4445 90)
			(size 0.1397 0.1397)
			(layers "F.Cu" "F.Mask" "F.Paste")
			(net "XM_ADDR_23")
			(options
				(clearance outline)
				(anchor circle)
			)
			(primitives
				(gr_poly
					(pts
						(arc
							(start -0.1778 -0.2794)
							(mid -0.249642 -0.249642)
							(end -0.2794 -0.1778)
						)
						(arc
							(start -0.2794 0.1778)
							(mid -0.249642 0.249642)
							(end -0.1778 0.2794)
						)
						(arc
							(start 0.1778 0.2794)
							(mid 0.249642 0.249642)
							(end 0.2794 0.1778)
						)
						(arc
							(start 0.2794 -0.1778)
							(mid 0.249642 -0.249642)
							(end 0.1778 -0.2794)
						)
					)
					(width 0)
					(fill yes)
				)
			)
		)
	)
	(footprint ""
		(layer "F.Cu")
		(at 60.9092 -121.3612 -90)
		(property "Reference" "SKT2"
			(at 0 0 270)
			(layer "F.SilkS")
			(hide yes)
			(effects
				(font
					(size 1.27 1.27)
				)
			)
		)
		(property "Value" "SKT-SPI16P-GP-U"
			(at -8.9916 4.641596 270)
			(unlocked yes)
			(layer "F.Fab")
			(hide yes)
			(effects
				(font
					(size 1.016 1.016)
					(thickness 0.1524)
				)
			)
		)
		(property "Device Type" "SKT-SOIC16-153139H258"
			(at -8.9916 3.117596 270)
			(unlocked yes)
			(layer "F.Fab")
			(hide yes)
			(effects
				(font
					(size 1.016 1.016)
					(thickness 0.1524)
				)
			)
		)
		(duplicate_pad_numbers_are_jumpers no)
		(fp_line
			(start -7.8994 6.4008)
			(end 7.8994 6.4008)
			(stroke
				(width 0.1524)
				(type default)
			)
			(layer "F.SilkS")
		)
		(fp_line
			(start 7.8994 6.4008)
			(end 7.8994 -6.4008)
			(stroke
				(width 0.1524)
				(type default)
			)
			(layer "F.SilkS")
		)
		(fp_line
			(start 6.7183 0.0762)
			(end 7.8994 1.2573)
			(stroke
				(width 0.1524)
				(type default)
			)
			(layer "F.SilkS")
		)
		(fp_line
			(start 7.8867 -1.0922)
			(end 6.7183 0.0762)
			(stroke
				(width 0.1524)
				(type default)
			)
			(layer "F.SilkS")
		)
		(fp_line
			(start 7.7216 -6.223)
			(end 7.7216 -3.6576)
			(stroke
				(width 0.508)
				(type default)
			)
			(layer "F.SilkS")
		)
		(fp_line
			(start -7.8994 -6.4008)
			(end -7.8994 6.4008)
			(stroke
				(width 0.1524)
				(type default)
			)
			(layer "F.SilkS")
		)
		(fp_line
			(start 7.8994 -6.4008)
			(end -7.8994 -6.4008)
			(stroke
				(width 0.1524)
				(type default)
			)
			(layer "F.SilkS")
		)
		(fp_poly
			(pts
				(xy -4.699 -3.855466) (xy -4.699 3.855466) (xy 4.699 3.855466) (xy 4.699 -3.855466)
			)
			(stroke
				(width 0)
				(type default)
			)
			(fill yes)
			(layer "F.SilkS")
		)
		(fp_rect
			(start -8.1534 11.6078)
			(end 8.1534 6.4008)
			(stroke
				(width 0)
				(type default)
			)
			(fill no)
			(layer "F.CrtYd")
		)
		(fp_rect
			(start -8.1534 -6.4008)
			(end 8.1534 -12.5222)
			(stroke
				(width 0)
				(type default)
			)
			(fill no)
			(layer "F.CrtYd")
		)
		(fp_poly
			(pts
				(xy -8.1534 6.4008) (xy -8.1534 -6.4008) (xy -6.2484 -6.4008) (xy -6.2484 -2.6416) (xy -7.6454 -2.6416)
				(xy -7.6454 2.6416) (xy -6.2484 2.6416) (xy -6.2484 6.4008)
			)
			(stroke
				(width 0)
				(type default)
			)
			(fill no)
			(layer "F.CrtYd")
		)
		(fp_poly
			(pts
				(xy 6.2484 -6.4008) (xy 8.1534 -6.4008) (xy 8.1534 6.4008) (xy 6.2484 6.4008) (xy 6.2484 2.6416)
				(xy 7.6454 2.6416) (xy 7.6454 -2.6416) (xy 6.2484 -2.6416)
			)
			(stroke
				(width 0)
				(type default)
			)
			(fill no)
			(layer "F.CrtYd")
		)
		(fp_poly
			(pts
				(xy 6.2484 -6.4008) (xy -6.2484 -6.4008) (xy -6.2484 -2.6416) (xy -7.6454 -2.6416) (xy -7.6454 2.6416)
				(xy -6.2484 2.6416) (xy -6.2484 6.4008) (xy 6.2484 6.4008) (xy 6.2484 2.6416) (xy 7.6454 2.6416)
				(xy 7.6454 -2.6416) (xy 6.2484 -2.6416)
			)
			(stroke
				(width 0)
				(type default)
			)
			(fill no)
			(layer "F.CrtYd")
		)
		(fp_rect
			(start -8.1534 11.6078)
			(end 8.1534 -12.5222)
			(stroke
				(width 0)
				(type default)
			)
			(fill no)
			(layer "F.Fab")
		)
		(pad "1" smd rect
			(at 4.445 -4.896866 270)
			(size 0.508 1.6764)
			(layers "F.Cu" "F.Mask" "F.Paste")
			(net "PU_IBMC_BT_HOLD_N")
		)
		(pad "2" smd rect
			(at 3.175 -4.896866 270)
			(size 0.508 1.6764)
			(layers "F.Cu" "F.Mask" "F.Paste")
			(net "P3V3_STBY")
		)
		(pad "3" smd rect
			(at 1.905 -4.896866 270)
			(size 0.508 1.6764)
			(layers "F.Cu" "F.Mask" "F.Paste")
			(net "FLA1_SPI_RST")
		)
		(pad "4" smd rect
			(at 0.635 -4.896866 270)
			(size 0.508 1.6764)
			(layers "F.Cu" "F.Mask" "F.Paste")
			(net "Net_345")
		)
		(pad "5" smd rect
			(at -0.635 -4.896866 270)
			(size 0.508 1.6764)
			(layers "F.Cu" "F.Mask" "F.Paste")
			(net "Net_344")
		)
		(pad "6" smd rect
			(at -1.905 -4.896866 270)
			(size 0.508 1.6764)
			(layers "F.Cu" "F.Mask" "F.Paste")
			(net "Net_343")
		)
		(pad "7" smd rect
			(at -3.175 -4.896866 270)
			(size 0.508 1.6764)
			(layers "F.Cu" "F.Mask" "F.Paste")
			(net "FLA_CS_1_R")
		)
		(pad "8" smd rect
			(at -4.445 -4.896866 270)
			(size 0.508 1.6764)
			(layers "F.Cu" "F.Mask" "F.Paste")
			(net "BMC_SPI_MISO_R")
		)
		(pad "9" smd rect
			(at -4.445 4.896866 270)
			(size 0.508 1.6764)
			(layers "F.Cu" "F.Mask" "F.Paste")
			(net "FLA1_WP_N")
		)
		(pad "10" smd rect
			(at -3.175 4.896866 270)
			(size 0.508 1.6764)
			(layers "F.Cu" "F.Mask" "F.Paste")
			(net "GND")
		)
		(pad "11" smd rect
			(at -1.905 4.896866 270)
			(size 0.508 1.6764)
			(layers "F.Cu" "F.Mask" "F.Paste")
			(net "Net_349")
		)
		(pad "12" smd rect
			(at -0.635 4.896866 270)
			(size 0.508 1.6764)
			(layers "F.Cu" "F.Mask" "F.Paste")
			(net "Net_348")
		)
		(pad "13" smd rect
			(at 0.635 4.896866 270)
			(size 0.508 1.6764)
			(layers "F.Cu" "F.Mask" "F.Paste")
			(net "Net_347")
		)
		(pad "14" smd rect
			(at 1.905 4.896866 270)
			(size 0.508 1.6764)
			(layers "F.Cu" "F.Mask" "F.Paste")
			(net "Net_346")
		)
		(pad "15" smd rect
			(at 3.175 4.896866 270)
			(size 0.508 1.6764)
			(layers "F.Cu" "F.Mask" "F.Paste")
			(net "BMC_SPI_MOSI_R")
		)
		(pad "16" smd rect
			(at 4.445 4.896866 270)
			(size 0.508 1.6764)
			(layers "F.Cu" "F.Mask" "F.Paste")
			(net "BMC_SPI_CLK_R")
		)
	)
	(footprint ""
		(layer "F.Cu")
		(at 175.768 -135.4582 180)
		(property "Reference" "L6"
			(at 0 0 180)
			(layer "F.SilkS")
			(hide yes)
			(effects
				(font
					(size 1.27 1.27)
				)
			)
		)
		(property "Value" "BLM21PG220SN1DGP"
			(at 0.0254 -5.6896 180)
			(unlocked yes)
			(layer "F.Fab")
			(hide yes)
			(effects
				(font
					(size 1.016 1.016)
					(thickness 0.1524)
				)
			)
		)
		(property "Device Type" "L20125H42"
			(at 0.0254 -7.5946 180)
			(unlocked yes)
			(layer "F.Fab")
			(hide yes)
			(effects
				(font
					(size 1.016 1.016)
					(thickness 0.1524)
				)
			)
		)
		(duplicate_pad_numbers_are_jumpers no)
		(fp_line
			(start 0.9144 1.7018)
			(end 0.9144 -1.7018)
			(stroke
				(width 0.1524)
				(type default)
			)
			(layer "F.SilkS")
		)
		(fp_line
			(start 0.9144 -1.7018)
			(end -0.9144 -1.7018)
			(stroke
				(width 0.1524)
				(type default)
			)
			(layer "F.SilkS")
		)
		(fp_line
			(start -0.9144 1.7018)
			(end 0.9144 1.7018)
			(stroke
				(width 0.1524)
				(type default)
			)
			(layer "F.SilkS")
		)
		(fp_line
			(start -0.9144 -1.7018)
			(end -0.9144 1.7018)
			(stroke
				(width 0.1524)
				(type default)
			)
			(layer "F.SilkS")
		)
		(fp_rect
			(start -1.0033 1.778)
			(end 1.0033 -1.778)
			(stroke
				(width 0)
				(type default)
			)
			(fill no)
			(layer "F.CrtYd")
		)
		(fp_poly
			(pts
				(xy -1.0033 -1.778) (xy 1.0033 -1.778) (xy 1.0033 1.778) (xy -1.0033 1.778)
			)
			(stroke
				(width 0)
				(type default)
			)
			(fill no)
			(layer "F.Fab")
		)
		(pad "1" smd rect
			(at 0 -0.9652 180)
			(size 1.397 1.143)
			(layers "F.Cu" "F.Mask" "F.Paste")
			(net "P12V_STBY")
		)
		(pad "2" smd rect
			(at 0 0.9652 180)
			(size 1.397 1.143)
			(layers "F.Cu" "F.Mask" "F.Paste")
			(net "P12V_STBY_VIN_PU1")
		)
	)
	(footprint ""
		(layer "F.Cu")
		(at 169.1894 -165.9128 -90)
		(property "Reference" "C167"
			(at 0 0 270)
			(layer "F.SilkS")
			(hide yes)
			(effects
				(font
					(size 1.27 1.27)
				)
			)
		)
		(property "Value" "ST100U16VDM-3-GP"
			(at 0 -9.6012 270)
			(unlocked yes)
			(layer "F.Fab")
			(hide yes)
			(effects
				(font
					(size 1.016 1.016)
					(thickness 0.1524)
				)
			)
		)
		(property "Device Type" "CT7343H79"
			(at 0 -11.1252 270)
			(unlocked yes)
			(layer "F.Fab")
			(hide yes)
			(effects
				(font
					(size 1.016 1.016)
					(thickness 0.1524)
				)
			)
		)
		(duplicate_pad_numbers_are_jumpers no)
		(fp_line
			(start -2.286 4.8768)
			(end -2.286 2.032)
			(stroke
				(width 0.1524)
				(type default)
			)
			(layer "F.SilkS")
		)
		(fp_line
			(start 2.286 4.8768)
			(end -2.286 4.8768)
			(stroke
				(width 0.1524)
				(type default)
			)
			(layer "F.SilkS")
		)
		(fp_line
			(start 2.286 2.032)
			(end 2.286 4.8768)
			(stroke
				(width 0.1524)
				(type default)
			)
			(layer "F.SilkS")
		)
		(fp_line
			(start 2.286 -2.032)
			(end 2.286 -4.8768)
			(stroke
				(width 0.1524)
				(type default)
			)
			(layer "F.SilkS")
		)
		(fp_line
			(start 2.1082 -4.699)
			(end -2.1082 -4.699)
			(stroke
				(width 0.508)
				(type default)
			)
			(layer "F.SilkS")
		)
		(fp_line
			(start -2.286 -4.8768)
			(end -2.286 -2.032)
			(stroke
				(width 0.1524)
				(type default)
			)
			(layer "F.SilkS")
		)
		(fp_line
			(start 2.286 -4.8768)
			(end -2.286 -4.8768)
			(stroke
				(width 0.1524)
				(type default)
			)
			(layer "F.SilkS")
		)
		(fp_rect
			(start -2.1463 3.6449)
			(end 2.1463 -3.6449)
			(stroke
				(width 0)
				(type default)
			)
			(fill no)
			(layer "F.CrtYd")
		)
		(fp_poly
			(pts
				(xy -2.54 4.953) (xy -2.54 4.2926) (xy -3.81 4.2926) (xy -3.81 -4.2926) (xy -2.54 -4.2926) (xy -2.54 -4.953)
				(xy 2.54 -4.953) (xy 2.54 -4.2926) (xy 3.81 -4.2926) (xy 3.81 -1.6256) (xy 2.1463 -1.6256) (xy 2.1463 -3.6449)
				(xy -2.1463 -3.6449) (xy -2.1463 3.6449) (xy 2.1463 3.6449) (xy 2.1463 -1.6129) (xy 3.81 -1.6129)
				(xy 3.81 4.2926) (xy 2.54 4.2926) (xy 2.54 4.953)
			)
			(stroke
				(width 0)
				(type default)
			)
			(fill no)
			(layer "F.CrtYd")
		)
		(fp_rect
			(start -2.54 4.953)
			(end 2.54 -4.953)
			(stroke
				(width 0)
				(type default)
			)
			(fill no)
			(layer "F.Fab")
		)
		(fp_rect
			(start -3.81 4.2926)
			(end -2.54 -4.2926)
			(stroke
				(width 0)
				(type default)
			)
			(fill no)
			(layer "F.Fab")
		)
		(fp_rect
			(start 2.54 4.2926)
			(end 3.81 -4.2926)
			(stroke
				(width 0)
				(type default)
			)
			(fill no)
			(layer "F.Fab")
		)
		(pad "1" smd rect
			(at 0 -3.1496 270)
			(size 2.413 2.286)
			(layers "F.Cu" "F.Mask" "F.Paste")
			(net "P5V_STBY")
		)
		(pad "2" smd rect
			(at 0 3.1496 270)
			(size 2.413 2.286)
			(layers "F.Cu" "F.Mask" "F.Paste")
			(net "GND")
		)
		(zone
			(layer "F.Cu")
			(hatch none 0.5)
			(connect_pads
				(clearance 0)
			)
			(min_thickness 0.25)
			(keepout
				(tracks allowed)
				(vias not_allowed)
				(pads allowed)
				(copperpour not_allowed)
				(footprints allowed)
			)
			(placement
				(enabled no)
				(sheetname "")
			)
			(fill
				(thermal_gap 0.5)
				(thermal_bridge_width 0.5)
				(island_removal_mode 0)
			)
			(polygon
				(pts
					(xy 164.592 -167.4241) (xy 164.592 -164.4015) (xy 167.4876 -164.4015) (xy 167.8178 -164.4015) (xy 167.8178 -167.4241)
					(xy 167.4876 -167.4241)
				)
			)
		)
		(zone
			(layer "F.Cu")
			(hatch none 0.5)
			(connect_pads
				(clearance 0)
			)
			(min_thickness 0.25)
			(keepout
				(tracks allowed)
				(vias not_allowed)
				(pads allowed)
				(copperpour not_allowed)
				(footprints allowed)
			)
			(placement
				(enabled no)
				(sheetname "")
			)
			(fill
				(thermal_gap 0.5)
				(thermal_bridge_width 0.5)
				(island_removal_mode 0)
			)
			(polygon
				(pts
					(xy 170.8785 -164.4015) (xy 173.7868 -164.4015) (xy 173.7868 -167.4241) (xy 170.8912 -167.4241)
					(xy 170.561 -167.4241) (xy 170.561 -164.4015)
				)
			)
		)
	)
	(footprint ""
		(layer "F.Cu")
		(at 177.34788 -50.22596 90)
		(property "Reference" "R662"
			(at 0 0 90)
			(layer "F.SilkS")
			(hide yes)
			(effects
				(font
					(size 1.27 1.27)
				)
			)
		)
		(property "Value" "10KR2F-2-GP"
			(at 0.064008 -3.993896 90)
			(unlocked yes)
			(layer "F.Fab")
			(hide yes)
			(effects
				(font
					(size 1.016 1.016)
					(thickness 0.1524)
				)
			)
		)
		(property "Device Type" "R402H16"
			(at 0.064008 -5.517896 90)
			(unlocked yes)
			(layer "F.Fab")
			(hide yes)
			(effects
				(font
					(size 1.016 1.016)
					(thickness 0.1524)
				)
			)
		)
		(duplicate_pad_numbers_are_jumpers no)
		(fp_line
			(start 0.508 -0.9398)
			(end -0.508 -0.9398)
			(stroke
				(width 0.1524)
				(type default)
			)
			(layer "F.SilkS")
		)
		(fp_line
			(start -0.508 -0.9398)
			(end -0.508 0.9398)
			(stroke
				(width 0.1524)
				(type default)
			)
			(layer "F.SilkS")
		)
		(fp_rect
			(start -0.508 0.9398)
			(end 0.508 -0.9398)
			(stroke
				(width 0)
				(type default)
			)
			(fill no)
			(layer "F.CrtYd")
		)
		(fp_rect
			(start -0.508 0.9398)
			(end 0.508 -0.9398)
			(stroke
				(width 0)
				(type default)
			)
			(fill no)
			(layer "F.Fab")
		)
		(pad "1" smd custom
			(at 0 -0.4445 90)
			(size 0.1397 0.1397)
			(layers "F.Cu" "F.Mask" "F.Paste")
			(net "P1V8")
			(options
				(clearance outline)
				(anchor circle)
			)
			(primitives
				(gr_poly
					(pts
						(arc
							(start -0.1778 -0.2794)
							(mid -0.249642 -0.249642)
							(end -0.2794 -0.1778)
						)
						(arc
							(start -0.2794 0.1778)
							(mid -0.249642 0.249642)
							(end -0.1778 0.2794)
						)
						(arc
							(start 0.1778 0.2794)
							(mid 0.249642 0.249642)
							(end 0.2794 0.1778)
						)
						(arc
							(start 0.2794 -0.1778)
							(mid 0.249642 -0.249642)
							(end 0.1778 -0.2794)
						)
					)
					(width 0)
					(fill yes)
				)
			)
		)
		(pad "2" smd custom
			(at 0 0.4445 90)
			(size 0.1397 0.1397)
			(layers "F.Cu" "F.Mask" "F.Paste")
			(net "XM_ADDR_7")
			(options
				(clearance outline)
				(anchor circle)
			)
			(primitives
				(gr_poly
					(pts
						(arc
							(start -0.1778 -0.2794)
							(mid -0.249642 -0.249642)
							(end -0.2794 -0.1778)
						)
						(arc
							(start -0.2794 0.1778)
							(mid -0.249642 0.249642)
							(end -0.1778 0.2794)
						)
						(arc
							(start 0.1778 0.2794)
							(mid 0.249642 0.249642)
							(end 0.2794 0.1778)
						)
						(arc
							(start 0.2794 -0.1778)
							(mid 0.249642 -0.249642)
							(end 0.1778 -0.2794)
						)
					)
					(width 0)
					(fill yes)
				)
			)
		)
	)
	(footprint ""
		(layer "F.Cu")
		(at 158.302706 -86.151466 180)
		(property "Reference" "R693"
			(at 0 0 180)
			(layer "F.SilkS")
			(hide yes)
			(effects
				(font
					(size 1.27 1.27)
				)
			)
		)
		(property "Value" "0R2J-2-GP"
			(at 0.064008 -3.993896 180)
			(unlocked yes)
			(layer "F.Fab")
			(hide yes)
			(effects
				(font
					(size 1.016 1.016)
					(thickness 0.1524)
				)
			)
		)
		(property "Device Type" "R402H16"
			(at 0.064008 -5.517896 180)
			(unlocked yes)
			(layer "F.Fab")
			(hide yes)
			(effects
				(font
					(size 1.016 1.016)
					(thickness 0.1524)
				)
			)
		)
		(duplicate_pad_numbers_are_jumpers no)
		(fp_line
			(start 0.508 -0.9398)
			(end -0.508 -0.9398)
			(stroke
				(width 0.1524)
				(type default)
			)
			(layer "F.SilkS")
		)
		(fp_line
			(start -0.508 -0.9398)
			(end -0.508 0.9398)
			(stroke
				(width 0.1524)
				(type default)
			)
			(layer "F.SilkS")
		)
		(fp_rect
			(start -0.508 0.9398)
			(end 0.508 -0.9398)
			(stroke
				(width 0)
				(type default)
			)
			(fill no)
			(layer "F.CrtYd")
		)
		(fp_rect
			(start -0.508 0.9398)
			(end 0.508 -0.9398)
			(stroke
				(width 0)
				(type default)
			)
			(fill no)
			(layer "F.Fab")
		)
		(pad "1" smd custom
			(at 0 -0.4445 180)
			(size 0.1397 0.1397)
			(layers "F.Cu" "F.Mask" "F.Paste")
			(net "IOC_UART_0_RX_R")
			(options
				(clearance outline)
				(anchor circle)
			)
			(primitives
				(gr_poly
					(pts
						(arc
							(start -0.1778 -0.2794)
							(mid -0.249642 -0.249642)
							(end -0.2794 -0.1778)
						)
						(arc
							(start -0.2794 0.1778)
							(mid -0.249642 0.249642)
							(end -0.1778 0.2794)
						)
						(arc
							(start 0.1778 0.2794)
							(mid 0.249642 0.249642)
							(end 0.2794 0.1778)
						)
						(arc
							(start 0.2794 -0.1778)
							(mid 0.249642 -0.249642)
							(end 0.1778 -0.2794)
						)
					)
					(width 0)
					(fill yes)
				)
			)
		)
		(pad "2" smd custom
			(at 0 0.4445 180)
			(size 0.1397 0.1397)
			(layers "F.Cu" "F.Mask" "F.Paste")
			(net "IOC_UART_0_RX")
			(options
				(clearance outline)
				(anchor circle)
			)
			(primitives
				(gr_poly
					(pts
						(arc
							(start -0.1778 -0.2794)
							(mid -0.249642 -0.249642)
							(end -0.2794 -0.1778)
						)
						(arc
							(start -0.2794 0.1778)
							(mid -0.249642 0.249642)
							(end -0.1778 0.2794)
						)
						(arc
							(start 0.1778 0.2794)
							(mid 0.249642 0.249642)
							(end 0.2794 0.1778)
						)
						(arc
							(start 0.2794 -0.1778)
							(mid 0.249642 -0.249642)
							(end 0.1778 -0.2794)
						)
					)
					(width 0)
					(fill yes)
				)
			)
		)
	)
	(footprint ""
		(layer "F.Cu")
		(at 173.568868 -62.114938 -90)
		(property "Reference" "R572"
			(at 0 0 270)
			(layer "F.SilkS")
			(hide yes)
			(effects
				(font
					(size 1.27 1.27)
				)
			)
		)
		(property "Value" "10KR2F-2-GP"
			(at 0.064008 -3.993896 270)
			(unlocked yes)
			(layer "F.Fab")
			(hide yes)
			(effects
				(font
					(size 1.016 1.016)
					(thickness 0.1524)
				)
			)
		)
		(property "Device Type" "R402H16"
			(at 0.064008 -5.517896 270)
			(unlocked yes)
			(layer "F.Fab")
			(hide yes)
			(effects
				(font
					(size 1.016 1.016)
					(thickness 0.1524)
				)
			)
		)
		(duplicate_pad_numbers_are_jumpers no)
		(fp_line
			(start -0.508 -0.9398)
			(end -0.508 0.9398)
			(stroke
				(width 0.1524)
				(type default)
			)
			(layer "F.SilkS")
		)
		(fp_line
			(start 0.508 -0.9398)
			(end -0.508 -0.9398)
			(stroke
				(width 0.1524)
				(type default)
			)
			(layer "F.SilkS")
		)
		(fp_rect
			(start -0.508 0.9398)
			(end 0.508 -0.9398)
			(stroke
				(width 0)
				(type default)
			)
			(fill no)
			(layer "F.CrtYd")
		)
		(fp_rect
			(start -0.508 0.9398)
			(end 0.508 -0.9398)
			(stroke
				(width 0)
				(type default)
			)
			(fill no)
			(layer "F.Fab")
		)
		(pad "1" smd custom
			(at 0 -0.4445 270)
			(size 0.1397 0.1397)
			(layers "F.Cu" "F.Mask" "F.Paste")
			(net "IOC_CLK_SEL0")
			(options
				(clearance outline)
				(anchor circle)
			)
			(primitives
				(gr_poly
					(pts
						(arc
							(start -0.1778 -0.2794)
							(mid -0.249642 -0.249642)
							(end -0.2794 -0.1778)
						)
						(arc
							(start -0.2794 0.1778)
							(mid -0.249642 0.249642)
							(end -0.1778 0.2794)
						)
						(arc
							(start 0.1778 0.2794)
							(mid 0.249642 0.249642)
							(end 0.2794 0.1778)
						)
						(arc
							(start 0.2794 -0.1778)
							(mid 0.249642 -0.249642)
							(end 0.1778 -0.2794)
						)
					)
					(width 0)
					(fill yes)
				)
			)
		)
		(pad "2" smd custom
			(at 0 0.4445 270)
			(size 0.1397 0.1397)
			(layers "F.Cu" "F.Mask" "F.Paste")
			(net "P1V8")
			(options
				(clearance outline)
				(anchor circle)
			)
			(primitives
				(gr_poly
					(pts
						(arc
							(start -0.1778 -0.2794)
							(mid -0.249642 -0.249642)
							(end -0.2794 -0.1778)
						)
						(arc
							(start -0.2794 0.1778)
							(mid -0.249642 0.249642)
							(end -0.1778 0.2794)
						)
						(arc
							(start 0.1778 0.2794)
							(mid 0.249642 0.249642)
							(end 0.2794 0.1778)
						)
						(arc
							(start 0.2794 -0.1778)
							(mid 0.249642 -0.249642)
							(end 0.1778 -0.2794)
						)
					)
					(width 0)
					(fill yes)
				)
			)
		)
	)
	(footprint ""
		(layer "F.Cu")
		(at 179.167536 -118.79072)
		(property "Reference" "U95"
			(at 0 0 0)
			(layer "F.SilkS")
			(hide yes)
			(effects
				(font
					(size 1.27 1.27)
				)
			)
		)
		(property "Value" "SN74LVC1G07DCKR-GP"
			(at -2.3368 -8.6868 0)
			(unlocked yes)
			(layer "F.Fab")
			(hide yes)
			(effects
				(font
					(size 1.016 1.016)
					(thickness 0.1524)
				)
			)
		)
		(property "Device Type" "SC70-5H44"
			(at -2.3114 -10.414 0)
			(unlocked yes)
			(layer "F.Fab")
			(hide yes)
			(effects
				(font
					(size 1.016 1.016)
					(thickness 0.1524)
				)
			)
		)
		(duplicate_pad_numbers_are_jumpers no)
		(fp_line
			(start -1.27 -1.7018)
			(end 1.27 -1.7018)
			(stroke
				(width 0.1524)
				(type default)
			)
			(layer "F.SilkS")
		)
		(fp_line
			(start -1.27 1.7018)
			(end -1.27 -1.7018)
			(stroke
				(width 0.1524)
				(type default)
			)
			(layer "F.SilkS")
		)
		(fp_line
			(start 0.6604 -1.8034)
			(end 1.3843 -1.8034)
			(stroke
				(width 0.3302)
				(type default)
			)
			(layer "F.SilkS")
		)
		(fp_line
			(start 1.27 -1.7018)
			(end 1.27 1.7018)
			(stroke
				(width 0.1524)
				(type default)
			)
			(layer "F.SilkS")
		)
		(fp_line
			(start 1.27 1.7018)
			(end -1.27 1.7018)
			(stroke
				(width 0.1524)
				(type default)
			)
			(layer "F.SilkS")
		)
		(fp_line
			(start 1.3843 -1.8034)
			(end 1.3843 -1.1176)
			(stroke
				(width 0.3302)
				(type default)
			)
			(layer "F.SilkS")
		)
		(fp_rect
			(start -1.524 1.9558)
			(end 1.524 -1.9558)
			(stroke
				(width 0)
				(type default)
			)
			(fill no)
			(layer "F.CrtYd")
		)
		(fp_poly
			(pts
				(xy -1.524 -1.9558) (xy 1.524 -1.9558) (xy 1.524 1.9558) (xy -1.524 1.9558)
			)
			(stroke
				(width 0)
				(type default)
			)
			(fill no)
			(layer "F.Fab")
		)
		(pad "1" smd rect
			(at 0.65024 -0.8255)
			(size 0.4064 1.2192)
			(layers "F.Cu" "F.Mask" "F.Paste")
			(net "Net_311")
		)
		(pad "2" smd rect
			(at 0 -0.8255)
			(size 0.4064 1.2192)
			(layers "F.Cu" "F.Mask" "F.Paste")
			(net "IOM_FULL_PGOOD")
		)
		(pad "3" smd rect
			(at -0.65024 -0.8255)
			(size 0.4064 1.2192)
			(layers "F.Cu" "F.Mask" "F.Paste")
			(net "GND")
		)
		(pad "4" smd rect
			(at -0.65024 0.8255)
			(size 0.4064 1.2192)
			(layers "F.Cu" "F.Mask" "F.Paste")
			(net "PWRGD_P0V975")
		)
		(pad "5" smd rect
			(at 0.65024 0.8255)
			(size 0.4064 1.2192)
			(layers "F.Cu" "F.Mask" "F.Paste")
			(net "P3V3_STBY")
		)
	)
	(footprint ""
		(layer "F.Cu")
		(at 60.5028 -133.2484)
		(property "Reference" "TP193"
			(at 0 0 0)
			(layer "F.SilkS")
			(hide yes)
			(effects
				(font
					(size 1.27 1.27)
				)
			)
		)
		(property "Value" "TPAD28-2-GP"
			(at -0.0127 -1.6637 0)
			(unlocked yes)
			(layer "F.Fab")
			(hide yes)
			(effects
				(font
					(size 1.016 1.016)
					(thickness 0.1524)
				)
			)
		)
		(property "Device Type" "TPAD28"
			(at -0.0127 -3.1877 0)
			(unlocked yes)
			(layer "F.Fab")
			(hide yes)
			(effects
				(font
					(size 1.016 1.016)
					(thickness 0.1524)
				)
			)
		)
		(duplicate_pad_numbers_are_jumpers no)
		(fp_poly
			(pts
				(arc
					(start 0.3556 0)
					(mid -0.3556 0)
					(end 0.3556 0)
				)
			)
			(stroke
				(width 0)
				(type default)
			)
			(fill no)
			(layer "F.CrtYd")
		)
		(fp_poly
			(pts
				(arc
					(start 0.6096 0)
					(mid -0.6096 0)
					(end 0.6096 0)
				)
			)
			(stroke
				(width 0)
				(type default)
			)
			(fill no)
			(layer "F.Fab")
		)
		(pad "1" smd circle
			(at 0 0)
			(size 0.7112 0.7112)
			(layers "F.Cu" "F.Mask" "F.Paste")
			(net "TP_BMC_EXT2_LED_B")
		)
	)
	(footprint ""
		(layer "F.Cu")
		(at 23.0886 -171.2976 90)
		(property "Reference" "C232"
			(at 0 0 90)
			(layer "F.SilkS")
			(hide yes)
			(effects
				(font
					(size 1.27 1.27)
				)
			)
		)
		(property "Value" "SC10U6D3V5KX-4GP"
			(at -0.0762 -6.1214 90)
			(unlocked yes)
			(layer "F.Fab")
			(hide yes)
			(effects
				(font
					(size 1.016 1.016)
					(thickness 0.1524)
				)
			)
		)
		(property "Device Type" "C805H58"
			(at -0.0762 -8.1534 90)
			(unlocked yes)
			(layer "F.Fab")
			(hide yes)
			(effects
				(font
					(size 1.016 1.016)
					(thickness 0.1524)
				)
			)
		)
		(duplicate_pad_numbers_are_jumpers no)
		(fp_line
			(start 0.635 0)
			(end -0.635 0)
			(stroke
				(width 0.508)
				(type default)
			)
			(layer "F.SilkS")
		)
		(fp_rect
			(start -0.9652 1.778)
			(end 0.9652 -1.778)
			(stroke
				(width 0)
				(type default)
			)
			(fill no)
			(layer "F.CrtYd")
		)
		(fp_poly
			(pts
				(xy -0.9652 -1.778) (xy 0.9652 -1.778) (xy 0.9652 1.778) (xy -0.9652 1.778)
			)
			(stroke
				(width 0)
				(type default)
			)
			(fill no)
			(layer "F.Fab")
		)
		(pad "1" smd rect
			(at 0 -0.9652 90)
			(size 1.397 1.143)
			(layers "F.Cu" "F.Mask" "F.Paste")
			(net "P1V8_STBY")
		)
		(pad "2" smd rect
			(at 0 0.9652 90)
			(size 1.397 1.143)
			(layers "F.Cu" "F.Mask" "F.Paste")
			(net "GND")
		)
	)
	(footprint ""
		(layer "F.Cu")
		(at 197.358 -124.6632 180)
		(property "Reference" "R555"
			(at 0 0 180)
			(layer "F.SilkS")
			(hide yes)
			(effects
				(font
					(size 1.27 1.27)
				)
			)
		)
		(property "Value" "221R2F-2-GP"
			(at 0.064008 -3.993896 180)
			(unlocked yes)
			(layer "F.Fab")
			(hide yes)
			(effects
				(font
					(size 1.016 1.016)
					(thickness 0.1524)
				)
			)
		)
		(property "Device Type" "R402H16"
			(at 0.064008 -5.517896 180)
			(unlocked yes)
			(layer "F.Fab")
			(hide yes)
			(effects
				(font
					(size 1.016 1.016)
					(thickness 0.1524)
				)
			)
		)
		(duplicate_pad_numbers_are_jumpers no)
		(fp_line
			(start 0.508 -0.9398)
			(end -0.508 -0.9398)
			(stroke
				(width 0.1524)
				(type default)
			)
			(layer "F.SilkS")
		)
		(fp_line
			(start -0.508 -0.9398)
			(end -0.508 0.9398)
			(stroke
				(width 0.1524)
				(type default)
			)
			(layer "F.SilkS")
		)
		(fp_rect
			(start -0.508 0.9398)
			(end 0.508 -0.9398)
			(stroke
				(width 0)
				(type default)
			)
			(fill no)
			(layer "F.CrtYd")
		)
		(fp_rect
			(start -0.508 0.9398)
			(end 0.508 -0.9398)
			(stroke
				(width 0)
				(type default)
			)
			(fill no)
			(layer "F.Fab")
		)
		(pad "1" smd custom
			(at 0 -0.4445 180)
			(size 0.1397 0.1397)
			(layers "F.Cu" "F.Mask" "F.Paste")
			(net "VT235_VFB")
			(options
				(clearance outline)
				(anchor circle)
			)
			(primitives
				(gr_poly
					(pts
						(arc
							(start -0.1778 -0.2794)
							(mid -0.249642 -0.249642)
							(end -0.2794 -0.1778)
						)
						(arc
							(start -0.2794 0.1778)
							(mid -0.249642 0.249642)
							(end -0.1778 0.2794)
						)
						(arc
							(start 0.1778 0.2794)
							(mid 0.249642 0.249642)
							(end 0.2794 0.1778)
						)
						(arc
							(start 0.2794 -0.1778)
							(mid 0.249642 -0.249642)
							(end 0.1778 -0.2794)
						)
					)
					(width 0)
					(fill yes)
				)
			)
		)
		(pad "2" smd custom
			(at 0 0.4445 180)
			(size 0.1397 0.1397)
			(layers "F.Cu" "F.Mask" "F.Paste")
			(net "P0V975_SEN")
			(options
				(clearance outline)
				(anchor circle)
			)
			(primitives
				(gr_poly
					(pts
						(arc
							(start -0.1778 -0.2794)
							(mid -0.249642 -0.249642)
							(end -0.2794 -0.1778)
						)
						(arc
							(start -0.2794 0.1778)
							(mid -0.249642 0.249642)
							(end -0.1778 0.2794)
						)
						(arc
							(start 0.1778 0.2794)
							(mid 0.249642 0.249642)
							(end 0.2794 0.1778)
						)
						(arc
							(start 0.2794 -0.1778)
							(mid 0.249642 -0.249642)
							(end 0.1778 -0.2794)
						)
					)
					(width 0)
					(fill yes)
				)
			)
		)
	)
	(footprint ""
		(layer "F.Cu")
		(at 48.703484 -166.456868 180)
		(property "Reference" "R779"
			(at 0 0 180)
			(layer "F.SilkS")
			(hide yes)
			(effects
				(font
					(size 1.27 1.27)
				)
			)
		)
		(property "Value" "1KR2F-3-GP"
			(at 0.064008 -3.993896 180)
			(unlocked yes)
			(layer "F.Fab")
			(hide yes)
			(effects
				(font
					(size 1.016 1.016)
					(thickness 0.1524)
				)
			)
		)
		(property "Device Type" "R402H16"
			(at 0.064008 -5.517896 180)
			(unlocked yes)
			(layer "F.Fab")
			(hide yes)
			(effects
				(font
					(size 1.016 1.016)
					(thickness 0.1524)
				)
			)
		)
		(duplicate_pad_numbers_are_jumpers no)
		(fp_line
			(start 0.508 -0.9398)
			(end -0.508 -0.9398)
			(stroke
				(width 0.1524)
				(type default)
			)
			(layer "F.SilkS")
		)
		(fp_line
			(start -0.508 -0.9398)
			(end -0.508 0.9398)
			(stroke
				(width 0.1524)
				(type default)
			)
			(layer "F.SilkS")
		)
		(fp_rect
			(start -0.508 0.9398)
			(end 0.508 -0.9398)
			(stroke
				(width 0)
				(type default)
			)
			(fill no)
			(layer "F.CrtYd")
		)
		(fp_rect
			(start -0.508 0.9398)
			(end 0.508 -0.9398)
			(stroke
				(width 0)
				(type default)
			)
			(fill no)
			(layer "F.Fab")
		)
		(pad "1" smd custom
			(at 0 -0.4445 180)
			(size 0.1397 0.1397)
			(layers "F.Cu" "F.Mask" "F.Paste")
			(net "ADC_P2V5_STBY")
			(options
				(clearance outline)
				(anchor circle)
			)
			(primitives
				(gr_poly
					(pts
						(arc
							(start -0.1778 -0.2794)
							(mid -0.249642 -0.249642)
							(end -0.2794 -0.1778)
						)
						(arc
							(start -0.2794 0.1778)
							(mid -0.249642 0.249642)
							(end -0.1778 0.2794)
						)
						(arc
							(start 0.1778 0.2794)
							(mid 0.249642 0.249642)
							(end 0.2794 0.1778)
						)
						(arc
							(start 0.2794 -0.1778)
							(mid 0.249642 -0.249642)
							(end 0.1778 -0.2794)
						)
					)
					(width 0)
					(fill yes)
				)
			)
		)
		(pad "2" smd custom
			(at 0 0.4445 180)
			(size 0.1397 0.1397)
			(layers "F.Cu" "F.Mask" "F.Paste")
			(net "GND")
			(options
				(clearance outline)
				(anchor circle)
			)
			(primitives
				(gr_poly
					(pts
						(arc
							(start -0.1778 -0.2794)
							(mid -0.249642 -0.249642)
							(end -0.2794 -0.1778)
						)
						(arc
							(start -0.2794 0.1778)
							(mid -0.249642 0.249642)
							(end -0.1778 0.2794)
						)
						(arc
							(start 0.1778 0.2794)
							(mid 0.249642 0.249642)
							(end 0.2794 0.1778)
						)
						(arc
							(start 0.2794 -0.1778)
							(mid 0.249642 -0.249642)
							(end 0.1778 -0.2794)
						)
					)
					(width 0)
					(fill yes)
				)
			)
		)
	)
	(footprint ""
		(layer "F.Cu")
		(at 124.841 -6.604 -90)
		(property "Reference" "R711"
			(at 0 0 270)
			(layer "F.SilkS")
			(hide yes)
			(effects
				(font
					(size 1.27 1.27)
				)
			)
		)
		(property "Value" "0R2J-2-GP"
			(at 0.064008 -3.993896 270)
			(unlocked yes)
			(layer "F.Fab")
			(hide yes)
			(effects
				(font
					(size 1.016 1.016)
					(thickness 0.1524)
				)
			)
		)
		(property "Device Type" "R402H16"
			(at 0.064008 -5.517896 270)
			(unlocked yes)
			(layer "F.Fab")
			(hide yes)
			(effects
				(font
					(size 1.016 1.016)
					(thickness 0.1524)
				)
			)
		)
		(duplicate_pad_numbers_are_jumpers no)
		(fp_line
			(start -0.508 -0.9398)
			(end -0.508 0.9398)
			(stroke
				(width 0.1524)
				(type default)
			)
			(layer "F.SilkS")
		)
		(fp_line
			(start 0.508 -0.9398)
			(end -0.508 -0.9398)
			(stroke
				(width 0.1524)
				(type default)
			)
			(layer "F.SilkS")
		)
		(fp_rect
			(start -0.508 0.9398)
			(end 0.508 -0.9398)
			(stroke
				(width 0)
				(type default)
			)
			(fill no)
			(layer "F.CrtYd")
		)
		(fp_rect
			(start -0.508 0.9398)
			(end 0.508 -0.9398)
			(stroke
				(width 0)
				(type default)
			)
			(fill no)
			(layer "F.Fab")
		)
		(pad "1" smd custom
			(at 0 -0.4445 270)
			(size 0.1397 0.1397)
			(layers "F.Cu" "F.Mask" "F.Paste")
			(net "I2C_IOM_SCL")
			(options
				(clearance outline)
				(anchor circle)
			)
			(primitives
				(gr_poly
					(pts
						(arc
							(start -0.1778 -0.2794)
							(mid -0.249642 -0.249642)
							(end -0.2794 -0.1778)
						)
						(arc
							(start -0.2794 0.1778)
							(mid -0.249642 0.249642)
							(end -0.1778 0.2794)
						)
						(arc
							(start 0.1778 0.2794)
							(mid 0.249642 0.249642)
							(end 0.2794 0.1778)
						)
						(arc
							(start 0.2794 -0.1778)
							(mid 0.249642 -0.249642)
							(end 0.1778 -0.2794)
						)
					)
					(width 0)
					(fill yes)
				)
			)
		)
		(pad "2" smd custom
			(at 0 0.4445 270)
			(size 0.1397 0.1397)
			(layers "F.Cu" "F.Mask" "F.Paste")
			(net "HSW_SCL")
			(options
				(clearance outline)
				(anchor circle)
			)
			(primitives
				(gr_poly
					(pts
						(arc
							(start -0.1778 -0.2794)
							(mid -0.249642 -0.249642)
							(end -0.2794 -0.1778)
						)
						(arc
							(start -0.2794 0.1778)
							(mid -0.249642 0.249642)
							(end -0.1778 0.2794)
						)
						(arc
							(start 0.1778 0.2794)
							(mid 0.249642 0.249642)
							(end 0.2794 0.1778)
						)
						(arc
							(start 0.2794 -0.1778)
							(mid 0.249642 -0.249642)
							(end 0.1778 -0.2794)
						)
					)
					(width 0)
					(fill yes)
				)
			)
		)
	)
	(footprint ""
		(layer "F.Cu")
		(at 17.99971 -119.99976)
		(property "Reference" ""
			(at 0 0 0)
			(layer "F.SilkS")
			(hide yes)
			(effects
				(font
					(size 1.27 1.27)
				)
			)
		)
		(property "Value" "*"
			(at -6.38175 0.19685 0)
			(unlocked yes)
			(layer "F.Fab")
			(hide yes)
			(effects
				(font
					(size 1.016 1.016)
					(thickness 0.1524)
				)
			)
		)
		(duplicate_pad_numbers_are_jumpers no)
		(fp_poly
			(pts
				(arc
					(start 5.0673 0)
					(mid -5.0673 0)
					(end 5.0673 0)
				)
			)
			(stroke
				(width 0)
				(type default)
			)
			(fill no)
			(layer "B.CrtYd")
		)
		(fp_poly
			(pts
				(arc
					(start 5.0673 0)
					(mid -5.0673 0)
					(end 5.0673 0)
				)
			)
			(stroke
				(width 0)
				(type default)
			)
			(fill no)
			(layer "F.CrtYd")
		)
		(fp_poly
			(pts
				(arc
					(start 5.0673 0)
					(mid -5.0673 0)
					(end 5.0673 0)
				)
			)
			(stroke
				(width 0)
				(type default)
			)
			(fill no)
			(layer "B.Fab")
		)
		(fp_poly
			(pts
				(arc
					(start 5.0673 0)
					(mid -5.0673 0)
					(end 5.0673 0)
				)
			)
			(stroke
				(width 0)
				(type default)
			)
			(fill no)
			(layer "F.Fab")
		)
		(pad "1" thru_hole circle
			(at 0 0)
			(size 9.525 9.525)
			(drill 3.5052)
			(layers "*.Cu" "*.Mask")
			(remove_unused_layers no)
			(net "Net_7")
			(clearance -2.5019)
			(thermal_gap 0.3048)
			(padstack
				(mode front_inner_back)
				(layer "Inner"
					(shape circle)
					(size 3.9116 3.9116)
					(clearance 0.3048)
				)
				(layer "B.Cu"
					(shape circle)
					(size 9.525 9.525)
					(clearance -2.5019)
				)
			)
		)
	)
	(footprint ""
		(layer "F.Cu")
		(at 208.055972 -72.7964 90)
		(property "Reference" "C312"
			(at 0 0 90)
			(layer "F.SilkS")
			(hide yes)
			(effects
				(font
					(size 1.27 1.27)
				)
			)
		)
		(property "Value" "SCD01U16V1KX-GP"
			(at -2.8321 -1.7399 90)
			(unlocked yes)
			(layer "F.Fab")
			(hide yes)
			(effects
				(font
					(size 1.016 1.016)
					(thickness 0.1524)
				)
			)
		)
		(property "Device Type" "C0201H13"
			(at -2.8321 -3.2639 90)
			(unlocked yes)
			(layer "F.Fab")
			(hide yes)
			(effects
				(font
					(size 1.016 1.016)
					(thickness 0.1524)
				)
			)
		)
		(duplicate_pad_numbers_are_jumpers no)
		(fp_rect
			(start -0.2794 0.6477)
			(end 0.2794 -0.6477)
			(stroke
				(width 0)
				(type default)
			)
			(fill no)
			(layer "F.CrtYd")
		)
		(fp_rect
			(start -0.2794 0.6477)
			(end 0.2794 -0.6477)
			(stroke
				(width 0)
				(type default)
			)
			(fill no)
			(layer "F.Fab")
		)
		(pad "1" smd custom
			(at 0 -0.2794 90)
			(size 0.0762 0.0762)
			(layers "F.Cu" "F.Mask" "F.Paste")
			(net "PHY_IOC_TO_CON_A_2_DN_C")
			(options
				(clearance outline)
				(anchor circle)
			)
			(primitives
				(gr_poly
					(pts
						(arc
							(start 0.1524 -0.127)
							(mid 0.137521 -0.162921)
							(end 0.1016 -0.1778)
						)
						(arc
							(start -0.1016 -0.1778)
							(mid -0.137521 -0.162921)
							(end -0.1524 -0.127)
						)
						(arc
							(start -0.1524 0.127)
							(mid -0.137521 0.162921)
							(end -0.1016 0.1778)
						)
						(arc
							(start 0.1016 0.1778)
							(mid 0.137521 0.162921)
							(end 0.1524 0.127)
						)
					)
					(width 0)
					(fill yes)
				)
			)
		)
		(pad "2" smd custom
			(at 0 0.2794 90)
			(size 0.0762 0.0762)
			(layers "F.Cu" "F.Mask" "F.Paste")
			(net "PHY_IOC_TO_CON_A_2_DN")
			(options
				(clearance outline)
				(anchor circle)
			)
			(primitives
				(gr_poly
					(pts
						(arc
							(start 0.1524 -0.127)
							(mid 0.137521 -0.162921)
							(end 0.1016 -0.1778)
						)
						(arc
							(start -0.1016 -0.1778)
							(mid -0.137521 -0.162921)
							(end -0.1524 -0.127)
						)
						(arc
							(start -0.1524 0.127)
							(mid -0.137521 0.162921)
							(end -0.1016 0.1778)
						)
						(arc
							(start 0.1016 0.1778)
							(mid 0.137521 0.162921)
							(end 0.1524 0.127)
						)
					)
					(width 0)
					(fill yes)
				)
			)
		)
	)
	(footprint ""
		(layer "F.Cu")
		(at 197.0532 -16.764 90)
		(property "Reference" "C516"
			(at 0 0 90)
			(layer "F.SilkS")
			(hide yes)
			(effects
				(font
					(size 1.27 1.27)
				)
			)
		)
		(property "Value" "SCD1U16V2KX-3GP"
			(at 1.1811 -2.7051 90)
			(unlocked yes)
			(layer "F.Fab")
			(hide yes)
			(effects
				(font
					(size 1.016 1.016)
					(thickness 0.1524)
				)
			)
		)
		(property "Device Type" "C402H22"
			(at 1.1811 -4.2291 90)
			(unlocked yes)
			(layer "F.Fab")
			(hide yes)
			(effects
				(font
					(size 1.016 1.016)
					(thickness 0.1524)
				)
			)
		)
		(duplicate_pad_numbers_are_jumpers no)
		(fp_rect
			(start -0.4318 0.9525)
			(end 0.4318 -0.9525)
			(stroke
				(width 0)
				(type default)
			)
			(fill no)
			(layer "F.CrtYd")
		)
		(fp_rect
			(start -0.4318 0.9525)
			(end 0.4318 -0.9525)
			(stroke
				(width 0)
				(type default)
			)
			(fill no)
			(layer "F.Fab")
		)
		(pad "1" smd custom
			(at 0 -0.4445 90)
			(size 0.1524 0.1524)
			(layers "F.Cu" "F.Mask" "F.Paste")
			(net "P3V3_STBY")
			(options
				(clearance outline)
				(anchor circle)
			)
			(primitives
				(gr_poly
					(pts
						(arc
							(start 0.3048 -0.2032)
							(mid 0.275042 -0.275042)
							(end 0.2032 -0.3048)
						)
						(arc
							(start -0.2032 -0.3048)
							(mid -0.275042 -0.275042)
							(end -0.3048 -0.2032)
						)
						(arc
							(start -0.3048 0.2032)
							(mid -0.275042 0.275042)
							(end -0.2032 0.3048)
						)
						(arc
							(start 0.2032 0.3048)
							(mid 0.275042 0.275042)
							(end 0.3048 0.2032)
						)
					)
					(width 0)
					(fill yes)
				)
			)
		)
		(pad "2" smd custom
			(at 0 0.4445 90)
			(size 0.1524 0.1524)
			(layers "F.Cu" "F.Mask" "F.Paste")
			(net "GND")
			(options
				(clearance outline)
				(anchor circle)
			)
			(primitives
				(gr_poly
					(pts
						(arc
							(start 0.3048 -0.2032)
							(mid 0.275042 -0.275042)
							(end 0.2032 -0.3048)
						)
						(arc
							(start -0.2032 -0.3048)
							(mid -0.275042 -0.275042)
							(end -0.3048 -0.2032)
						)
						(arc
							(start -0.3048 0.2032)
							(mid -0.275042 0.275042)
							(end -0.2032 0.3048)
						)
						(arc
							(start 0.2032 0.3048)
							(mid 0.275042 0.275042)
							(end 0.3048 0.2032)
						)
					)
					(width 0)
					(fill yes)
				)
			)
		)
	)
	(footprint ""
		(layer "F.Cu")
		(at 75.81138 -186.683396 180)
		(property "Reference" "C199"
			(at 0 0 180)
			(layer "F.SilkS")
			(hide yes)
			(effects
				(font
					(size 1.27 1.27)
				)
			)
		)
		(property "Value" "SC10U6D3V5KX-4GP"
			(at -0.0762 -6.1214 180)
			(unlocked yes)
			(layer "F.Fab")
			(hide yes)
			(effects
				(font
					(size 1.016 1.016)
					(thickness 0.1524)
				)
			)
		)
		(property "Device Type" "C805H58"
			(at -0.0762 -8.1534 180)
			(unlocked yes)
			(layer "F.Fab")
			(hide yes)
			(effects
				(font
					(size 1.016 1.016)
					(thickness 0.1524)
				)
			)
		)
		(duplicate_pad_numbers_are_jumpers no)
		(fp_line
			(start 0.635 0)
			(end -0.635 0)
			(stroke
				(width 0.508)
				(type default)
			)
			(layer "F.SilkS")
		)
		(fp_rect
			(start -0.9652 1.778)
			(end 0.9652 -1.778)
			(stroke
				(width 0)
				(type default)
			)
			(fill no)
			(layer "F.CrtYd")
		)
		(fp_poly
			(pts
				(xy -0.9652 -1.778) (xy 0.9652 -1.778) (xy 0.9652 1.778) (xy -0.9652 1.778)
			)
			(stroke
				(width 0)
				(type default)
			)
			(fill no)
			(layer "F.Fab")
		)
		(pad "1" smd rect
			(at 0 -0.9652 180)
			(size 1.397 1.143)
			(layers "F.Cu" "F.Mask" "F.Paste")
			(net "P3V3_STBY")
		)
		(pad "2" smd rect
			(at 0 0.9652 180)
			(size 1.397 1.143)
			(layers "F.Cu" "F.Mask" "F.Paste")
			(net "GND")
		)
	)
	(footprint ""
		(layer "F.Cu")
		(at 72.04964 -163.6395 -90)
		(property "Reference" "C245"
			(at 0 0 270)
			(layer "F.SilkS")
			(hide yes)
			(effects
				(font
					(size 1.27 1.27)
				)
			)
		)
		(property "Value" "SCD1U16V2KX-3GP"
			(at 1.1811 -2.7051 270)
			(unlocked yes)
			(layer "F.Fab")
			(hide yes)
			(effects
				(font
					(size 1.016 1.016)
					(thickness 0.1524)
				)
			)
		)
		(property "Device Type" "C402H22"
			(at 1.1811 -4.2291 270)
			(unlocked yes)
			(layer "F.Fab")
			(hide yes)
			(effects
				(font
					(size 1.016 1.016)
					(thickness 0.1524)
				)
			)
		)
		(duplicate_pad_numbers_are_jumpers no)
		(fp_rect
			(start -0.4318 0.9525)
			(end 0.4318 -0.9525)
			(stroke
				(width 0)
				(type default)
			)
			(fill no)
			(layer "F.CrtYd")
		)
		(fp_rect
			(start -0.4318 0.9525)
			(end 0.4318 -0.9525)
			(stroke
				(width 0)
				(type default)
			)
			(fill no)
			(layer "F.Fab")
		)
		(pad "1" smd custom
			(at 0 -0.4445 270)
			(size 0.1524 0.1524)
			(layers "F.Cu" "F.Mask" "F.Paste")
			(net "TPS74801_P1V15_STBY_EN")
			(options
				(clearance outline)
				(anchor circle)
			)
			(primitives
				(gr_poly
					(pts
						(arc
							(start 0.3048 -0.2032)
							(mid 0.275042 -0.275042)
							(end 0.2032 -0.3048)
						)
						(arc
							(start -0.2032 -0.3048)
							(mid -0.275042 -0.275042)
							(end -0.3048 -0.2032)
						)
						(arc
							(start -0.3048 0.2032)
							(mid -0.275042 0.275042)
							(end -0.2032 0.3048)
						)
						(arc
							(start 0.2032 0.3048)
							(mid 0.275042 0.275042)
							(end 0.3048 0.2032)
						)
					)
					(width 0)
					(fill yes)
				)
			)
		)
		(pad "2" smd custom
			(at 0 0.4445 270)
			(size 0.1524 0.1524)
			(layers "F.Cu" "F.Mask" "F.Paste")
			(net "GND")
			(options
				(clearance outline)
				(anchor circle)
			)
			(primitives
				(gr_poly
					(pts
						(arc
							(start 0.3048 -0.2032)
							(mid 0.275042 -0.275042)
							(end 0.2032 -0.3048)
						)
						(arc
							(start -0.2032 -0.3048)
							(mid -0.275042 -0.275042)
							(end -0.3048 -0.2032)
						)
						(arc
							(start -0.3048 0.2032)
							(mid -0.275042 0.275042)
							(end -0.2032 0.3048)
						)
						(arc
							(start 0.2032 0.3048)
							(mid 0.275042 0.275042)
							(end 0.3048 0.2032)
						)
					)
					(width 0)
					(fill yes)
				)
			)
		)
	)
	(footprint ""
		(layer "F.Cu")
		(at 36.7792 -165.5572)
		(property "Reference" "R740"
			(at 0 0 0)
			(layer "F.SilkS")
			(hide yes)
			(effects
				(font
					(size 1.27 1.27)
				)
			)
		)
		(property "Value" "4K7R2F-GP"
			(at 0.064008 -3.993896 0)
			(unlocked yes)
			(layer "F.Fab")
			(hide yes)
			(effects
				(font
					(size 1.016 1.016)
					(thickness 0.1524)
				)
			)
		)
		(property "Device Type" "R402H16"
			(at 0.064008 -5.517896 0)
			(unlocked yes)
			(layer "F.Fab")
			(hide yes)
			(effects
				(font
					(size 1.016 1.016)
					(thickness 0.1524)
				)
			)
		)
		(duplicate_pad_numbers_are_jumpers no)
		(fp_line
			(start -0.508 -0.9398)
			(end -0.508 0.9398)
			(stroke
				(width 0.1524)
				(type default)
			)
			(layer "F.SilkS")
		)
		(fp_line
			(start 0.508 -0.9398)
			(end -0.508 -0.9398)
			(stroke
				(width 0.1524)
				(type default)
			)
			(layer "F.SilkS")
		)
		(fp_rect
			(start -0.508 0.9398)
			(end 0.508 -0.9398)
			(stroke
				(width 0)
				(type default)
			)
			(fill no)
			(layer "F.CrtYd")
		)
		(fp_rect
			(start -0.508 0.9398)
			(end 0.508 -0.9398)
			(stroke
				(width 0)
				(type default)
			)
			(fill no)
			(layer "F.Fab")
		)
		(pad "1" smd custom
			(at 0 -0.4445)
			(size 0.1397 0.1397)
			(layers "F.Cu" "F.Mask" "F.Paste")
			(net "GND")
			(options
				(clearance outline)
				(anchor circle)
			)
			(primitives
				(gr_poly
					(pts
						(arc
							(start -0.1778 -0.2794)
							(mid -0.249642 -0.249642)
							(end -0.2794 -0.1778)
						)
						(arc
							(start -0.2794 0.1778)
							(mid -0.249642 0.249642)
							(end -0.1778 0.2794)
						)
						(arc
							(start 0.1778 0.2794)
							(mid 0.249642 0.249642)
							(end 0.2794 0.1778)
						)
						(arc
							(start 0.2794 -0.1778)
							(mid 0.249642 -0.249642)
							(end 0.1778 -0.2794)
						)
					)
					(width 0)
					(fill yes)
				)
			)
		)
		(pad "2" smd custom
			(at 0 0.4445)
			(size 0.1397 0.1397)
			(layers "F.Cu" "F.Mask" "F.Paste")
			(net "IOM_TYPE0")
			(options
				(clearance outline)
				(anchor circle)
			)
			(primitives
				(gr_poly
					(pts
						(arc
							(start -0.1778 -0.2794)
							(mid -0.249642 -0.249642)
							(end -0.2794 -0.1778)
						)
						(arc
							(start -0.2794 0.1778)
							(mid -0.249642 0.249642)
							(end -0.1778 0.2794)
						)
						(arc
							(start 0.1778 0.2794)
							(mid 0.249642 0.249642)
							(end 0.2794 0.1778)
						)
						(arc
							(start 0.2794 -0.1778)
							(mid 0.249642 -0.249642)
							(end 0.1778 -0.2794)
						)
					)
					(width 0)
					(fill yes)
				)
			)
		)
	)
	(footprint ""
		(layer "F.Cu")
		(at 181.24805 -140.837158)
		(property "Reference" "R470"
			(at 0 0 0)
			(layer "F.SilkS")
			(hide yes)
			(effects
				(font
					(size 1.27 1.27)
				)
			)
		)
		(property "Value" "200KR2F-L-GP"
			(at 0.064008 -3.993896 0)
			(unlocked yes)
			(layer "F.Fab")
			(hide yes)
			(effects
				(font
					(size 1.016 1.016)
					(thickness 0.1524)
				)
			)
		)
		(property "Device Type" "R402H16"
			(at 0.064008 -5.517896 0)
			(unlocked yes)
			(layer "F.Fab")
			(hide yes)
			(effects
				(font
					(size 1.016 1.016)
					(thickness 0.1524)
				)
			)
		)
		(duplicate_pad_numbers_are_jumpers no)
		(fp_line
			(start -0.508 -0.9398)
			(end -0.508 0.9398)
			(stroke
				(width 0.1524)
				(type default)
			)
			(layer "F.SilkS")
		)
		(fp_line
			(start 0.508 -0.9398)
			(end -0.508 -0.9398)
			(stroke
				(width 0.1524)
				(type default)
			)
			(layer "F.SilkS")
		)
		(fp_rect
			(start -0.508 0.9398)
			(end 0.508 -0.9398)
			(stroke
				(width 0)
				(type default)
			)
			(fill no)
			(layer "F.CrtYd")
		)
		(fp_rect
			(start -0.508 0.9398)
			(end 0.508 -0.9398)
			(stroke
				(width 0)
				(type default)
			)
			(fill no)
			(layer "F.Fab")
		)
		(pad "1" smd custom
			(at 0 -0.4445)
			(size 0.1397 0.1397)
			(layers "F.Cu" "F.Mask" "F.Paste")
			(net "P5V_MODE")
			(options
				(clearance outline)
				(anchor circle)
			)
			(primitives
				(gr_poly
					(pts
						(arc
							(start -0.1778 -0.2794)
							(mid -0.249642 -0.249642)
							(end -0.2794 -0.1778)
						)
						(arc
							(start -0.2794 0.1778)
							(mid -0.249642 0.249642)
							(end -0.1778 0.2794)
						)
						(arc
							(start 0.1778 0.2794)
							(mid 0.249642 0.249642)
							(end 0.2794 0.1778)
						)
						(arc
							(start 0.2794 -0.1778)
							(mid 0.249642 -0.249642)
							(end 0.1778 -0.2794)
						)
					)
					(width 0)
					(fill yes)
				)
			)
		)
		(pad "2" smd custom
			(at 0 0.4445)
			(size 0.1397 0.1397)
			(layers "F.Cu" "F.Mask" "F.Paste")
			(net "PWRGD_P5V_STBY")
			(options
				(clearance outline)
				(anchor circle)
			)
			(primitives
				(gr_poly
					(pts
						(arc
							(start -0.1778 -0.2794)
							(mid -0.249642 -0.249642)
							(end -0.2794 -0.1778)
						)
						(arc
							(start -0.2794 0.1778)
							(mid -0.249642 0.249642)
							(end -0.1778 0.2794)
						)
						(arc
							(start 0.1778 0.2794)
							(mid 0.249642 0.249642)
							(end 0.2794 0.1778)
						)
						(arc
							(start 0.2794 -0.1778)
							(mid 0.249642 -0.249642)
							(end 0.1778 -0.2794)
						)
					)
					(width 0)
					(fill yes)
				)
			)
		)
	)
	(footprint ""
		(layer "F.Cu")
		(at 60.2488 -167.4114 90)
		(property "Reference" "R77"
			(at 0 0 90)
			(layer "F.SilkS")
			(hide yes)
			(effects
				(font
					(size 1.27 1.27)
				)
			)
		)
		(property "Value" "10KR2F-2-GP"
			(at 0.064008 -3.993896 90)
			(unlocked yes)
			(layer "F.Fab")
			(hide yes)
			(effects
				(font
					(size 1.016 1.016)
					(thickness 0.1524)
				)
			)
		)
		(property "Device Type" "R402H16"
			(at 0.064008 -5.517896 90)
			(unlocked yes)
			(layer "F.Fab")
			(hide yes)
			(effects
				(font
					(size 1.016 1.016)
					(thickness 0.1524)
				)
			)
		)
		(duplicate_pad_numbers_are_jumpers no)
		(fp_line
			(start 0.508 -0.9398)
			(end -0.508 -0.9398)
			(stroke
				(width 0.1524)
				(type default)
			)
			(layer "F.SilkS")
		)
		(fp_line
			(start -0.508 -0.9398)
			(end -0.508 0.9398)
			(stroke
				(width 0.1524)
				(type default)
			)
			(layer "F.SilkS")
		)
		(fp_rect
			(start -0.508 0.9398)
			(end 0.508 -0.9398)
			(stroke
				(width 0)
				(type default)
			)
			(fill no)
			(layer "F.CrtYd")
		)
		(fp_rect
			(start -0.508 0.9398)
			(end 0.508 -0.9398)
			(stroke
				(width 0)
				(type default)
			)
			(fill no)
			(layer "F.Fab")
		)
		(pad "1" smd custom
			(at 0 -0.4445 90)
			(size 0.1397 0.1397)
			(layers "F.Cu" "F.Mask" "F.Paste")
			(net "P3V3_STBY")
			(options
				(clearance outline)
				(anchor circle)
			)
			(primitives
				(gr_poly
					(pts
						(arc
							(start -0.1778 -0.2794)
							(mid -0.249642 -0.249642)
							(end -0.2794 -0.1778)
						)
						(arc
							(start -0.2794 0.1778)
							(mid -0.249642 0.249642)
							(end -0.1778 0.2794)
						)
						(arc
							(start 0.1778 0.2794)
							(mid 0.249642 0.249642)
							(end 0.2794 0.1778)
						)
						(arc
							(start 0.2794 -0.1778)
							(mid 0.249642 -0.249642)
							(end 0.1778 -0.2794)
						)
					)
					(width 0)
					(fill yes)
				)
			)
		)
		(pad "2" smd custom
			(at 0 0.4445 90)
			(size 0.1397 0.1397)
			(layers "F.Cu" "F.Mask" "F.Paste")
			(net "FM_TPM_PRSNT_RST_N")
			(options
				(clearance outline)
				(anchor circle)
			)
			(primitives
				(gr_poly
					(pts
						(arc
							(start -0.1778 -0.2794)
							(mid -0.249642 -0.249642)
							(end -0.2794 -0.1778)
						)
						(arc
							(start -0.2794 0.1778)
							(mid -0.249642 0.249642)
							(end -0.1778 0.2794)
						)
						(arc
							(start 0.1778 0.2794)
							(mid 0.249642 0.249642)
							(end 0.2794 0.1778)
						)
						(arc
							(start 0.2794 -0.1778)
							(mid 0.249642 -0.249642)
							(end 0.1778 -0.2794)
						)
					)
					(width 0)
					(fill yes)
				)
			)
		)
	)
	(footprint ""
		(layer "F.Cu")
		(at 53.47208 -160.30194)
		(property "Reference" "C84"
			(at 0 0 0)
			(layer "F.SilkS")
			(hide yes)
			(effects
				(font
					(size 1.27 1.27)
				)
			)
		)
		(property "Value" "SCD1U16V2KX-3GP"
			(at 1.1811 -2.7051 0)
			(unlocked yes)
			(layer "F.Fab")
			(hide yes)
			(effects
				(font
					(size 1.016 1.016)
					(thickness 0.1524)
				)
			)
		)
		(property "Device Type" "C402H22"
			(at 1.1811 -4.2291 0)
			(unlocked yes)
			(layer "F.Fab")
			(hide yes)
			(effects
				(font
					(size 1.016 1.016)
					(thickness 0.1524)
				)
			)
		)
		(duplicate_pad_numbers_are_jumpers no)
		(fp_rect
			(start -0.4318 0.9525)
			(end 0.4318 -0.9525)
			(stroke
				(width 0)
				(type default)
			)
			(fill no)
			(layer "F.CrtYd")
		)
		(fp_rect
			(start -0.4318 0.9525)
			(end 0.4318 -0.9525)
			(stroke
				(width 0)
				(type default)
			)
			(fill no)
			(layer "F.Fab")
		)
		(pad "1" smd custom
			(at 0 -0.4445)
			(size 0.1524 0.1524)
			(layers "F.Cu" "F.Mask" "F.Paste")
			(net "ADCAV33")
			(options
				(clearance outline)
				(anchor circle)
			)
			(primitives
				(gr_poly
					(pts
						(arc
							(start 0.3048 -0.2032)
							(mid 0.275042 -0.275042)
							(end 0.2032 -0.3048)
						)
						(arc
							(start -0.2032 -0.3048)
							(mid -0.275042 -0.275042)
							(end -0.3048 -0.2032)
						)
						(arc
							(start -0.3048 0.2032)
							(mid -0.275042 0.275042)
							(end -0.2032 0.3048)
						)
						(arc
							(start 0.2032 0.3048)
							(mid 0.275042 0.275042)
							(end 0.3048 0.2032)
						)
					)
					(width 0)
					(fill yes)
				)
			)
		)
		(pad "2" smd custom
			(at 0 0.4445)
			(size 0.1524 0.1524)
			(layers "F.Cu" "F.Mask" "F.Paste")
			(net "ADCVREFFP")
			(options
				(clearance outline)
				(anchor circle)
			)
			(primitives
				(gr_poly
					(pts
						(arc
							(start 0.3048 -0.2032)
							(mid 0.275042 -0.275042)
							(end 0.2032 -0.3048)
						)
						(arc
							(start -0.2032 -0.3048)
							(mid -0.275042 -0.275042)
							(end -0.3048 -0.2032)
						)
						(arc
							(start -0.3048 0.2032)
							(mid -0.275042 0.275042)
							(end -0.2032 0.3048)
						)
						(arc
							(start 0.2032 0.3048)
							(mid 0.275042 0.275042)
							(end 0.3048 0.2032)
						)
					)
					(width 0)
					(fill yes)
				)
			)
		)
	)
	(footprint ""
		(layer "F.Cu")
		(at 94.153228 -49.421796)
		(property "Reference" "R500"
			(at 0 0 0)
			(layer "F.SilkS")
			(hide yes)
			(effects
				(font
					(size 1.27 1.27)
				)
			)
		)
		(property "Value" "2K2R2J-2-GP"
			(at 0.064008 -3.993896 0)
			(unlocked yes)
			(layer "F.Fab")
			(hide yes)
			(effects
				(font
					(size 1.016 1.016)
					(thickness 0.1524)
				)
			)
		)
		(property "Device Type" "R402H16"
			(at 0.064008 -5.517896 0)
			(unlocked yes)
			(layer "F.Fab")
			(hide yes)
			(effects
				(font
					(size 1.016 1.016)
					(thickness 0.1524)
				)
			)
		)
		(duplicate_pad_numbers_are_jumpers no)
		(fp_line
			(start -0.508 -0.9398)
			(end -0.508 0.9398)
			(stroke
				(width 0.1524)
				(type default)
			)
			(layer "F.SilkS")
		)
		(fp_line
			(start 0.508 -0.9398)
			(end -0.508 -0.9398)
			(stroke
				(width 0.1524)
				(type default)
			)
			(layer "F.SilkS")
		)
		(fp_rect
			(start -0.508 0.9398)
			(end 0.508 -0.9398)
			(stroke
				(width 0)
				(type default)
			)
			(fill no)
			(layer "F.CrtYd")
		)
		(fp_rect
			(start -0.508 0.9398)
			(end 0.508 -0.9398)
			(stroke
				(width 0)
				(type default)
			)
			(fill no)
			(layer "F.Fab")
		)
		(pad "1" smd custom
			(at 0 -0.4445)
			(size 0.1397 0.1397)
			(layers "F.Cu" "F.Mask" "F.Paste")
			(net "P3V3_STBY")
			(options
				(clearance outline)
				(anchor circle)
			)
			(primitives
				(gr_poly
					(pts
						(arc
							(start -0.1778 -0.2794)
							(mid -0.249642 -0.249642)
							(end -0.2794 -0.1778)
						)
						(arc
							(start -0.2794 0.1778)
							(mid -0.249642 0.249642)
							(end -0.1778 0.2794)
						)
						(arc
							(start 0.1778 0.2794)
							(mid 0.249642 0.249642)
							(end 0.2794 0.1778)
						)
						(arc
							(start 0.2794 -0.1778)
							(mid 0.249642 -0.249642)
							(end 0.1778 -0.2794)
						)
					)
					(width 0)
					(fill yes)
				)
			)
		)
		(pad "2" smd custom
			(at 0 0.4445)
			(size 0.1397 0.1397)
			(layers "F.Cu" "F.Mask" "F.Paste")
			(net "PQ2_G")
			(options
				(clearance outline)
				(anchor circle)
			)
			(primitives
				(gr_poly
					(pts
						(arc
							(start -0.1778 -0.2794)
							(mid -0.249642 -0.249642)
							(end -0.2794 -0.1778)
						)
						(arc
							(start -0.2794 0.1778)
							(mid -0.249642 0.249642)
							(end -0.1778 0.2794)
						)
						(arc
							(start 0.1778 0.2794)
							(mid 0.249642 0.249642)
							(end 0.2794 0.1778)
						)
						(arc
							(start 0.2794 -0.1778)
							(mid 0.249642 -0.249642)
							(end 0.1778 -0.2794)
						)
					)
					(width 0)
					(fill yes)
				)
			)
		)
	)
	(footprint ""
		(layer "F.Cu")
		(at 89.908888 -48.245776 180)
		(property "Reference" "C186"
			(at 0 0 180)
			(layer "F.SilkS")
			(hide yes)
			(effects
				(font
					(size 1.27 1.27)
				)
			)
		)
		(property "Value" "SCD47U25V3KX-3-GP"
			(at 0 -2.8194 180)
			(unlocked yes)
			(layer "F.Fab")
			(hide yes)
			(effects
				(font
					(size 1.016 1.016)
					(thickness 0.1524)
				)
			)
		)
		(property "Device Type" "C603H36"
			(at 0 -4.3434 180)
			(unlocked yes)
			(layer "F.Fab")
			(hide yes)
			(effects
				(font
					(size 1.016 1.016)
					(thickness 0.1524)
				)
			)
		)
		(duplicate_pad_numbers_are_jumpers no)
		(fp_line
			(start 0.508 0)
			(end -0.508 0)
			(stroke
				(width 0.2032)
				(type default)
			)
			(layer "F.SilkS")
		)
		(fp_rect
			(start -0.5842 1.3335)
			(end 0.5842 -1.3335)
			(stroke
				(width 0)
				(type default)
			)
			(fill no)
			(layer "F.CrtYd")
		)
		(fp_rect
			(start -0.5842 1.3335)
			(end 0.5842 -1.3335)
			(stroke
				(width 0)
				(type default)
			)
			(fill no)
			(layer "F.Fab")
		)
		(pad "1" smd custom
			(at 0 -0.762 180)
			(size 0.2159 0.2159)
			(layers "F.Cu" "F.Mask" "F.Paste")
			(net "PQ2_D")
			(options
				(clearance outline)
				(anchor circle)
			)
			(primitives
				(gr_poly
					(pts
						(arc
							(start -0.3302 -0.4318)
							(mid -0.402042 -0.402042)
							(end -0.4318 -0.3302)
						)
						(arc
							(start -0.4318 0.3302)
							(mid -0.402042 0.402042)
							(end -0.3302 0.4318)
						)
						(arc
							(start 0.3302 0.4318)
							(mid 0.402042 0.402042)
							(end 0.4318 0.3302)
						)
						(arc
							(start 0.4318 -0.3302)
							(mid 0.402042 -0.402042)
							(end 0.3302 -0.4318)
						)
					)
					(width 0)
					(fill yes)
				)
			)
		)
		(pad "2" smd custom
			(at 0 0.762 180)
			(size 0.2159 0.2159)
			(layers "F.Cu" "F.Mask" "F.Paste")
			(net "P3V3")
			(options
				(clearance outline)
				(anchor circle)
			)
			(primitives
				(gr_poly
					(pts
						(arc
							(start -0.3302 -0.4318)
							(mid -0.402042 -0.402042)
							(end -0.4318 -0.3302)
						)
						(arc
							(start -0.4318 0.3302)
							(mid -0.402042 0.402042)
							(end -0.3302 0.4318)
						)
						(arc
							(start 0.3302 0.4318)
							(mid 0.402042 0.402042)
							(end 0.4318 0.3302)
						)
						(arc
							(start 0.4318 -0.3302)
							(mid 0.402042 -0.402042)
							(end 0.3302 -0.4318)
						)
					)
					(width 0)
					(fill yes)
				)
			)
		)
	)
	(footprint ""
		(layer "F.Cu")
		(at 93.972126 -148.223732)
		(property "Reference" "C18"
			(at 0 0 0)
			(layer "F.SilkS")
			(hide yes)
			(effects
				(font
					(size 1.27 1.27)
				)
			)
		)
		(property "Value" "SC1U16V3KX-5GP"
			(at 0 -2.8194 0)
			(unlocked yes)
			(layer "F.Fab")
			(hide yes)
			(effects
				(font
					(size 1.016 1.016)
					(thickness 0.1524)
				)
			)
		)
		(property "Device Type" "C603H36"
			(at 0 -4.3434 0)
			(unlocked yes)
			(layer "F.Fab")
			(hide yes)
			(effects
				(font
					(size 1.016 1.016)
					(thickness 0.1524)
				)
			)
		)
		(duplicate_pad_numbers_are_jumpers no)
		(fp_line
			(start 0.508 0)
			(end -0.508 0)
			(stroke
				(width 0.2032)
				(type default)
			)
			(layer "F.SilkS")
		)
		(fp_rect
			(start -0.5842 1.3335)
			(end 0.5842 -1.3335)
			(stroke
				(width 0)
				(type default)
			)
			(fill no)
			(layer "F.CrtYd")
		)
		(fp_rect
			(start -0.5842 1.3335)
			(end 0.5842 -1.3335)
			(stroke
				(width 0)
				(type default)
			)
			(fill no)
			(layer "F.Fab")
		)
		(pad "1" smd custom
			(at 0 -0.762)
			(size 0.2159 0.2159)
			(layers "F.Cu" "F.Mask" "F.Paste")
			(net "CRFILT")
			(options
				(clearance outline)
				(anchor circle)
			)
			(primitives
				(gr_poly
					(pts
						(arc
							(start -0.3302 -0.4318)
							(mid -0.402042 -0.402042)
							(end -0.4318 -0.3302)
						)
						(arc
							(start -0.4318 0.3302)
							(mid -0.402042 0.402042)
							(end -0.3302 0.4318)
						)
						(arc
							(start 0.3302 0.4318)
							(mid 0.402042 0.402042)
							(end 0.4318 0.3302)
						)
						(arc
							(start 0.4318 -0.3302)
							(mid 0.402042 -0.402042)
							(end 0.3302 -0.4318)
						)
					)
					(width 0)
					(fill yes)
				)
			)
		)
		(pad "2" smd custom
			(at 0 0.762)
			(size 0.2159 0.2159)
			(layers "F.Cu" "F.Mask" "F.Paste")
			(net "GND")
			(options
				(clearance outline)
				(anchor circle)
			)
			(primitives
				(gr_poly
					(pts
						(arc
							(start -0.3302 -0.4318)
							(mid -0.402042 -0.402042)
							(end -0.4318 -0.3302)
						)
						(arc
							(start -0.4318 0.3302)
							(mid -0.402042 0.402042)
							(end -0.3302 0.4318)
						)
						(arc
							(start 0.3302 0.4318)
							(mid 0.402042 0.402042)
							(end 0.4318 0.3302)
						)
						(arc
							(start 0.4318 -0.3302)
							(mid 0.402042 -0.402042)
							(end 0.3302 -0.4318)
						)
					)
					(width 0)
					(fill yes)
				)
			)
		)
	)
	(footprint ""
		(layer "F.Cu")
		(at 192.5574 -48.2854)
		(property "Reference" "R658"
			(at 0 0 0)
			(layer "F.SilkS")
			(hide yes)
			(effects
				(font
					(size 1.27 1.27)
				)
			)
		)
		(property "Value" "4K7R2F-GP"
			(at 0.064008 -3.993896 0)
			(unlocked yes)
			(layer "F.Fab")
			(hide yes)
			(effects
				(font
					(size 1.016 1.016)
					(thickness 0.1524)
				)
			)
		)
		(property "Device Type" "R402H16"
			(at 0.064008 -5.517896 0)
			(unlocked yes)
			(layer "F.Fab")
			(hide yes)
			(effects
				(font
					(size 1.016 1.016)
					(thickness 0.1524)
				)
			)
		)
		(duplicate_pad_numbers_are_jumpers no)
		(fp_line
			(start -0.508 -0.9398)
			(end -0.508 0.9398)
			(stroke
				(width 0.1524)
				(type default)
			)
			(layer "F.SilkS")
		)
		(fp_line
			(start 0.508 -0.9398)
			(end -0.508 -0.9398)
			(stroke
				(width 0.1524)
				(type default)
			)
			(layer "F.SilkS")
		)
		(fp_rect
			(start -0.508 0.9398)
			(end 0.508 -0.9398)
			(stroke
				(width 0)
				(type default)
			)
			(fill no)
			(layer "F.CrtYd")
		)
		(fp_rect
			(start -0.508 0.9398)
			(end 0.508 -0.9398)
			(stroke
				(width 0)
				(type default)
			)
			(fill no)
			(layer "F.Fab")
		)
		(pad "1" smd custom
			(at 0 -0.4445)
			(size 0.1397 0.1397)
			(layers "F.Cu" "F.Mask" "F.Paste")
			(net "IOC_TRST_N")
			(options
				(clearance outline)
				(anchor circle)
			)
			(primitives
				(gr_poly
					(pts
						(arc
							(start -0.1778 -0.2794)
							(mid -0.249642 -0.249642)
							(end -0.2794 -0.1778)
						)
						(arc
							(start -0.2794 0.1778)
							(mid -0.249642 0.249642)
							(end -0.1778 0.2794)
						)
						(arc
							(start 0.1778 0.2794)
							(mid 0.249642 0.249642)
							(end 0.2794 0.1778)
						)
						(arc
							(start 0.2794 -0.1778)
							(mid 0.249642 -0.249642)
							(end 0.1778 -0.2794)
						)
					)
					(width 0)
					(fill yes)
				)
			)
		)
		(pad "2" smd custom
			(at 0 0.4445)
			(size 0.1397 0.1397)
			(layers "F.Cu" "F.Mask" "F.Paste")
			(net "GND")
			(options
				(clearance outline)
				(anchor circle)
			)
			(primitives
				(gr_poly
					(pts
						(arc
							(start -0.1778 -0.2794)
							(mid -0.249642 -0.249642)
							(end -0.2794 -0.1778)
						)
						(arc
							(start -0.2794 0.1778)
							(mid -0.249642 0.249642)
							(end -0.1778 0.2794)
						)
						(arc
							(start 0.1778 0.2794)
							(mid 0.249642 0.249642)
							(end 0.2794 0.1778)
						)
						(arc
							(start 0.2794 -0.1778)
							(mid 0.249642 -0.249642)
							(end 0.1778 -0.2794)
						)
					)
					(width 0)
					(fill yes)
				)
			)
		)
	)
	(footprint ""
		(layer "F.Cu")
		(at 88.788494 -128.989074 90)
		(property "Reference" "R420"
			(at 0 0 90)
			(layer "F.SilkS")
			(hide yes)
			(effects
				(font
					(size 1.27 1.27)
				)
			)
		)
		(property "Value" "4K7R2F-GP"
			(at 0.064008 -3.993896 90)
			(unlocked yes)
			(layer "F.Fab")
			(hide yes)
			(effects
				(font
					(size 1.016 1.016)
					(thickness 0.1524)
				)
			)
		)
		(property "Device Type" "R402H16"
			(at 0.064008 -5.517896 90)
			(unlocked yes)
			(layer "F.Fab")
			(hide yes)
			(effects
				(font
					(size 1.016 1.016)
					(thickness 0.1524)
				)
			)
		)
		(duplicate_pad_numbers_are_jumpers no)
		(fp_line
			(start 0.508 -0.9398)
			(end -0.508 -0.9398)
			(stroke
				(width 0.1524)
				(type default)
			)
			(layer "F.SilkS")
		)
		(fp_line
			(start -0.508 -0.9398)
			(end -0.508 0.9398)
			(stroke
				(width 0.1524)
				(type default)
			)
			(layer "F.SilkS")
		)
		(fp_rect
			(start -0.508 0.9398)
			(end 0.508 -0.9398)
			(stroke
				(width 0)
				(type default)
			)
			(fill no)
			(layer "F.CrtYd")
		)
		(fp_rect
			(start -0.508 0.9398)
			(end 0.508 -0.9398)
			(stroke
				(width 0)
				(type default)
			)
			(fill no)
			(layer "F.Fab")
		)
		(pad "1" smd custom
			(at 0 -0.4445 90)
			(size 0.1397 0.1397)
			(layers "F.Cu" "F.Mask" "F.Paste")
			(net "P3V3_STBY")
			(options
				(clearance outline)
				(anchor circle)
			)
			(primitives
				(gr_poly
					(pts
						(arc
							(start -0.1778 -0.2794)
							(mid -0.249642 -0.249642)
							(end -0.2794 -0.1778)
						)
						(arc
							(start -0.2794 0.1778)
							(mid -0.249642 0.249642)
							(end -0.1778 0.2794)
						)
						(arc
							(start 0.1778 0.2794)
							(mid 0.249642 0.249642)
							(end 0.2794 0.1778)
						)
						(arc
							(start 0.2794 -0.1778)
							(mid 0.249642 -0.249642)
							(end 0.1778 -0.2794)
						)
					)
					(width 0)
					(fill yes)
				)
			)
		)
		(pad "2" smd custom
			(at 0 0.4445 90)
			(size 0.1397 0.1397)
			(layers "F.Cu" "F.Mask" "F.Paste")
			(net "UART_SEL_MUX")
			(options
				(clearance outline)
				(anchor circle)
			)
			(primitives
				(gr_poly
					(pts
						(arc
							(start -0.1778 -0.2794)
							(mid -0.249642 -0.249642)
							(end -0.2794 -0.1778)
						)
						(arc
							(start -0.2794 0.1778)
							(mid -0.249642 0.249642)
							(end -0.1778 0.2794)
						)
						(arc
							(start 0.1778 0.2794)
							(mid 0.249642 0.249642)
							(end 0.2794 0.1778)
						)
						(arc
							(start 0.2794 -0.1778)
							(mid 0.249642 -0.249642)
							(end 0.1778 -0.2794)
						)
					)
					(width 0)
					(fill yes)
				)
			)
		)
	)
	(footprint ""
		(layer "F.Cu")
		(at 65.659 -172.085 180)
		(property "Reference" "R78"
			(at 0 0 180)
			(layer "F.SilkS")
			(hide yes)
			(effects
				(font
					(size 1.27 1.27)
				)
			)
		)
		(property "Value" "10KR2F-2-GP"
			(at 0.064008 -3.993896 180)
			(unlocked yes)
			(layer "F.Fab")
			(hide yes)
			(effects
				(font
					(size 1.016 1.016)
					(thickness 0.1524)
				)
			)
		)
		(property "Device Type" "R402H16"
			(at 0.064008 -5.517896 180)
			(unlocked yes)
			(layer "F.Fab")
			(hide yes)
			(effects
				(font
					(size 1.016 1.016)
					(thickness 0.1524)
				)
			)
		)
		(duplicate_pad_numbers_are_jumpers no)
		(fp_line
			(start 0.508 -0.9398)
			(end -0.508 -0.9398)
			(stroke
				(width 0.1524)
				(type default)
			)
			(layer "F.SilkS")
		)
		(fp_line
			(start -0.508 -0.9398)
			(end -0.508 0.9398)
			(stroke
				(width 0.1524)
				(type default)
			)
			(layer "F.SilkS")
		)
		(fp_rect
			(start -0.508 0.9398)
			(end 0.508 -0.9398)
			(stroke
				(width 0)
				(type default)
			)
			(fill no)
			(layer "F.CrtYd")
		)
		(fp_rect
			(start -0.508 0.9398)
			(end 0.508 -0.9398)
			(stroke
				(width 0)
				(type default)
			)
			(fill no)
			(layer "F.Fab")
		)
		(pad "1" smd custom
			(at 0 -0.4445 180)
			(size 0.1397 0.1397)
			(layers "F.Cu" "F.Mask" "F.Paste")
			(net "P3V3_STBY")
			(options
				(clearance outline)
				(anchor circle)
			)
			(primitives
				(gr_poly
					(pts
						(arc
							(start -0.1778 -0.2794)
							(mid -0.249642 -0.249642)
							(end -0.2794 -0.1778)
						)
						(arc
							(start -0.2794 0.1778)
							(mid -0.249642 0.249642)
							(end -0.1778 0.2794)
						)
						(arc
							(start 0.1778 0.2794)
							(mid 0.249642 0.249642)
							(end 0.2794 0.1778)
						)
						(arc
							(start 0.2794 -0.1778)
							(mid 0.249642 -0.249642)
							(end 0.1778 -0.2794)
						)
					)
					(width 0)
					(fill yes)
				)
			)
		)
		(pad "2" smd custom
			(at 0 0.4445 180)
			(size 0.1397 0.1397)
			(layers "F.Cu" "F.Mask" "F.Paste")
			(net "FM_TPM_PRSNT_N")
			(options
				(clearance outline)
				(anchor circle)
			)
			(primitives
				(gr_poly
					(pts
						(arc
							(start -0.1778 -0.2794)
							(mid -0.249642 -0.249642)
							(end -0.2794 -0.1778)
						)
						(arc
							(start -0.2794 0.1778)
							(mid -0.249642 0.249642)
							(end -0.1778 0.2794)
						)
						(arc
							(start 0.1778 0.2794)
							(mid 0.249642 0.249642)
							(end 0.2794 0.1778)
						)
						(arc
							(start 0.2794 -0.1778)
							(mid 0.249642 -0.249642)
							(end 0.1778 -0.2794)
						)
					)
					(width 0)
					(fill yes)
				)
			)
		)
	)
	(footprint ""
		(layer "F.Cu")
		(at 8.886698 -141.008862 90)
		(property "Reference" "R227"
			(at 0 0 90)
			(layer "F.SilkS")
			(hide yes)
			(effects
				(font
					(size 1.27 1.27)
				)
			)
		)
		(property "Value" "120R2F-GP"
			(at 0.064008 -3.993896 90)
			(unlocked yes)
			(layer "F.Fab")
			(hide yes)
			(effects
				(font
					(size 1.016 1.016)
					(thickness 0.1524)
				)
			)
		)
		(property "Device Type" "R402H16"
			(at 0.064008 -5.517896 90)
			(unlocked yes)
			(layer "F.Fab")
			(hide yes)
			(effects
				(font
					(size 1.016 1.016)
					(thickness 0.1524)
				)
			)
		)
		(duplicate_pad_numbers_are_jumpers no)
		(fp_line
			(start 0.508 -0.9398)
			(end -0.508 -0.9398)
			(stroke
				(width 0.1524)
				(type default)
			)
			(layer "F.SilkS")
		)
		(fp_line
			(start -0.508 -0.9398)
			(end -0.508 0.9398)
			(stroke
				(width 0.1524)
				(type default)
			)
			(layer "F.SilkS")
		)
		(fp_rect
			(start -0.508 0.9398)
			(end 0.508 -0.9398)
			(stroke
				(width 0)
				(type default)
			)
			(fill no)
			(layer "F.CrtYd")
		)
		(fp_rect
			(start -0.508 0.9398)
			(end 0.508 -0.9398)
			(stroke
				(width 0)
				(type default)
			)
			(fill no)
			(layer "F.Fab")
		)
		(pad "1" smd custom
			(at 0 -0.4445 90)
			(size 0.1397 0.1397)
			(layers "F.Cu" "F.Mask" "F.Paste")
			(net "GND")
			(options
				(clearance outline)
				(anchor circle)
			)
			(primitives
				(gr_poly
					(pts
						(arc
							(start -0.1778 -0.2794)
							(mid -0.249642 -0.249642)
							(end -0.2794 -0.1778)
						)
						(arc
							(start -0.2794 0.1778)
							(mid -0.249642 0.249642)
							(end -0.1778 0.2794)
						)
						(arc
							(start 0.1778 0.2794)
							(mid 0.249642 0.249642)
							(end 0.2794 0.1778)
						)
						(arc
							(start 0.2794 -0.1778)
							(mid 0.249642 -0.249642)
							(end 0.1778 -0.2794)
						)
					)
					(width 0)
					(fill yes)
				)
			)
		)
		(pad "2" smd custom
			(at 0 0.4445 90)
			(size 0.1397 0.1397)
			(layers "F.Cu" "F.Mask" "F.Paste")
			(net "MEMWEN")
			(options
				(clearance outline)
				(anchor circle)
			)
			(primitives
				(gr_poly
					(pts
						(arc
							(start -0.1778 -0.2794)
							(mid -0.249642 -0.249642)
							(end -0.2794 -0.1778)
						)
						(arc
							(start -0.2794 0.1778)
							(mid -0.249642 0.249642)
							(end -0.1778 0.2794)
						)
						(arc
							(start 0.1778 0.2794)
							(mid 0.249642 0.249642)
							(end 0.2794 0.1778)
						)
						(arc
							(start 0.2794 -0.1778)
							(mid 0.249642 -0.249642)
							(end 0.1778 -0.2794)
						)
					)
					(width 0)
					(fill yes)
				)
			)
		)
	)
	(footprint ""
		(layer "F.Cu")
		(at 40.4368 -158.30296)
		(property "Reference" "TP189"
			(at 0 0 0)
			(layer "F.SilkS")
			(hide yes)
			(effects
				(font
					(size 1.27 1.27)
				)
			)
		)
		(property "Value" "TPAD28-2-GP"
			(at -0.0127 -1.6637 0)
			(unlocked yes)
			(layer "F.Fab")
			(hide yes)
			(effects
				(font
					(size 1.016 1.016)
					(thickness 0.1524)
				)
			)
		)
		(property "Device Type" "TPAD28"
			(at -0.0127 -3.1877 0)
			(unlocked yes)
			(layer "F.Fab")
			(hide yes)
			(effects
				(font
					(size 1.016 1.016)
					(thickness 0.1524)
				)
			)
		)
		(duplicate_pad_numbers_are_jumpers no)
		(fp_poly
			(pts
				(arc
					(start 0.3556 0)
					(mid -0.3556 0)
					(end 0.3556 0)
				)
			)
			(stroke
				(width 0)
				(type default)
			)
			(fill no)
			(layer "F.CrtYd")
		)
		(fp_poly
			(pts
				(arc
					(start 0.6096 0)
					(mid -0.6096 0)
					(end 0.6096 0)
				)
			)
			(stroke
				(width 0)
				(type default)
			)
			(fill no)
			(layer "F.Fab")
		)
		(pad "1" smd circle
			(at 0 0)
			(size 0.7112 0.7112)
			(layers "F.Cu" "F.Mask" "F.Paste")
			(net "TP_BMC_GPIOL3")
		)
	)
	(footprint ""
		(layer "F.Cu")
		(at 180.921406 -107.418886)
		(property "Reference" "L11"
			(at 0 0 0)
			(layer "F.SilkS")
			(hide yes)
			(effects
				(font
					(size 1.27 1.27)
				)
			)
		)
		(property "Value" "BLM41PG600-GP"
			(at -3.690874 -7.441184 0)
			(unlocked yes)
			(layer "F.Fab")
			(hide yes)
			(effects
				(font
					(size 1.016 1.016)
					(thickness 0.1524)
				)
			)
		)
		(property "Device Type" "L451616H71"
			(at -3.690874 -5.917184 0)
			(unlocked yes)
			(layer "F.Fab")
			(hide yes)
			(effects
				(font
					(size 1.016 1.016)
					(thickness 0.1524)
				)
			)
		)
		(duplicate_pad_numbers_are_jumpers no)
		(fp_line
			(start -2.8702 -1.2954)
			(end -2.8702 1.2954)
			(stroke
				(width 0.1524)
				(type default)
			)
			(layer "F.SilkS")
		)
		(fp_line
			(start -2.8702 -1.2954)
			(end -2.8702 1.2954)
			(stroke
				(width 0.1524)
				(type default)
			)
			(layer "F.SilkS")
		)
		(fp_line
			(start -2.8702 1.2954)
			(end 2.8702 1.2954)
			(stroke
				(width 0.1524)
				(type default)
			)
			(layer "F.SilkS")
		)
		(fp_line
			(start -2.8702 1.2954)
			(end 2.8702 1.2954)
			(stroke
				(width 0.1524)
				(type default)
			)
			(layer "F.SilkS")
		)
		(fp_line
			(start 2.8702 -1.2954)
			(end -2.8702 -1.2954)
			(stroke
				(width 0.1524)
				(type default)
			)
			(layer "F.SilkS")
		)
		(fp_line
			(start 2.8702 -1.2954)
			(end -2.8702 -1.2954)
			(stroke
				(width 0.1524)
				(type default)
			)
			(layer "F.SilkS")
		)
		(fp_line
			(start 2.8702 1.2954)
			(end 2.8702 -1.2954)
			(stroke
				(width 0.1524)
				(type default)
			)
			(layer "F.SilkS")
		)
		(fp_line
			(start 2.8702 1.2954)
			(end 2.8702 -1.2954)
			(stroke
				(width 0.1524)
				(type default)
			)
			(layer "F.SilkS")
		)
		(fp_poly
			(pts
				(xy -2.8702 1.2954) (xy 2.8702 1.2954) (xy 2.8702 -1.2954) (xy -2.8702 -1.2954)
			)
			(stroke
				(width 0)
				(type default)
			)
			(fill no)
			(layer "F.CrtYd")
		)
		(fp_poly
			(pts
				(xy -2.8702 1.2954) (xy 2.8702 1.2954) (xy 2.8702 -1.2954) (xy -2.8702 -1.2954)
			)
			(stroke
				(width 0)
				(type default)
			)
			(fill no)
			(layer "F.Fab")
		)
		(pad "1" smd rect
			(at -1.9685 0)
			(size 1.3716 1.8796)
			(layers "F.Cu" "F.Mask" "F.Paste")
			(net "P12V_STBY")
		)
		(pad "2" smd rect
			(at 1.9685 0)
			(size 1.3716 1.8796)
			(layers "F.Cu" "F.Mask" "F.Paste")
			(net "VT235_VDDH")
		)
	)
	(footprint ""
		(layer "F.Cu")
		(at 17.723612 -131.007358 180)
		(property "Reference" "R221"
			(at 0 0 180)
			(layer "F.SilkS")
			(hide yes)
			(effects
				(font
					(size 1.27 1.27)
				)
			)
		)
		(property "Value" "120R2F-GP"
			(at 0.064008 -3.993896 180)
			(unlocked yes)
			(layer "F.Fab")
			(hide yes)
			(effects
				(font
					(size 1.016 1.016)
					(thickness 0.1524)
				)
			)
		)
		(property "Device Type" "R402H16"
			(at 0.064008 -5.517896 180)
			(unlocked yes)
			(layer "F.Fab")
			(hide yes)
			(effects
				(font
					(size 1.016 1.016)
					(thickness 0.1524)
				)
			)
		)
		(duplicate_pad_numbers_are_jumpers no)
		(fp_line
			(start 0.508 -0.9398)
			(end -0.508 -0.9398)
			(stroke
				(width 0.1524)
				(type default)
			)
			(layer "F.SilkS")
		)
		(fp_line
			(start -0.508 -0.9398)
			(end -0.508 0.9398)
			(stroke
				(width 0.1524)
				(type default)
			)
			(layer "F.SilkS")
		)
		(fp_rect
			(start -0.508 0.9398)
			(end 0.508 -0.9398)
			(stroke
				(width 0)
				(type default)
			)
			(fill no)
			(layer "F.CrtYd")
		)
		(fp_rect
			(start -0.508 0.9398)
			(end 0.508 -0.9398)
			(stroke
				(width 0)
				(type default)
			)
			(fill no)
			(layer "F.Fab")
		)
		(pad "1" smd custom
			(at 0 -0.4445 180)
			(size 0.1397 0.1397)
			(layers "F.Cu" "F.Mask" "F.Paste")
			(net "DDR4_ACT")
			(options
				(clearance outline)
				(anchor circle)
			)
			(primitives
				(gr_poly
					(pts
						(arc
							(start -0.1778 -0.2794)
							(mid -0.249642 -0.249642)
							(end -0.2794 -0.1778)
						)
						(arc
							(start -0.2794 0.1778)
							(mid -0.249642 0.249642)
							(end -0.1778 0.2794)
						)
						(arc
							(start 0.1778 0.2794)
							(mid 0.249642 0.249642)
							(end 0.2794 0.1778)
						)
						(arc
							(start 0.2794 -0.1778)
							(mid 0.249642 -0.249642)
							(end 0.1778 -0.2794)
						)
					)
					(width 0)
					(fill yes)
				)
			)
		)
		(pad "2" smd custom
			(at 0 0.4445 180)
			(size 0.1397 0.1397)
			(layers "F.Cu" "F.Mask" "F.Paste")
			(net "P1V2_STBY")
			(options
				(clearance outline)
				(anchor circle)
			)
			(primitives
				(gr_poly
					(pts
						(arc
							(start -0.1778 -0.2794)
							(mid -0.249642 -0.249642)
							(end -0.2794 -0.1778)
						)
						(arc
							(start -0.2794 0.1778)
							(mid -0.249642 0.249642)
							(end -0.1778 0.2794)
						)
						(arc
							(start 0.1778 0.2794)
							(mid 0.249642 0.249642)
							(end 0.2794 0.1778)
						)
						(arc
							(start 0.2794 -0.1778)
							(mid 0.249642 -0.249642)
							(end 0.1778 -0.2794)
						)
					)
					(width 0)
					(fill yes)
				)
			)
		)
	)
	(footprint ""
		(layer "F.Cu")
		(at 96.266 -137.9728 -90)
		(property "Reference" "C51"
			(at 0 0 270)
			(layer "F.SilkS")
			(hide yes)
			(effects
				(font
					(size 1.27 1.27)
				)
			)
		)
		(property "Value" "SCD1U16V2KX-3GP"
			(at 1.1811 -2.7051 270)
			(unlocked yes)
			(layer "F.Fab")
			(hide yes)
			(effects
				(font
					(size 1.016 1.016)
					(thickness 0.1524)
				)
			)
		)
		(property "Device Type" "C402H22"
			(at 1.1811 -4.2291 270)
			(unlocked yes)
			(layer "F.Fab")
			(hide yes)
			(effects
				(font
					(size 1.016 1.016)
					(thickness 0.1524)
				)
			)
		)
		(duplicate_pad_numbers_are_jumpers no)
		(fp_rect
			(start -0.4318 0.9525)
			(end 0.4318 -0.9525)
			(stroke
				(width 0)
				(type default)
			)
			(fill no)
			(layer "F.CrtYd")
		)
		(fp_rect
			(start -0.4318 0.9525)
			(end 0.4318 -0.9525)
			(stroke
				(width 0)
				(type default)
			)
			(fill no)
			(layer "F.Fab")
		)
		(pad "1" smd custom
			(at 0 -0.4445 270)
			(size 0.1524 0.1524)
			(layers "F.Cu" "F.Mask" "F.Paste")
			(net "P3V3_STBY")
			(options
				(clearance outline)
				(anchor circle)
			)
			(primitives
				(gr_poly
					(pts
						(arc
							(start 0.3048 -0.2032)
							(mid 0.275042 -0.275042)
							(end 0.2032 -0.3048)
						)
						(arc
							(start -0.2032 -0.3048)
							(mid -0.275042 -0.275042)
							(end -0.3048 -0.2032)
						)
						(arc
							(start -0.3048 0.2032)
							(mid -0.275042 0.275042)
							(end -0.2032 0.3048)
						)
						(arc
							(start 0.2032 0.3048)
							(mid 0.275042 0.275042)
							(end 0.3048 0.2032)
						)
					)
					(width 0)
					(fill yes)
				)
			)
		)
		(pad "2" smd custom
			(at 0 0.4445 270)
			(size 0.1524 0.1524)
			(layers "F.Cu" "F.Mask" "F.Paste")
			(net "GND")
			(options
				(clearance outline)
				(anchor circle)
			)
			(primitives
				(gr_poly
					(pts
						(arc
							(start 0.3048 -0.2032)
							(mid 0.275042 -0.275042)
							(end 0.2032 -0.3048)
						)
						(arc
							(start -0.2032 -0.3048)
							(mid -0.275042 -0.275042)
							(end -0.3048 -0.2032)
						)
						(arc
							(start -0.3048 0.2032)
							(mid -0.275042 0.275042)
							(end -0.2032 0.3048)
						)
						(arc
							(start 0.2032 0.3048)
							(mid 0.275042 0.275042)
							(end 0.3048 0.2032)
						)
					)
					(width 0)
					(fill yes)
				)
			)
		)
	)
	(footprint ""
		(layer "F.Cu")
		(at 162.323018 -91.513914)
		(property "Reference" "R689"
			(at 0 0 0)
			(layer "F.SilkS")
			(hide yes)
			(effects
				(font
					(size 1.27 1.27)
				)
			)
		)
		(property "Value" "2K2R2F-GP"
			(at 0.064008 -3.993896 0)
			(unlocked yes)
			(layer "F.Fab")
			(hide yes)
			(effects
				(font
					(size 1.016 1.016)
					(thickness 0.1524)
				)
			)
		)
		(property "Device Type" "R402H16"
			(at 0.064008 -5.517896 0)
			(unlocked yes)
			(layer "F.Fab")
			(hide yes)
			(effects
				(font
					(size 1.016 1.016)
					(thickness 0.1524)
				)
			)
		)
		(duplicate_pad_numbers_are_jumpers no)
		(fp_line
			(start -0.508 -0.9398)
			(end -0.508 0.9398)
			(stroke
				(width 0.1524)
				(type default)
			)
			(layer "F.SilkS")
		)
		(fp_line
			(start 0.508 -0.9398)
			(end -0.508 -0.9398)
			(stroke
				(width 0.1524)
				(type default)
			)
			(layer "F.SilkS")
		)
		(fp_rect
			(start -0.508 0.9398)
			(end 0.508 -0.9398)
			(stroke
				(width 0)
				(type default)
			)
			(fill no)
			(layer "F.CrtYd")
		)
		(fp_rect
			(start -0.508 0.9398)
			(end 0.508 -0.9398)
			(stroke
				(width 0)
				(type default)
			)
			(fill no)
			(layer "F.Fab")
		)
		(pad "1" smd custom
			(at 0 -0.4445)
			(size 0.1397 0.1397)
			(layers "F.Cu" "F.Mask" "F.Paste")
			(net "I2C_IOC_SDA")
			(options
				(clearance outline)
				(anchor circle)
			)
			(primitives
				(gr_poly
					(pts
						(arc
							(start -0.1778 -0.2794)
							(mid -0.249642 -0.249642)
							(end -0.2794 -0.1778)
						)
						(arc
							(start -0.2794 0.1778)
							(mid -0.249642 0.249642)
							(end -0.1778 0.2794)
						)
						(arc
							(start 0.1778 0.2794)
							(mid 0.249642 0.249642)
							(end 0.2794 0.1778)
						)
						(arc
							(start 0.2794 -0.1778)
							(mid 0.249642 -0.249642)
							(end 0.1778 -0.2794)
						)
					)
					(width 0)
					(fill yes)
				)
			)
		)
		(pad "2" smd custom
			(at 0 0.4445)
			(size 0.1397 0.1397)
			(layers "F.Cu" "F.Mask" "F.Paste")
			(net "P3V3_STBY")
			(options
				(clearance outline)
				(anchor circle)
			)
			(primitives
				(gr_poly
					(pts
						(arc
							(start -0.1778 -0.2794)
							(mid -0.249642 -0.249642)
							(end -0.2794 -0.1778)
						)
						(arc
							(start -0.2794 0.1778)
							(mid -0.249642 0.249642)
							(end -0.1778 0.2794)
						)
						(arc
							(start 0.1778 0.2794)
							(mid 0.249642 0.249642)
							(end 0.2794 0.1778)
						)
						(arc
							(start 0.2794 -0.1778)
							(mid 0.249642 -0.249642)
							(end 0.1778 -0.2794)
						)
					)
					(width 0)
					(fill yes)
				)
			)
		)
	)
	(footprint ""
		(layer "F.Cu")
		(at 67.7672 -170.0022 180)
		(property "Reference" "R79"
			(at 0 0 180)
			(layer "F.SilkS")
			(hide yes)
			(effects
				(font
					(size 1.27 1.27)
				)
			)
		)
		(property "Value" "470KR2F-GP"
			(at 0.064008 -3.993896 180)
			(unlocked yes)
			(layer "F.Fab")
			(hide yes)
			(effects
				(font
					(size 1.016 1.016)
					(thickness 0.1524)
				)
			)
		)
		(property "Device Type" "R402H16"
			(at 0.064008 -5.517896 180)
			(unlocked yes)
			(layer "F.Fab")
			(hide yes)
			(effects
				(font
					(size 1.016 1.016)
					(thickness 0.1524)
				)
			)
		)
		(duplicate_pad_numbers_are_jumpers no)
		(fp_line
			(start 0.508 -0.9398)
			(end -0.508 -0.9398)
			(stroke
				(width 0.1524)
				(type default)
			)
			(layer "F.SilkS")
		)
		(fp_line
			(start -0.508 -0.9398)
			(end -0.508 0.9398)
			(stroke
				(width 0.1524)
				(type default)
			)
			(layer "F.SilkS")
		)
		(fp_rect
			(start -0.508 0.9398)
			(end 0.508 -0.9398)
			(stroke
				(width 0)
				(type default)
			)
			(fill no)
			(layer "F.CrtYd")
		)
		(fp_rect
			(start -0.508 0.9398)
			(end 0.508 -0.9398)
			(stroke
				(width 0)
				(type default)
			)
			(fill no)
			(layer "F.Fab")
		)
		(pad "1" smd custom
			(at 0 -0.4445 180)
			(size 0.1397 0.1397)
			(layers "F.Cu" "F.Mask" "F.Paste")
			(net "BMC_SELF_HW_RST_D")
			(options
				(clearance outline)
				(anchor circle)
			)
			(primitives
				(gr_poly
					(pts
						(arc
							(start -0.1778 -0.2794)
							(mid -0.249642 -0.249642)
							(end -0.2794 -0.1778)
						)
						(arc
							(start -0.2794 0.1778)
							(mid -0.249642 0.249642)
							(end -0.1778 0.2794)
						)
						(arc
							(start 0.1778 0.2794)
							(mid 0.249642 0.249642)
							(end 0.2794 0.1778)
						)
						(arc
							(start 0.2794 -0.1778)
							(mid 0.249642 -0.249642)
							(end 0.1778 -0.2794)
						)
					)
					(width 0)
					(fill yes)
				)
			)
		)
		(pad "2" smd custom
			(at 0 0.4445 180)
			(size 0.1397 0.1397)
			(layers "F.Cu" "F.Mask" "F.Paste")
			(net "GND")
			(options
				(clearance outline)
				(anchor circle)
			)
			(primitives
				(gr_poly
					(pts
						(arc
							(start -0.1778 -0.2794)
							(mid -0.249642 -0.249642)
							(end -0.2794 -0.1778)
						)
						(arc
							(start -0.2794 0.1778)
							(mid -0.249642 0.249642)
							(end -0.1778 0.2794)
						)
						(arc
							(start 0.1778 0.2794)
							(mid 0.249642 0.249642)
							(end 0.2794 0.1778)
						)
						(arc
							(start 0.2794 -0.1778)
							(mid 0.249642 -0.249642)
							(end 0.1778 -0.2794)
						)
					)
					(width 0)
					(fill yes)
				)
			)
		)
	)
	(footprint ""
		(layer "F.Cu")
		(at 66.1924 -170.1292 -90)
		(property "Reference" "C35"
			(at 0 0 270)
			(layer "F.SilkS")
			(hide yes)
			(effects
				(font
					(size 1.27 1.27)
				)
			)
		)
		(property "Value" "SC1U16V2KX-7-GP"
			(at 1.7526 -1.6002 270)
			(unlocked yes)
			(layer "F.Fab")
			(hide yes)
			(effects
				(font
					(size 1.016 1.016)
					(thickness 0.1524)
				)
			)
		)
		(property "Device Type" "C402-TO0D2H24"
			(at 1.7526 -3.1242 270)
			(unlocked yes)
			(layer "F.Fab")
			(hide yes)
			(effects
				(font
					(size 1.016 1.016)
					(thickness 0.1524)
				)
			)
		)
		(duplicate_pad_numbers_are_jumpers no)
		(fp_rect
			(start -0.4826 0.889)
			(end 0.4826 -0.889)
			(stroke
				(width 0)
				(type default)
			)
			(fill no)
			(layer "F.CrtYd")
		)
		(fp_rect
			(start -0.4826 0.889)
			(end 0.4826 -0.889)
			(stroke
				(width 0)
				(type default)
			)
			(fill no)
			(layer "F.Fab")
		)
		(pad "1" smd custom
			(at 0 -0.4572 270)
			(size 0.1524 0.1524)
			(layers "F.Cu" "F.Mask" "F.Paste")
			(net "BMC_SELF_HW_RST_D")
			(options
				(clearance outline)
				(anchor circle)
			)
			(primitives
				(gr_poly
					(pts
						(arc
							(start -0.254 0.3048)
							(mid -0.325842 0.275042)
							(end -0.3556 0.2032)
						)
						(arc
							(start -0.3556 -0.2032)
							(mid -0.325842 -0.275042)
							(end -0.254 -0.3048)
						)
						(arc
							(start 0.254 -0.3048)
							(mid 0.325842 -0.275042)
							(end 0.3556 -0.2032)
						)
						(arc
							(start 0.3556 0.2032)
							(mid 0.325842 0.275042)
							(end 0.254 0.3048)
						)
					)
					(width 0)
					(fill yes)
				)
			)
		)
		(pad "2" smd custom
			(at 0 0.4572 270)
			(size 0.1524 0.1524)
			(layers "F.Cu" "F.Mask" "F.Paste")
			(net "Q4_G")
			(options
				(clearance outline)
				(anchor circle)
			)
			(primitives
				(gr_poly
					(pts
						(arc
							(start -0.254 0.3048)
							(mid -0.325842 0.275042)
							(end -0.3556 0.2032)
						)
						(arc
							(start -0.3556 -0.2032)
							(mid -0.325842 -0.275042)
							(end -0.254 -0.3048)
						)
						(arc
							(start 0.254 -0.3048)
							(mid 0.325842 -0.275042)
							(end 0.3556 -0.2032)
						)
						(arc
							(start 0.3556 0.2032)
							(mid 0.325842 0.275042)
							(end 0.254 0.3048)
						)
					)
					(width 0)
					(fill yes)
				)
			)
		)
	)
	(footprint ""
		(layer "F.Cu")
		(at 77.81798 -186.683396 180)
		(property "Reference" "C200"
			(at 0 0 180)
			(layer "F.SilkS")
			(hide yes)
			(effects
				(font
					(size 1.27 1.27)
				)
			)
		)
		(property "Value" "SC10U6D3V5KX-4GP"
			(at -0.0762 -6.1214 180)
			(unlocked yes)
			(layer "F.Fab")
			(hide yes)
			(effects
				(font
					(size 1.016 1.016)
					(thickness 0.1524)
				)
			)
		)
		(property "Device Type" "C805H58"
			(at -0.0762 -8.1534 180)
			(unlocked yes)
			(layer "F.Fab")
			(hide yes)
			(effects
				(font
					(size 1.016 1.016)
					(thickness 0.1524)
				)
			)
		)
		(duplicate_pad_numbers_are_jumpers no)
		(fp_line
			(start 0.635 0)
			(end -0.635 0)
			(stroke
				(width 0.508)
				(type default)
			)
			(layer "F.SilkS")
		)
		(fp_rect
			(start -0.9652 1.778)
			(end 0.9652 -1.778)
			(stroke
				(width 0)
				(type default)
			)
			(fill no)
			(layer "F.CrtYd")
		)
		(fp_poly
			(pts
				(xy -0.9652 -1.778) (xy 0.9652 -1.778) (xy 0.9652 1.778) (xy -0.9652 1.778)
			)
			(stroke
				(width 0)
				(type default)
			)
			(fill no)
			(layer "F.Fab")
		)
		(pad "1" smd rect
			(at 0 -0.9652 180)
			(size 1.397 1.143)
			(layers "F.Cu" "F.Mask" "F.Paste")
			(net "P3V3_STBY")
		)
		(pad "2" smd rect
			(at 0 0.9652 180)
			(size 1.397 1.143)
			(layers "F.Cu" "F.Mask" "F.Paste")
			(net "GND")
		)
	)
	(footprint ""
		(layer "F.Cu")
		(at 155.956 -86.1314)
		(property "Reference" "C483"
			(at 0 0 0)
			(layer "F.SilkS")
			(hide yes)
			(effects
				(font
					(size 1.27 1.27)
				)
			)
		)
		(property "Value" "SCD1U16V2KX-3GP"
			(at 1.1811 -2.7051 0)
			(unlocked yes)
			(layer "F.Fab")
			(hide yes)
			(effects
				(font
					(size 1.016 1.016)
					(thickness 0.1524)
				)
			)
		)
		(property "Device Type" "C402H22"
			(at 1.1811 -4.2291 0)
			(unlocked yes)
			(layer "F.Fab")
			(hide yes)
			(effects
				(font
					(size 1.016 1.016)
					(thickness 0.1524)
				)
			)
		)
		(duplicate_pad_numbers_are_jumpers no)
		(fp_rect
			(start -0.4318 0.9525)
			(end 0.4318 -0.9525)
			(stroke
				(width 0)
				(type default)
			)
			(fill no)
			(layer "F.CrtYd")
		)
		(fp_rect
			(start -0.4318 0.9525)
			(end 0.4318 -0.9525)
			(stroke
				(width 0)
				(type default)
			)
			(fill no)
			(layer "F.Fab")
		)
		(pad "1" smd custom
			(at 0 -0.4445)
			(size 0.1524 0.1524)
			(layers "F.Cu" "F.Mask" "F.Paste")
			(net "P1V8")
			(options
				(clearance outline)
				(anchor circle)
			)
			(primitives
				(gr_poly
					(pts
						(arc
							(start 0.3048 -0.2032)
							(mid 0.275042 -0.275042)
							(end 0.2032 -0.3048)
						)
						(arc
							(start -0.2032 -0.3048)
							(mid -0.275042 -0.275042)
							(end -0.3048 -0.2032)
						)
						(arc
							(start -0.3048 0.2032)
							(mid -0.275042 0.275042)
							(end -0.2032 0.3048)
						)
						(arc
							(start 0.2032 0.3048)
							(mid 0.275042 0.275042)
							(end 0.3048 0.2032)
						)
					)
					(width 0)
					(fill yes)
				)
			)
		)
		(pad "2" smd custom
			(at 0 0.4445)
			(size 0.1524 0.1524)
			(layers "F.Cu" "F.Mask" "F.Paste")
			(net "GND")
			(options
				(clearance outline)
				(anchor circle)
			)
			(primitives
				(gr_poly
					(pts
						(arc
							(start 0.3048 -0.2032)
							(mid 0.275042 -0.275042)
							(end 0.2032 -0.3048)
						)
						(arc
							(start -0.2032 -0.3048)
							(mid -0.275042 -0.275042)
							(end -0.3048 -0.2032)
						)
						(arc
							(start -0.3048 0.2032)
							(mid -0.275042 0.275042)
							(end -0.2032 0.3048)
						)
						(arc
							(start 0.2032 0.3048)
							(mid 0.275042 0.275042)
							(end 0.3048 0.2032)
						)
					)
					(width 0)
					(fill yes)
				)
			)
		)
	)
	(footprint ""
		(layer "F.Cu")
		(at 181.37886 -82.94116)
		(property "Reference" "R644"
			(at 0 0 0)
			(layer "F.SilkS")
			(hide yes)
			(effects
				(font
					(size 1.27 1.27)
				)
			)
		)
		(property "Value" "4K7R2F-GP"
			(at 0.064008 -3.993896 0)
			(unlocked yes)
			(layer "F.Fab")
			(hide yes)
			(effects
				(font
					(size 1.016 1.016)
					(thickness 0.1524)
				)
			)
		)
		(property "Device Type" "R402H16"
			(at 0.064008 -5.517896 0)
			(unlocked yes)
			(layer "F.Fab")
			(hide yes)
			(effects
				(font
					(size 1.016 1.016)
					(thickness 0.1524)
				)
			)
		)
		(duplicate_pad_numbers_are_jumpers no)
		(fp_line
			(start -0.508 -0.9398)
			(end -0.508 0.9398)
			(stroke
				(width 0.1524)
				(type default)
			)
			(layer "F.SilkS")
		)
		(fp_line
			(start 0.508 -0.9398)
			(end -0.508 -0.9398)
			(stroke
				(width 0.1524)
				(type default)
			)
			(layer "F.SilkS")
		)
		(fp_rect
			(start -0.508 0.9398)
			(end 0.508 -0.9398)
			(stroke
				(width 0)
				(type default)
			)
			(fill no)
			(layer "F.CrtYd")
		)
		(fp_rect
			(start -0.508 0.9398)
			(end 0.508 -0.9398)
			(stroke
				(width 0)
				(type default)
			)
			(fill no)
			(layer "F.Fab")
		)
		(pad "1" smd custom
			(at 0 -0.4445)
			(size 0.1397 0.1397)
			(layers "F.Cu" "F.Mask" "F.Paste")
			(net "P1V8")
			(options
				(clearance outline)
				(anchor circle)
			)
			(primitives
				(gr_poly
					(pts
						(arc
							(start -0.1778 -0.2794)
							(mid -0.249642 -0.249642)
							(end -0.2794 -0.1778)
						)
						(arc
							(start -0.2794 0.1778)
							(mid -0.249642 0.249642)
							(end -0.1778 0.2794)
						)
						(arc
							(start 0.1778 0.2794)
							(mid 0.249642 0.249642)
							(end 0.2794 0.1778)
						)
						(arc
							(start 0.2794 -0.1778)
							(mid 0.249642 -0.249642)
							(end 0.1778 -0.2794)
						)
					)
					(width 0)
					(fill yes)
				)
			)
		)
		(pad "2" smd custom
			(at 0 0.4445)
			(size 0.1397 0.1397)
			(layers "F.Cu" "F.Mask" "F.Paste")
			(net "SYS_DBMODE0")
			(options
				(clearance outline)
				(anchor circle)
			)
			(primitives
				(gr_poly
					(pts
						(arc
							(start -0.1778 -0.2794)
							(mid -0.249642 -0.249642)
							(end -0.2794 -0.1778)
						)
						(arc
							(start -0.2794 0.1778)
							(mid -0.249642 0.249642)
							(end -0.1778 0.2794)
						)
						(arc
							(start 0.1778 0.2794)
							(mid 0.249642 0.249642)
							(end 0.2794 0.1778)
						)
						(arc
							(start 0.2794 -0.1778)
							(mid 0.249642 -0.249642)
							(end 0.1778 -0.2794)
						)
					)
					(width 0)
					(fill yes)
				)
			)
		)
	)
	(footprint ""
		(layer "F.Cu")
		(at 173.1518 -39.5224)
		(property "Reference" "TP170"
			(at 0 0 0)
			(layer "F.SilkS")
			(hide yes)
			(effects
				(font
					(size 1.27 1.27)
				)
			)
		)
		(property "Value" "TPAD28-2-GP"
			(at -0.0127 -1.6637 0)
			(unlocked yes)
			(layer "F.Fab")
			(hide yes)
			(effects
				(font
					(size 1.016 1.016)
					(thickness 0.1524)
				)
			)
		)
		(property "Device Type" "TPAD28"
			(at -0.0127 -3.1877 0)
			(unlocked yes)
			(layer "F.Fab")
			(hide yes)
			(effects
				(font
					(size 1.016 1.016)
					(thickness 0.1524)
				)
			)
		)
		(duplicate_pad_numbers_are_jumpers no)
		(fp_poly
			(pts
				(arc
					(start 0.3556 0)
					(mid -0.3556 0)
					(end 0.3556 0)
				)
			)
			(stroke
				(width 0)
				(type default)
			)
			(fill no)
			(layer "F.CrtYd")
		)
		(fp_poly
			(pts
				(arc
					(start 0.6096 0)
					(mid -0.6096 0)
					(end 0.6096 0)
				)
			)
			(stroke
				(width 0)
				(type default)
			)
			(fill no)
			(layer "F.Fab")
		)
		(pad "1" smd circle
			(at 0 0)
			(size 0.7112 0.7112)
			(layers "F.Cu" "F.Mask" "F.Paste")
			(net "ZDEF_EXTA_TP_A1")
		)
	)
	(footprint ""
		(layer "F.Cu")
		(at 81.162144 -168.225216 180)
		(property "Reference" "C243"
			(at 0 0 180)
			(layer "F.SilkS")
			(hide yes)
			(effects
				(font
					(size 1.27 1.27)
				)
			)
		)
		(property "Value" "SC10U6D3V5KX-4GP"
			(at -0.0762 -6.1214 180)
			(unlocked yes)
			(layer "F.Fab")
			(hide yes)
			(effects
				(font
					(size 1.016 1.016)
					(thickness 0.1524)
				)
			)
		)
		(property "Device Type" "C805H58"
			(at -0.0762 -8.1534 180)
			(unlocked yes)
			(layer "F.Fab")
			(hide yes)
			(effects
				(font
					(size 1.016 1.016)
					(thickness 0.1524)
				)
			)
		)
		(duplicate_pad_numbers_are_jumpers no)
		(fp_line
			(start 0.635 0)
			(end -0.635 0)
			(stroke
				(width 0.508)
				(type default)
			)
			(layer "F.SilkS")
		)
		(fp_rect
			(start -0.9652 1.778)
			(end 0.9652 -1.778)
			(stroke
				(width 0)
				(type default)
			)
			(fill no)
			(layer "F.CrtYd")
		)
		(fp_poly
			(pts
				(xy -0.9652 -1.778) (xy 0.9652 -1.778) (xy 0.9652 1.778) (xy -0.9652 1.778)
			)
			(stroke
				(width 0)
				(type default)
			)
			(fill no)
			(layer "F.Fab")
		)
		(pad "1" smd rect
			(at 0 -0.9652 180)
			(size 1.397 1.143)
			(layers "F.Cu" "F.Mask" "F.Paste")
			(net "P1V8_STBY")
		)
		(pad "2" smd rect
			(at 0 0.9652 180)
			(size 1.397 1.143)
			(layers "F.Cu" "F.Mask" "F.Paste")
			(net "GND")
		)
	)
	(footprint ""
		(layer "F.Cu")
		(at 177.546 -73.6854)
		(property "Reference" "TP93"
			(at 0 0 0)
			(layer "F.SilkS")
			(hide yes)
			(effects
				(font
					(size 1.27 1.27)
				)
			)
		)
		(property "Value" "TPAD28-2-GP"
			(at -0.0127 -1.6637 0)
			(unlocked yes)
			(layer "F.Fab")
			(hide yes)
			(effects
				(font
					(size 1.016 1.016)
					(thickness 0.1524)
				)
			)
		)
		(property "Device Type" "TPAD28"
			(at -0.0127 -3.1877 0)
			(unlocked yes)
			(layer "F.Fab")
			(hide yes)
			(effects
				(font
					(size 1.016 1.016)
					(thickness 0.1524)
				)
			)
		)
		(duplicate_pad_numbers_are_jumpers no)
		(fp_poly
			(pts
				(arc
					(start 0.3556 0)
					(mid -0.3556 0)
					(end 0.3556 0)
				)
			)
			(stroke
				(width 0)
				(type default)
			)
			(fill no)
			(layer "F.CrtYd")
		)
		(fp_poly
			(pts
				(arc
					(start 0.6096 0)
					(mid -0.6096 0)
					(end 0.6096 0)
				)
			)
			(stroke
				(width 0)
				(type default)
			)
			(fill no)
			(layer "F.Fab")
		)
		(pad "1" smd circle
			(at 0 0)
			(size 0.7112 0.7112)
			(layers "F.Cu" "F.Mask" "F.Paste")
			(net "IOC_GPIO_8")
		)
	)
	(footprint ""
		(layer "F.Cu")
		(at 158.40964 -140.955522 -90)
		(property "Reference" "C208"
			(at 0 0 270)
			(layer "F.SilkS")
			(hide yes)
			(effects
				(font
					(size 1.27 1.27)
				)
			)
		)
		(property "Value" "SC3300P50V2KX-1GP"
			(at 1.1811 -2.7051 270)
			(unlocked yes)
			(layer "F.Fab")
			(hide yes)
			(effects
				(font
					(size 1.016 1.016)
					(thickness 0.1524)
				)
			)
		)
		(property "Device Type" "C402H22"
			(at 1.1811 -4.2291 270)
			(unlocked yes)
			(layer "F.Fab")
			(hide yes)
			(effects
				(font
					(size 1.016 1.016)
					(thickness 0.1524)
				)
			)
		)
		(duplicate_pad_numbers_are_jumpers no)
		(fp_rect
			(start -0.4318 0.9525)
			(end 0.4318 -0.9525)
			(stroke
				(width 0)
				(type default)
			)
			(fill no)
			(layer "F.CrtYd")
		)
		(fp_rect
			(start -0.4318 0.9525)
			(end 0.4318 -0.9525)
			(stroke
				(width 0)
				(type default)
			)
			(fill no)
			(layer "F.Fab")
		)
		(pad "1" smd custom
			(at 0 -0.4445 270)
			(size 0.1524 0.1524)
			(layers "F.Cu" "F.Mask" "F.Paste")
			(net "P1V8_STBY_SS")
			(options
				(clearance outline)
				(anchor circle)
			)
			(primitives
				(gr_poly
					(pts
						(arc
							(start 0.3048 -0.2032)
							(mid 0.275042 -0.275042)
							(end 0.2032 -0.3048)
						)
						(arc
							(start -0.2032 -0.3048)
							(mid -0.275042 -0.275042)
							(end -0.3048 -0.2032)
						)
						(arc
							(start -0.3048 0.2032)
							(mid -0.275042 0.275042)
							(end -0.2032 0.3048)
						)
						(arc
							(start 0.2032 0.3048)
							(mid 0.275042 0.275042)
							(end 0.3048 0.2032)
						)
					)
					(width 0)
					(fill yes)
				)
			)
		)
		(pad "2" smd custom
			(at 0 0.4445 270)
			(size 0.1524 0.1524)
			(layers "F.Cu" "F.Mask" "F.Paste")
			(net "AGND_P1V8_STBY")
			(options
				(clearance outline)
				(anchor circle)
			)
			(primitives
				(gr_poly
					(pts
						(arc
							(start 0.3048 -0.2032)
							(mid 0.275042 -0.275042)
							(end 0.2032 -0.3048)
						)
						(arc
							(start -0.2032 -0.3048)
							(mid -0.275042 -0.275042)
							(end -0.3048 -0.2032)
						)
						(arc
							(start -0.3048 0.2032)
							(mid -0.275042 0.275042)
							(end -0.2032 0.3048)
						)
						(arc
							(start 0.2032 0.3048)
							(mid 0.275042 0.275042)
							(end 0.3048 0.2032)
						)
					)
					(width 0)
					(fill yes)
				)
			)
		)
	)
	(footprint ""
		(layer "F.Cu")
		(at 99.601782 -151.43226)
		(property "Reference" "R36"
			(at 0 0 0)
			(layer "F.SilkS")
			(hide yes)
			(effects
				(font
					(size 1.27 1.27)
				)
			)
		)
		(property "Value" "4K7R2F-GP"
			(at 0.064008 -3.993896 0)
			(unlocked yes)
			(layer "F.Fab")
			(hide yes)
			(effects
				(font
					(size 1.016 1.016)
					(thickness 0.1524)
				)
			)
		)
		(property "Device Type" "R402H16"
			(at 0.064008 -5.517896 0)
			(unlocked yes)
			(layer "F.Fab")
			(hide yes)
			(effects
				(font
					(size 1.016 1.016)
					(thickness 0.1524)
				)
			)
		)
		(duplicate_pad_numbers_are_jumpers no)
		(fp_line
			(start -0.508 -0.9398)
			(end -0.508 0.9398)
			(stroke
				(width 0.1524)
				(type default)
			)
			(layer "F.SilkS")
		)
		(fp_line
			(start 0.508 -0.9398)
			(end -0.508 -0.9398)
			(stroke
				(width 0.1524)
				(type default)
			)
			(layer "F.SilkS")
		)
		(fp_rect
			(start -0.508 0.9398)
			(end 0.508 -0.9398)
			(stroke
				(width 0)
				(type default)
			)
			(fill no)
			(layer "F.CrtYd")
		)
		(fp_rect
			(start -0.508 0.9398)
			(end 0.508 -0.9398)
			(stroke
				(width 0)
				(type default)
			)
			(fill no)
			(layer "F.Fab")
		)
		(pad "1" smd custom
			(at 0 -0.4445)
			(size 0.1397 0.1397)
			(layers "F.Cu" "F.Mask" "F.Paste")
			(net "P3V3_STBY")
			(options
				(clearance outline)
				(anchor circle)
			)
			(primitives
				(gr_poly
					(pts
						(arc
							(start -0.1778 -0.2794)
							(mid -0.249642 -0.249642)
							(end -0.2794 -0.1778)
						)
						(arc
							(start -0.2794 0.1778)
							(mid -0.249642 0.249642)
							(end -0.1778 0.2794)
						)
						(arc
							(start 0.1778 0.2794)
							(mid 0.249642 0.249642)
							(end 0.2794 0.1778)
						)
						(arc
							(start 0.2794 -0.1778)
							(mid 0.249642 -0.249642)
							(end 0.1778 -0.2794)
						)
					)
					(width 0)
					(fill yes)
				)
			)
		)
		(pad "2" smd custom
			(at 0 0.4445)
			(size 0.1397 0.1397)
			(layers "F.Cu" "F.Mask" "F.Paste")
			(net "USB_EN_4")
			(options
				(clearance outline)
				(anchor circle)
			)
			(primitives
				(gr_poly
					(pts
						(arc
							(start -0.1778 -0.2794)
							(mid -0.249642 -0.249642)
							(end -0.2794 -0.1778)
						)
						(arc
							(start -0.2794 0.1778)
							(mid -0.249642 0.249642)
							(end -0.1778 0.2794)
						)
						(arc
							(start 0.1778 0.2794)
							(mid 0.249642 0.249642)
							(end 0.2794 0.1778)
						)
						(arc
							(start 0.2794 -0.1778)
							(mid 0.249642 -0.249642)
							(end 0.1778 -0.2794)
						)
					)
					(width 0)
					(fill yes)
				)
			)
		)
	)
	(footprint ""
		(layer "F.Cu")
		(at 98.9076 -153.9748 -90)
		(property "Reference" "R19"
			(at 0 0 270)
			(layer "F.SilkS")
			(hide yes)
			(effects
				(font
					(size 1.27 1.27)
				)
			)
		)
		(property "Value" "4K7R2F-GP"
			(at 0.064008 -3.993896 270)
			(unlocked yes)
			(layer "F.Fab")
			(hide yes)
			(effects
				(font
					(size 1.016 1.016)
					(thickness 0.1524)
				)
			)
		)
		(property "Device Type" "R402H16"
			(at 0.064008 -5.517896 270)
			(unlocked yes)
			(layer "F.Fab")
			(hide yes)
			(effects
				(font
					(size 1.016 1.016)
					(thickness 0.1524)
				)
			)
		)
		(duplicate_pad_numbers_are_jumpers no)
		(fp_line
			(start -0.508 -0.9398)
			(end -0.508 0.9398)
			(stroke
				(width 0.1524)
				(type default)
			)
			(layer "F.SilkS")
		)
		(fp_line
			(start 0.508 -0.9398)
			(end -0.508 -0.9398)
			(stroke
				(width 0.1524)
				(type default)
			)
			(layer "F.SilkS")
		)
		(fp_rect
			(start -0.508 0.9398)
			(end 0.508 -0.9398)
			(stroke
				(width 0)
				(type default)
			)
			(fill no)
			(layer "F.CrtYd")
		)
		(fp_rect
			(start -0.508 0.9398)
			(end 0.508 -0.9398)
			(stroke
				(width 0)
				(type default)
			)
			(fill no)
			(layer "F.Fab")
		)
		(pad "1" smd custom
			(at 0 -0.4445 270)
			(size 0.1397 0.1397)
			(layers "F.Cu" "F.Mask" "F.Paste")
			(net "P3V3_STBY")
			(options
				(clearance outline)
				(anchor circle)
			)
			(primitives
				(gr_poly
					(pts
						(arc
							(start -0.1778 -0.2794)
							(mid -0.249642 -0.249642)
							(end -0.2794 -0.1778)
						)
						(arc
							(start -0.2794 0.1778)
							(mid -0.249642 0.249642)
							(end -0.1778 0.2794)
						)
						(arc
							(start 0.1778 0.2794)
							(mid 0.249642 0.249642)
							(end 0.2794 0.1778)
						)
						(arc
							(start 0.2794 -0.1778)
							(mid 0.249642 -0.249642)
							(end 0.1778 -0.2794)
						)
					)
					(width 0)
					(fill yes)
				)
			)
		)
		(pad "2" smd custom
			(at 0 0.4445 270)
			(size 0.1397 0.1397)
			(layers "F.Cu" "F.Mask" "F.Paste")
			(net "CFG_SEL0")
			(options
				(clearance outline)
				(anchor circle)
			)
			(primitives
				(gr_poly
					(pts
						(arc
							(start -0.1778 -0.2794)
							(mid -0.249642 -0.249642)
							(end -0.2794 -0.1778)
						)
						(arc
							(start -0.2794 0.1778)
							(mid -0.249642 0.249642)
							(end -0.1778 0.2794)
						)
						(arc
							(start 0.1778 0.2794)
							(mid 0.249642 0.249642)
							(end 0.2794 0.1778)
						)
						(arc
							(start 0.2794 -0.1778)
							(mid 0.249642 -0.249642)
							(end 0.1778 -0.2794)
						)
					)
					(width 0)
					(fill yes)
				)
			)
		)
	)
	(footprint ""
		(layer "F.Cu")
		(at 94.765876 -21.51253 90)
		(property "Reference" "D17"
			(at 0 0 90)
			(layer "F.SilkS")
			(hide yes)
			(effects
				(font
					(size 1.27 1.27)
				)
			)
		)
		(property "Value" "PESD5V0S1BL-1-GP"
			(at 1.8923 -1.5621 90)
			(unlocked yes)
			(layer "F.Fab")
			(hide yes)
			(effects
				(font
					(size 1.016 1.016)
					(thickness 0.1524)
				)
			)
		)
		(property "Device Type" "SOD882-10D6-1H20"
			(at 1.8923 -3.0861 90)
			(unlocked yes)
			(layer "F.Fab")
			(hide yes)
			(effects
				(font
					(size 1.016 1.016)
					(thickness 0.1524)
				)
			)
		)
		(duplicate_pad_numbers_are_jumpers no)
		(fp_line
			(start -0.3048 -0.9271)
			(end 0.3048 -0.9271)
			(stroke
				(width 0.254)
				(type default)
			)
			(layer "F.SilkS")
		)
		(fp_rect
			(start -0.2921 0.4953)
			(end 0.2921 -0.4953)
			(stroke
				(width 0)
				(type default)
			)
			(fill no)
			(layer "F.CrtYd")
		)
		(fp_poly
			(pts
				(xy -0.4318 0.8001) (xy -0.4318 -0.266192) (xy -0.2921 -0.266192) (xy -0.2921 0.4953) (xy 0.2921 0.4953)
				(xy 0.2921 -0.4953) (xy -0.2921 -0.4953) (xy -0.2921 -0.2667) (xy -0.4318 -0.2667) (xy -0.4318 -0.8001)
				(xy 0.4318 -0.8001) (xy 0.4318 0.8001)
			)
			(stroke
				(width 0)
				(type default)
			)
			(fill no)
			(layer "F.CrtYd")
		)
		(fp_rect
			(start -0.4318 0.8001)
			(end 0.4318 -0.8001)
			(stroke
				(width 0)
				(type default)
			)
			(fill no)
			(layer "F.Fab")
		)
		(pad "1" smd custom
			(at 0 -0.4445 90)
			(size 0.1143 0.1143)
			(layers "F.Cu" "F.Mask" "F.Paste")
			(net "UART_IOM_RX")
			(options
				(clearance outline)
				(anchor circle)
			)
			(primitives
				(gr_poly
					(pts
						(arc
							(start -0.2032 0.2286)
							(mid -0.275042 0.198842)
							(end -0.3048 0.127)
						)
						(arc
							(start -0.3048 -0.127)
							(mid -0.275042 -0.198842)
							(end -0.2032 -0.2286)
						)
						(arc
							(start 0.2032 -0.2286)
							(mid 0.275042 -0.198842)
							(end 0.3048 -0.127)
						)
						(arc
							(start 0.3048 0.127)
							(mid 0.275042 0.198842)
							(end 0.2032 0.2286)
						)
					)
					(width 0)
					(fill yes)
				)
			)
		)
		(pad "2" smd custom
			(at 0 0.4445 90)
			(size 0.1143 0.1143)
			(layers "F.Cu" "F.Mask" "F.Paste")
			(net "GND")
			(options
				(clearance outline)
				(anchor circle)
			)
			(primitives
				(gr_poly
					(pts
						(arc
							(start 0.2032 -0.2286)
							(mid 0.275042 -0.198842)
							(end 0.3048 -0.127)
						)
						(arc
							(start 0.3048 0.127)
							(mid 0.275042 0.198842)
							(end 0.2032 0.2286)
						)
						(arc
							(start -0.2032 0.2286)
							(mid -0.275042 0.198842)
							(end -0.3048 0.127)
						)
						(arc
							(start -0.3048 -0.127)
							(mid -0.275042 -0.198842)
							(end -0.2032 -0.2286)
						)
					)
					(width 0)
					(fill yes)
				)
			)
		)
	)
	(footprint ""
		(layer "F.Cu")
		(at 87.702898 -136.971786 180)
		(property "Reference" "R133"
			(at 0 0 180)
			(layer "F.SilkS")
			(hide yes)
			(effects
				(font
					(size 1.27 1.27)
				)
			)
		)
		(property "Value" "8K2R2J-3-GP"
			(at 0.064008 -3.993896 180)
			(unlocked yes)
			(layer "F.Fab")
			(hide yes)
			(effects
				(font
					(size 1.016 1.016)
					(thickness 0.1524)
				)
			)
		)
		(property "Device Type" "R402H16"
			(at 0.064008 -5.517896 180)
			(unlocked yes)
			(layer "F.Fab")
			(hide yes)
			(effects
				(font
					(size 1.016 1.016)
					(thickness 0.1524)
				)
			)
		)
		(duplicate_pad_numbers_are_jumpers no)
		(fp_line
			(start 0.508 -0.9398)
			(end -0.508 -0.9398)
			(stroke
				(width 0.1524)
				(type default)
			)
			(layer "F.SilkS")
		)
		(fp_line
			(start -0.508 -0.9398)
			(end -0.508 0.9398)
			(stroke
				(width 0.1524)
				(type default)
			)
			(layer "F.SilkS")
		)
		(fp_rect
			(start -0.508 0.9398)
			(end 0.508 -0.9398)
			(stroke
				(width 0)
				(type default)
			)
			(fill no)
			(layer "F.CrtYd")
		)
		(fp_rect
			(start -0.508 0.9398)
			(end 0.508 -0.9398)
			(stroke
				(width 0)
				(type default)
			)
			(fill no)
			(layer "F.Fab")
		)
		(pad "1" smd custom
			(at 0 -0.4445 180)
			(size 0.1397 0.1397)
			(layers "F.Cu" "F.Mask" "F.Paste")
			(net "P3V3_STBY")
			(options
				(clearance outline)
				(anchor circle)
			)
			(primitives
				(gr_poly
					(pts
						(arc
							(start -0.1778 -0.2794)
							(mid -0.249642 -0.249642)
							(end -0.2794 -0.1778)
						)
						(arc
							(start -0.2794 0.1778)
							(mid -0.249642 0.249642)
							(end -0.1778 0.2794)
						)
						(arc
							(start 0.1778 0.2794)
							(mid 0.249642 0.249642)
							(end 0.2794 0.1778)
						)
						(arc
							(start 0.2794 -0.1778)
							(mid 0.249642 -0.249642)
							(end 0.1778 -0.2794)
						)
					)
					(width 0)
					(fill yes)
				)
			)
		)
		(pad "2" smd custom
			(at 0 0.4445 180)
			(size 0.1397 0.1397)
			(layers "F.Cu" "F.Mask" "F.Paste")
			(net "EEPROM_A0")
			(options
				(clearance outline)
				(anchor circle)
			)
			(primitives
				(gr_poly
					(pts
						(arc
							(start -0.1778 -0.2794)
							(mid -0.249642 -0.249642)
							(end -0.2794 -0.1778)
						)
						(arc
							(start -0.2794 0.1778)
							(mid -0.249642 0.249642)
							(end -0.1778 0.2794)
						)
						(arc
							(start 0.1778 0.2794)
							(mid 0.249642 0.249642)
							(end 0.2794 0.1778)
						)
						(arc
							(start 0.2794 -0.1778)
							(mid 0.249642 -0.249642)
							(end 0.1778 -0.2794)
						)
					)
					(width 0)
					(fill yes)
				)
			)
		)
	)
	(footprint ""
		(layer "F.Cu")
		(at 199.5424 -28.9179)
		(property "Reference" "Q27"
			(at 0 0 0)
			(layer "F.SilkS")
			(hide yes)
			(effects
				(font
					(size 1.27 1.27)
				)
			)
		)
		(property "Value" "SSM3K324R-GP"
			(at 0.127 -8.9662 0)
			(unlocked yes)
			(layer "F.Fab")
			(hide yes)
			(effects
				(font
					(size 1.016 1.016)
					(thickness 0.1524)
				)
			)
		)
		(property "Device Type" "SOT23DGS2D4H35"
			(at 0.127 -10.4902 0)
			(unlocked yes)
			(layer "F.Fab")
			(hide yes)
			(effects
				(font
					(size 1.016 1.016)
					(thickness 0.1524)
				)
			)
		)
		(duplicate_pad_numbers_are_jumpers no)
		(fp_line
			(start -1.651 -1.778)
			(end -1.651 1.778)
			(stroke
				(width 0.1524)
				(type default)
			)
			(layer "F.SilkS")
		)
		(fp_line
			(start -1.651 1.778)
			(end 1.651 1.778)
			(stroke
				(width 0.1524)
				(type default)
			)
			(layer "F.SilkS")
		)
		(fp_line
			(start 1.651 -1.778)
			(end -1.651 -1.778)
			(stroke
				(width 0.1524)
				(type default)
			)
			(layer "F.SilkS")
		)
		(fp_line
			(start 1.651 1.778)
			(end 1.651 -1.778)
			(stroke
				(width 0.1524)
				(type default)
			)
			(layer "F.SilkS")
		)
		(fp_poly
			(pts
				(xy -1.778 1.8796) (xy -1.778 -1.8796) (xy 1.778 -1.8796) (xy 1.778 1.8796)
			)
			(stroke
				(width 0)
				(type default)
			)
			(fill no)
			(layer "F.CrtYd")
		)
		(fp_poly
			(pts
				(xy -1.778 1.8796) (xy -1.778 -1.8796) (xy 1.778 -1.8796) (xy 1.778 1.8796)
			)
			(stroke
				(width 0)
				(type default)
			)
			(fill no)
			(layer "F.Fab")
		)
		(pad "D" smd custom
			(at 0 -0.9525)
			(size 0.1905 0.1905)
			(layers "F.Cu" "F.Mask" "F.Paste")
			(net "EXT2_LED_BLUE_G2")
			(options
				(clearance outline)
				(anchor circle)
			)
			(primitives
				(gr_poly
					(pts
						(arc
							(start -0.1778 0.5715)
							(mid -0.321484 0.511984)
							(end -0.381 0.3683)
						)
						(arc
							(start -0.381 -0.3683)
							(mid -0.321484 -0.511984)
							(end -0.1778 -0.5715)
						)
						(arc
							(start 0.1778 -0.5715)
							(mid 0.321484 -0.511984)
							(end 0.381 -0.3683)
						)
						(arc
							(start 0.381 0.3683)
							(mid 0.321484 0.511984)
							(end 0.1778 0.5715)
						)
					)
					(width 0)
					(fill yes)
				)
			)
		)
		(pad "G" smd custom
			(at -0.98425 0.9525)
			(size 0.1905 0.1905)
			(layers "F.Cu" "F.Mask" "F.Paste")
			(net "EXT2_LED_BLUE_G_Q27")
			(options
				(clearance outline)
				(anchor circle)
			)
			(primitives
				(gr_poly
					(pts
						(arc
							(start -0.1778 0.5715)
							(mid -0.321484 0.511984)
							(end -0.381 0.3683)
						)
						(arc
							(start -0.381 -0.3683)
							(mid -0.321484 -0.511984)
							(end -0.1778 -0.5715)
						)
						(arc
							(start 0.1778 -0.5715)
							(mid 0.321484 -0.511984)
							(end 0.381 -0.3683)
						)
						(arc
							(start 0.381 0.3683)
							(mid 0.321484 0.511984)
							(end 0.1778 0.5715)
						)
					)
					(width 0)
					(fill yes)
				)
			)
		)
		(pad "S" smd custom
			(at 0.98425 0.9525)
			(size 0.1905 0.1905)
			(layers "F.Cu" "F.Mask" "F.Paste")
			(net "GND")
			(options
				(clearance outline)
				(anchor circle)
			)
			(primitives
				(gr_poly
					(pts
						(arc
							(start -0.1778 0.5715)
							(mid -0.321484 0.511984)
							(end -0.381 0.3683)
						)
						(arc
							(start -0.381 -0.3683)
							(mid -0.321484 -0.511984)
							(end -0.1778 -0.5715)
						)
						(arc
							(start 0.1778 -0.5715)
							(mid 0.321484 -0.511984)
							(end 0.381 -0.3683)
						)
						(arc
							(start 0.381 0.3683)
							(mid 0.321484 0.511984)
							(end 0.1778 0.5715)
						)
					)
					(width 0)
					(fill yes)
				)
			)
		)
	)
	(footprint ""
		(layer "F.Cu")
		(at 84.983828 -85.349334 90)
		(property "Reference" "VIA14"
			(at 0 0 90)
			(layer "F.SilkS")
			(hide yes)
			(effects
				(font
					(size 1.27 1.27)
				)
			)
		)
		(property "Value" "85OHM-8L-1D6MM-L16L18-GP"
			(at 4.064 0.6096 90)
			(unlocked yes)
			(layer "F.Fab")
			(hide yes)
			(effects
				(font
					(size 1.016 1.016)
					(thickness 0.1524)
				)
			)
		)
		(property "Device Type" "VIA-PCIE-4P-368076"
			(at 4.064 -0.9144 90)
			(unlocked yes)
			(layer "F.Fab")
			(hide yes)
			(effects
				(font
					(size 1.016 1.016)
					(thickness 0.1524)
				)
			)
		)
		(duplicate_pad_numbers_are_jumpers no)
		(fp_rect
			(start -1.8415 0.381)
			(end 1.8415 -0.381)
			(stroke
				(width 0)
				(type default)
			)
			(fill no)
			(layer "F.CrtYd")
		)
		(fp_rect
			(start -1.8415 0.381)
			(end 1.8415 -0.381)
			(stroke
				(width 0)
				(type default)
			)
			(fill no)
			(layer "F.Fab")
		)
		(pad "1" thru_hole circle
			(at -1.4605 0 90)
			(size 0.508 0.508)
			(drill 0.254)
			(layers "*.Cu" "*.Mask")
			(remove_unused_layers no)
			(net "GND")
			(clearance 0.127)
			(thermal_gap 0.127)
		)
		(pad "2" thru_hole circle
			(at -0.4445 0 90)
			(size 0.508 0.508)
			(drill 0.254)
			(layers "*.Cu" "*.Mask")
			(remove_unused_layers no)
			(net "PCIE_IOM_TO_COMP_20_DP")
			(clearance 0.127)
			(thermal_gap 0.127)
		)
		(pad "3" thru_hole circle
			(at 0.4445 0 90)
			(size 0.508 0.508)
			(drill 0.254)
			(layers "*.Cu" "*.Mask")
			(remove_unused_layers no)
			(net "PCIE_IOM_TO_COMP_20_DN")
			(clearance 0.127)
			(thermal_gap 0.127)
		)
		(pad "4" thru_hole circle
			(at 1.4605 0 90)
			(size 0.508 0.508)
			(drill 0.254)
			(layers "*.Cu" "*.Mask")
			(remove_unused_layers no)
			(net "GND")
			(clearance 0.127)
			(thermal_gap 0.127)
		)
	)
	(footprint ""
		(layer "F.Cu")
		(at 47.8536 -128.1684 180)
		(property "Reference" "R88"
			(at 0 0 180)
			(layer "F.SilkS")
			(hide yes)
			(effects
				(font
					(size 1.27 1.27)
				)
			)
		)
		(property "Value" "100KR2F-L1-GP"
			(at 0.064008 -3.993896 180)
			(unlocked yes)
			(layer "F.Fab")
			(hide yes)
			(effects
				(font
					(size 1.016 1.016)
					(thickness 0.1524)
				)
			)
		)
		(property "Device Type" "R402H16"
			(at 0.064008 -5.517896 180)
			(unlocked yes)
			(layer "F.Fab")
			(hide yes)
			(effects
				(font
					(size 1.016 1.016)
					(thickness 0.1524)
				)
			)
		)
		(duplicate_pad_numbers_are_jumpers no)
		(fp_line
			(start 0.508 -0.9398)
			(end -0.508 -0.9398)
			(stroke
				(width 0.1524)
				(type default)
			)
			(layer "F.SilkS")
		)
		(fp_line
			(start -0.508 -0.9398)
			(end -0.508 0.9398)
			(stroke
				(width 0.1524)
				(type default)
			)
			(layer "F.SilkS")
		)
		(fp_rect
			(start -0.508 0.9398)
			(end 0.508 -0.9398)
			(stroke
				(width 0)
				(type default)
			)
			(fill no)
			(layer "F.CrtYd")
		)
		(fp_rect
			(start -0.508 0.9398)
			(end 0.508 -0.9398)
			(stroke
				(width 0)
				(type default)
			)
			(fill no)
			(layer "F.Fab")
		)
		(pad "1" smd custom
			(at 0 -0.4445 180)
			(size 0.1397 0.1397)
			(layers "F.Cu" "F.Mask" "F.Paste")
			(net "SCC_LOC_FULL_PWR_EN")
			(options
				(clearance outline)
				(anchor circle)
			)
			(primitives
				(gr_poly
					(pts
						(arc
							(start -0.1778 -0.2794)
							(mid -0.249642 -0.249642)
							(end -0.2794 -0.1778)
						)
						(arc
							(start -0.2794 0.1778)
							(mid -0.249642 0.249642)
							(end -0.1778 0.2794)
						)
						(arc
							(start 0.1778 0.2794)
							(mid 0.249642 0.249642)
							(end 0.2794 0.1778)
						)
						(arc
							(start 0.2794 -0.1778)
							(mid 0.249642 -0.249642)
							(end 0.1778 -0.2794)
						)
					)
					(width 0)
					(fill yes)
				)
			)
		)
		(pad "2" smd custom
			(at 0 0.4445 180)
			(size 0.1397 0.1397)
			(layers "F.Cu" "F.Mask" "F.Paste")
			(net "GND")
			(options
				(clearance outline)
				(anchor circle)
			)
			(primitives
				(gr_poly
					(pts
						(arc
							(start -0.1778 -0.2794)
							(mid -0.249642 -0.249642)
							(end -0.2794 -0.1778)
						)
						(arc
							(start -0.2794 0.1778)
							(mid -0.249642 0.249642)
							(end -0.1778 0.2794)
						)
						(arc
							(start 0.1778 0.2794)
							(mid 0.249642 0.249642)
							(end 0.2794 0.1778)
						)
						(arc
							(start 0.2794 -0.1778)
							(mid 0.249642 -0.249642)
							(end 0.1778 -0.2794)
						)
					)
					(width 0)
					(fill yes)
				)
			)
		)
	)
	(footprint ""
		(layer "F.Cu")
		(at 94.488 -16.256 180)
		(property "Reference" "D18"
			(at 0 0 180)
			(layer "F.SilkS")
			(hide yes)
			(effects
				(font
					(size 1.27 1.27)
				)
			)
		)
		(property "Value" "PESD5V0F1BL-GP"
			(at 1.8923 -1.5621 180)
			(unlocked yes)
			(layer "F.Fab")
			(hide yes)
			(effects
				(font
					(size 1.016 1.016)
					(thickness 0.1524)
				)
			)
		)
		(property "Device Type" "SOD882-10D6-1H20"
			(at 1.8923 -3.0861 180)
			(unlocked yes)
			(layer "F.Fab")
			(hide yes)
			(effects
				(font
					(size 1.016 1.016)
					(thickness 0.1524)
				)
			)
		)
		(duplicate_pad_numbers_are_jumpers no)
		(fp_line
			(start -0.3048 -0.9271)
			(end 0.3048 -0.9271)
			(stroke
				(width 0.254)
				(type default)
			)
			(layer "F.SilkS")
		)
		(fp_rect
			(start -0.2921 0.4953)
			(end 0.2921 -0.4953)
			(stroke
				(width 0)
				(type default)
			)
			(fill no)
			(layer "F.CrtYd")
		)
		(fp_poly
			(pts
				(xy -0.4318 0.8001) (xy -0.4318 -0.266192) (xy -0.2921 -0.266192) (xy -0.2921 0.4953) (xy 0.2921 0.4953)
				(xy 0.2921 -0.4953) (xy -0.2921 -0.4953) (xy -0.2921 -0.2667) (xy -0.4318 -0.2667) (xy -0.4318 -0.8001)
				(xy 0.4318 -0.8001) (xy 0.4318 0.8001)
			)
			(stroke
				(width 0)
				(type default)
			)
			(fill no)
			(layer "F.CrtYd")
		)
		(fp_rect
			(start -0.4318 0.8001)
			(end 0.4318 -0.8001)
			(stroke
				(width 0)
				(type default)
			)
			(fill no)
			(layer "F.Fab")
		)
		(pad "1" smd custom
			(at 0 -0.4445 180)
			(size 0.1143 0.1143)
			(layers "F.Cu" "F.Mask" "F.Paste")
			(net "GND")
			(options
				(clearance outline)
				(anchor circle)
			)
			(primitives
				(gr_poly
					(pts
						(arc
							(start -0.2032 0.2286)
							(mid -0.275042 0.198842)
							(end -0.3048 0.127)
						)
						(arc
							(start -0.3048 -0.127)
							(mid -0.275042 -0.198842)
							(end -0.2032 -0.2286)
						)
						(arc
							(start 0.2032 -0.2286)
							(mid 0.275042 -0.198842)
							(end 0.3048 -0.127)
						)
						(arc
							(start 0.3048 0.127)
							(mid 0.275042 0.198842)
							(end 0.2032 0.2286)
						)
					)
					(width 0)
					(fill yes)
				)
			)
		)
		(pad "2" smd custom
			(at 0 0.4445 180)
			(size 0.1143 0.1143)
			(layers "F.Cu" "F.Mask" "F.Paste")
			(net "USB_P1_F_DP1")
			(options
				(clearance outline)
				(anchor circle)
			)
			(primitives
				(gr_poly
					(pts
						(arc
							(start 0.2032 -0.2286)
							(mid 0.275042 -0.198842)
							(end 0.3048 -0.127)
						)
						(arc
							(start 0.3048 0.127)
							(mid 0.275042 0.198842)
							(end 0.2032 0.2286)
						)
						(arc
							(start -0.2032 0.2286)
							(mid -0.275042 0.198842)
							(end -0.3048 0.127)
						)
						(arc
							(start -0.3048 -0.127)
							(mid -0.275042 -0.198842)
							(end -0.2032 -0.2286)
						)
					)
					(width 0)
					(fill yes)
				)
			)
		)
	)
	(footprint ""
		(layer "F.Cu")
		(at 23.88108 -186.560714 180)
		(property "Reference" "C171"
			(at 0 0 180)
			(layer "F.SilkS")
			(hide yes)
			(effects
				(font
					(size 1.27 1.27)
				)
			)
		)
		(property "Value" "SC10U16V5KX-7-GP-U"
			(at -0.0762 -6.1214 180)
			(unlocked yes)
			(layer "F.Fab")
			(hide yes)
			(effects
				(font
					(size 1.016 1.016)
					(thickness 0.1524)
				)
			)
		)
		(property "Device Type" "C805H58"
			(at -0.0762 -8.1534 180)
			(unlocked yes)
			(layer "F.Fab")
			(hide yes)
			(effects
				(font
					(size 1.016 1.016)
					(thickness 0.1524)
				)
			)
		)
		(duplicate_pad_numbers_are_jumpers no)
		(fp_line
			(start 0.635 0)
			(end -0.635 0)
			(stroke
				(width 0.508)
				(type default)
			)
			(layer "F.SilkS")
		)
		(fp_rect
			(start -0.9652 1.778)
			(end 0.9652 -1.778)
			(stroke
				(width 0)
				(type default)
			)
			(fill no)
			(layer "F.CrtYd")
		)
		(fp_poly
			(pts
				(xy -0.9652 -1.778) (xy 0.9652 -1.778) (xy 0.9652 1.778) (xy -0.9652 1.778)
			)
			(stroke
				(width 0)
				(type default)
			)
			(fill no)
			(layer "F.Fab")
		)
		(pad "1" smd rect
			(at 0 -0.9652 180)
			(size 1.397 1.143)
			(layers "F.Cu" "F.Mask" "F.Paste")
			(net "P12V_STBY_VIN_PU2")
		)
		(pad "2" smd rect
			(at 0 0.9652 180)
			(size 1.397 1.143)
			(layers "F.Cu" "F.Mask" "F.Paste")
			(net "GND")
		)
	)
	(footprint ""
		(layer "F.Cu")
		(at 76.1746 -148.336 180)
		(property "Reference" "C75"
			(at 0 0 180)
			(layer "F.SilkS")
			(hide yes)
			(effects
				(font
					(size 1.27 1.27)
				)
			)
		)
		(property "Value" "SCD1U16V2KX-3GP"
			(at 1.1811 -2.7051 180)
			(unlocked yes)
			(layer "F.Fab")
			(hide yes)
			(effects
				(font
					(size 1.016 1.016)
					(thickness 0.1524)
				)
			)
		)
		(property "Device Type" "C402H22"
			(at 1.1811 -4.2291 180)
			(unlocked yes)
			(layer "F.Fab")
			(hide yes)
			(effects
				(font
					(size 1.016 1.016)
					(thickness 0.1524)
				)
			)
		)
		(duplicate_pad_numbers_are_jumpers no)
		(fp_rect
			(start -0.4318 0.9525)
			(end 0.4318 -0.9525)
			(stroke
				(width 0)
				(type default)
			)
			(fill no)
			(layer "F.CrtYd")
		)
		(fp_rect
			(start -0.4318 0.9525)
			(end 0.4318 -0.9525)
			(stroke
				(width 0)
				(type default)
			)
			(fill no)
			(layer "F.Fab")
		)
		(pad "1" smd custom
			(at 0 -0.4445 180)
			(size 0.1524 0.1524)
			(layers "F.Cu" "F.Mask" "F.Paste")
			(net "P3V3_STBY")
			(options
				(clearance outline)
				(anchor circle)
			)
			(primitives
				(gr_poly
					(pts
						(arc
							(start 0.3048 -0.2032)
							(mid 0.275042 -0.275042)
							(end 0.2032 -0.3048)
						)
						(arc
							(start -0.2032 -0.3048)
							(mid -0.275042 -0.275042)
							(end -0.3048 -0.2032)
						)
						(arc
							(start -0.3048 0.2032)
							(mid -0.275042 0.275042)
							(end -0.2032 0.3048)
						)
						(arc
							(start 0.2032 0.3048)
							(mid 0.275042 0.275042)
							(end 0.3048 0.2032)
						)
					)
					(width 0)
					(fill yes)
				)
			)
		)
		(pad "2" smd custom
			(at 0 0.4445 180)
			(size 0.1524 0.1524)
			(layers "F.Cu" "F.Mask" "F.Paste")
			(net "GND")
			(options
				(clearance outline)
				(anchor circle)
			)
			(primitives
				(gr_poly
					(pts
						(arc
							(start 0.3048 -0.2032)
							(mid 0.275042 -0.275042)
							(end 0.2032 -0.3048)
						)
						(arc
							(start -0.2032 -0.3048)
							(mid -0.275042 -0.275042)
							(end -0.3048 -0.2032)
						)
						(arc
							(start -0.3048 0.2032)
							(mid -0.275042 0.275042)
							(end -0.2032 0.3048)
						)
						(arc
							(start 0.2032 0.3048)
							(mid 0.275042 0.275042)
							(end 0.3048 0.2032)
						)
					)
					(width 0)
					(fill yes)
				)
			)
		)
	)
	(footprint ""
		(layer "F.Cu")
		(at 161.203894 -93.740224 180)
		(property "Reference" "R690"
			(at 0 0 180)
			(layer "F.SilkS")
			(hide yes)
			(effects
				(font
					(size 1.27 1.27)
				)
			)
		)
		(property "Value" "2K2R2F-GP"
			(at 0.064008 -3.993896 180)
			(unlocked yes)
			(layer "F.Fab")
			(hide yes)
			(effects
				(font
					(size 1.016 1.016)
					(thickness 0.1524)
				)
			)
		)
		(property "Device Type" "R402H16"
			(at 0.064008 -5.517896 180)
			(unlocked yes)
			(layer "F.Fab")
			(hide yes)
			(effects
				(font
					(size 1.016 1.016)
					(thickness 0.1524)
				)
			)
		)
		(duplicate_pad_numbers_are_jumpers no)
		(fp_line
			(start 0.508 -0.9398)
			(end -0.508 -0.9398)
			(stroke
				(width 0.1524)
				(type default)
			)
			(layer "F.SilkS")
		)
		(fp_line
			(start -0.508 -0.9398)
			(end -0.508 0.9398)
			(stroke
				(width 0.1524)
				(type default)
			)
			(layer "F.SilkS")
		)
		(fp_rect
			(start -0.508 0.9398)
			(end 0.508 -0.9398)
			(stroke
				(width 0)
				(type default)
			)
			(fill no)
			(layer "F.CrtYd")
		)
		(fp_rect
			(start -0.508 0.9398)
			(end 0.508 -0.9398)
			(stroke
				(width 0)
				(type default)
			)
			(fill no)
			(layer "F.Fab")
		)
		(pad "1" smd custom
			(at 0 -0.4445 180)
			(size 0.1397 0.1397)
			(layers "F.Cu" "F.Mask" "F.Paste")
			(net "I2C_IOC_SCL")
			(options
				(clearance outline)
				(anchor circle)
			)
			(primitives
				(gr_poly
					(pts
						(arc
							(start -0.1778 -0.2794)
							(mid -0.249642 -0.249642)
							(end -0.2794 -0.1778)
						)
						(arc
							(start -0.2794 0.1778)
							(mid -0.249642 0.249642)
							(end -0.1778 0.2794)
						)
						(arc
							(start 0.1778 0.2794)
							(mid 0.249642 0.249642)
							(end 0.2794 0.1778)
						)
						(arc
							(start 0.2794 -0.1778)
							(mid 0.249642 -0.249642)
							(end 0.1778 -0.2794)
						)
					)
					(width 0)
					(fill yes)
				)
			)
		)
		(pad "2" smd custom
			(at 0 0.4445 180)
			(size 0.1397 0.1397)
			(layers "F.Cu" "F.Mask" "F.Paste")
			(net "P3V3_STBY")
			(options
				(clearance outline)
				(anchor circle)
			)
			(primitives
				(gr_poly
					(pts
						(arc
							(start -0.1778 -0.2794)
							(mid -0.249642 -0.249642)
							(end -0.2794 -0.1778)
						)
						(arc
							(start -0.2794 0.1778)
							(mid -0.249642 0.249642)
							(end -0.1778 0.2794)
						)
						(arc
							(start 0.1778 0.2794)
							(mid 0.249642 0.249642)
							(end 0.2794 0.1778)
						)
						(arc
							(start 0.2794 -0.1778)
							(mid 0.249642 -0.249642)
							(end 0.1778 -0.2794)
						)
					)
					(width 0)
					(fill yes)
				)
			)
		)
	)
	(footprint ""
		(layer "F.Cu")
		(at 23.0759 -173.267116 90)
		(property "Reference" "C231"
			(at 0 0 90)
			(layer "F.SilkS")
			(hide yes)
			(effects
				(font
					(size 1.27 1.27)
				)
			)
		)
		(property "Value" "SC10U6D3V5KX-4GP"
			(at -0.0762 -6.1214 90)
			(unlocked yes)
			(layer "F.Fab")
			(hide yes)
			(effects
				(font
					(size 1.016 1.016)
					(thickness 0.1524)
				)
			)
		)
		(property "Device Type" "C805H58"
			(at -0.0762 -8.1534 90)
			(unlocked yes)
			(layer "F.Fab")
			(hide yes)
			(effects
				(font
					(size 1.016 1.016)
					(thickness 0.1524)
				)
			)
		)
		(duplicate_pad_numbers_are_jumpers no)
		(fp_line
			(start 0.635 0)
			(end -0.635 0)
			(stroke
				(width 0.508)
				(type default)
			)
			(layer "F.SilkS")
		)
		(fp_rect
			(start -0.9652 1.778)
			(end 0.9652 -1.778)
			(stroke
				(width 0)
				(type default)
			)
			(fill no)
			(layer "F.CrtYd")
		)
		(fp_poly
			(pts
				(xy -0.9652 -1.778) (xy 0.9652 -1.778) (xy 0.9652 1.778) (xy -0.9652 1.778)
			)
			(stroke
				(width 0)
				(type default)
			)
			(fill no)
			(layer "F.Fab")
		)
		(pad "1" smd rect
			(at 0 -0.9652 90)
			(size 1.397 1.143)
			(layers "F.Cu" "F.Mask" "F.Paste")
			(net "P1V8_STBY")
		)
		(pad "2" smd rect
			(at 0 0.9652 90)
			(size 1.397 1.143)
			(layers "F.Cu" "F.Mask" "F.Paste")
			(net "GND")
		)
	)
	(footprint ""
		(layer "F.Cu")
		(at 93.599 -150.3426 -90)
		(property "Reference" "TP5"
			(at 0 0 270)
			(layer "F.SilkS")
			(hide yes)
			(effects
				(font
					(size 1.27 1.27)
				)
			)
		)
		(property "Value" "TPAD28-2-GP"
			(at -0.0127 -1.6637 270)
			(unlocked yes)
			(layer "F.Fab")
			(hide yes)
			(effects
				(font
					(size 1.016 1.016)
					(thickness 0.1524)
				)
			)
		)
		(property "Device Type" "TPAD28"
			(at -0.0127 -3.1877 270)
			(unlocked yes)
			(layer "F.Fab")
			(hide yes)
			(effects
				(font
					(size 1.016 1.016)
					(thickness 0.1524)
				)
			)
		)
		(duplicate_pad_numbers_are_jumpers no)
		(fp_poly
			(pts
				(arc
					(start 0 -0.3556)
					(mid 0 0.3556)
					(end 0 -0.3556)
				)
			)
			(stroke
				(width 0)
				(type default)
			)
			(fill no)
			(layer "F.CrtYd")
		)
		(fp_poly
			(pts
				(arc
					(start 0 -0.6096)
					(mid 0 0.6096)
					(end 0 -0.6096)
				)
			)
			(stroke
				(width 0)
				(type default)
			)
			(fill no)
			(layer "F.Fab")
		)
		(pad "1" smd circle
			(at 0 0 270)
			(size 0.7112 0.7112)
			(layers "F.Cu" "F.Mask" "F.Paste")
			(net "CRFILT")
		)
	)
	(footprint ""
		(layer "F.Cu")
		(at 89.41562 -178.46548 -90)
		(property "Reference" "C136"
			(at 0 0 270)
			(layer "F.SilkS")
			(hide yes)
			(effects
				(font
					(size 1.27 1.27)
				)
			)
		)
		(property "Value" "SCD1U16V2KX-3GP"
			(at 1.1811 -2.7051 270)
			(unlocked yes)
			(layer "F.Fab")
			(hide yes)
			(effects
				(font
					(size 1.016 1.016)
					(thickness 0.1524)
				)
			)
		)
		(property "Device Type" "C402H22"
			(at 1.1811 -4.2291 270)
			(unlocked yes)
			(layer "F.Fab")
			(hide yes)
			(effects
				(font
					(size 1.016 1.016)
					(thickness 0.1524)
				)
			)
		)
		(duplicate_pad_numbers_are_jumpers no)
		(fp_rect
			(start -0.4318 0.9525)
			(end 0.4318 -0.9525)
			(stroke
				(width 0)
				(type default)
			)
			(fill no)
			(layer "F.CrtYd")
		)
		(fp_rect
			(start -0.4318 0.9525)
			(end 0.4318 -0.9525)
			(stroke
				(width 0)
				(type default)
			)
			(fill no)
			(layer "F.Fab")
		)
		(pad "1" smd custom
			(at 0 -0.4445 270)
			(size 0.1524 0.1524)
			(layers "F.Cu" "F.Mask" "F.Paste")
			(net "P3V3_STBY")
			(options
				(clearance outline)
				(anchor circle)
			)
			(primitives
				(gr_poly
					(pts
						(arc
							(start 0.3048 -0.2032)
							(mid 0.275042 -0.275042)
							(end 0.2032 -0.3048)
						)
						(arc
							(start -0.2032 -0.3048)
							(mid -0.275042 -0.275042)
							(end -0.3048 -0.2032)
						)
						(arc
							(start -0.3048 0.2032)
							(mid -0.275042 0.275042)
							(end -0.2032 0.3048)
						)
						(arc
							(start 0.2032 0.3048)
							(mid 0.275042 0.275042)
							(end 0.3048 0.2032)
						)
					)
					(width 0)
					(fill yes)
				)
			)
		)
		(pad "2" smd custom
			(at 0 0.4445 270)
			(size 0.1524 0.1524)
			(layers "F.Cu" "F.Mask" "F.Paste")
			(net "GND")
			(options
				(clearance outline)
				(anchor circle)
			)
			(primitives
				(gr_poly
					(pts
						(arc
							(start 0.3048 -0.2032)
							(mid 0.275042 -0.275042)
							(end 0.2032 -0.3048)
						)
						(arc
							(start -0.2032 -0.3048)
							(mid -0.275042 -0.275042)
							(end -0.3048 -0.2032)
						)
						(arc
							(start -0.3048 0.2032)
							(mid -0.275042 0.275042)
							(end -0.2032 0.3048)
						)
						(arc
							(start 0.2032 0.3048)
							(mid 0.275042 0.275042)
							(end 0.3048 0.2032)
						)
					)
					(width 0)
					(fill yes)
				)
			)
		)
	)
	(footprint ""
		(layer "F.Cu")
		(at 182.0291 -45.5422 180)
		(property "Reference" "R661"
			(at 0 0 180)
			(layer "F.SilkS")
			(hide yes)
			(effects
				(font
					(size 1.27 1.27)
				)
			)
		)
		(property "Value" "10KR2F-2-GP"
			(at 0.064008 -3.993896 180)
			(unlocked yes)
			(layer "F.Fab")
			(hide yes)
			(effects
				(font
					(size 1.016 1.016)
					(thickness 0.1524)
				)
			)
		)
		(property "Device Type" "R402H16"
			(at 0.064008 -5.517896 180)
			(unlocked yes)
			(layer "F.Fab")
			(hide yes)
			(effects
				(font
					(size 1.016 1.016)
					(thickness 0.1524)
				)
			)
		)
		(duplicate_pad_numbers_are_jumpers no)
		(fp_line
			(start 0.508 -0.9398)
			(end -0.508 -0.9398)
			(stroke
				(width 0.1524)
				(type default)
			)
			(layer "F.SilkS")
		)
		(fp_line
			(start -0.508 -0.9398)
			(end -0.508 0.9398)
			(stroke
				(width 0.1524)
				(type default)
			)
			(layer "F.SilkS")
		)
		(fp_rect
			(start -0.508 0.9398)
			(end 0.508 -0.9398)
			(stroke
				(width 0)
				(type default)
			)
			(fill no)
			(layer "F.CrtYd")
		)
		(fp_rect
			(start -0.508 0.9398)
			(end 0.508 -0.9398)
			(stroke
				(width 0)
				(type default)
			)
			(fill no)
			(layer "F.Fab")
		)
		(pad "1" smd custom
			(at 0 -0.4445 180)
			(size 0.1397 0.1397)
			(layers "F.Cu" "F.Mask" "F.Paste")
			(net "P1V8")
			(options
				(clearance outline)
				(anchor circle)
			)
			(primitives
				(gr_poly
					(pts
						(arc
							(start -0.1778 -0.2794)
							(mid -0.249642 -0.249642)
							(end -0.2794 -0.1778)
						)
						(arc
							(start -0.2794 0.1778)
							(mid -0.249642 0.249642)
							(end -0.1778 0.2794)
						)
						(arc
							(start 0.1778 0.2794)
							(mid 0.249642 0.249642)
							(end 0.2794 0.1778)
						)
						(arc
							(start 0.2794 -0.1778)
							(mid 0.249642 -0.249642)
							(end 0.1778 -0.2794)
						)
					)
					(width 0)
					(fill yes)
				)
			)
		)
		(pad "2" smd custom
			(at 0 0.4445 180)
			(size 0.1397 0.1397)
			(layers "F.Cu" "F.Mask" "F.Paste")
			(net "XM_ADDR_4")
			(options
				(clearance outline)
				(anchor circle)
			)
			(primitives
				(gr_poly
					(pts
						(arc
							(start -0.1778 -0.2794)
							(mid -0.249642 -0.249642)
							(end -0.2794 -0.1778)
						)
						(arc
							(start -0.2794 0.1778)
							(mid -0.249642 0.249642)
							(end -0.1778 0.2794)
						)
						(arc
							(start 0.1778 0.2794)
							(mid 0.249642 0.249642)
							(end 0.2794 0.1778)
						)
						(arc
							(start 0.2794 -0.1778)
							(mid 0.249642 -0.249642)
							(end 0.1778 -0.2794)
						)
					)
					(width 0)
					(fill yes)
				)
			)
		)
	)
	(footprint ""
		(layer "F.Cu")
		(at 168.6306 -105.029 -90)
		(property "Reference" "C462"
			(at 0 0 270)
			(layer "F.SilkS")
			(hide yes)
			(effects
				(font
					(size 1.27 1.27)
				)
			)
		)
		(property "Value" "SC1U16V2KX-7-GP"
			(at 1.7526 -1.6002 270)
			(unlocked yes)
			(layer "F.Fab")
			(hide yes)
			(effects
				(font
					(size 1.016 1.016)
					(thickness 0.1524)
				)
			)
		)
		(property "Device Type" "C402-TO0D2H24"
			(at 1.7526 -3.1242 270)
			(unlocked yes)
			(layer "F.Fab")
			(hide yes)
			(effects
				(font
					(size 1.016 1.016)
					(thickness 0.1524)
				)
			)
		)
		(duplicate_pad_numbers_are_jumpers no)
		(fp_rect
			(start -0.4826 0.889)
			(end 0.4826 -0.889)
			(stroke
				(width 0)
				(type default)
			)
			(fill no)
			(layer "F.CrtYd")
		)
		(fp_rect
			(start -0.4826 0.889)
			(end 0.4826 -0.889)
			(stroke
				(width 0)
				(type default)
			)
			(fill no)
			(layer "F.Fab")
		)
		(pad "1" smd custom
			(at 0 -0.4572 270)
			(size 0.1524 0.1524)
			(layers "F.Cu" "F.Mask" "F.Paste")
			(net "P1V8")
			(options
				(clearance outline)
				(anchor circle)
			)
			(primitives
				(gr_poly
					(pts
						(arc
							(start -0.254 0.3048)
							(mid -0.325842 0.275042)
							(end -0.3556 0.2032)
						)
						(arc
							(start -0.3556 -0.2032)
							(mid -0.325842 -0.275042)
							(end -0.254 -0.3048)
						)
						(arc
							(start 0.254 -0.3048)
							(mid 0.325842 -0.275042)
							(end 0.3556 -0.2032)
						)
						(arc
							(start 0.3556 0.2032)
							(mid 0.325842 0.275042)
							(end 0.254 0.3048)
						)
					)
					(width 0)
					(fill yes)
				)
			)
		)
		(pad "2" smd custom
			(at 0 0.4572 270)
			(size 0.1524 0.1524)
			(layers "F.Cu" "F.Mask" "F.Paste")
			(net "GND")
			(options
				(clearance outline)
				(anchor circle)
			)
			(primitives
				(gr_poly
					(pts
						(arc
							(start -0.254 0.3048)
							(mid -0.325842 0.275042)
							(end -0.3556 0.2032)
						)
						(arc
							(start -0.3556 -0.2032)
							(mid -0.325842 -0.275042)
							(end -0.254 -0.3048)
						)
						(arc
							(start 0.254 -0.3048)
							(mid 0.325842 -0.275042)
							(end 0.3556 -0.2032)
						)
						(arc
							(start 0.3556 0.2032)
							(mid 0.325842 0.275042)
							(end 0.254 0.3048)
						)
					)
					(width 0)
					(fill yes)
				)
			)
		)
	)
	(footprint ""
		(layer "F.Cu")
		(at 171.831 -124.333 -90)
		(property "Reference" "Q7"
			(at 0 0 270)
			(layer "F.SilkS")
			(hide yes)
			(effects
				(font
					(size 1.27 1.27)
				)
			)
		)
		(property "Value" "2N7002K-1-GP"
			(at 0.127 -8.9662 270)
			(unlocked yes)
			(layer "F.Fab")
			(hide yes)
			(effects
				(font
					(size 1.016 1.016)
					(thickness 0.1524)
				)
			)
		)
		(property "Device Type" "SOT23DGS2D4H44"
			(at 0.127 -10.4902 270)
			(unlocked yes)
			(layer "F.Fab")
			(hide yes)
			(effects
				(font
					(size 1.016 1.016)
					(thickness 0.1524)
				)
			)
		)
		(duplicate_pad_numbers_are_jumpers no)
		(fp_line
			(start -1.651 1.778)
			(end 1.651 1.778)
			(stroke
				(width 0.1524)
				(type default)
			)
			(layer "F.SilkS")
		)
		(fp_line
			(start 1.651 1.778)
			(end 1.651 -1.778)
			(stroke
				(width 0.1524)
				(type default)
			)
			(layer "F.SilkS")
		)
		(fp_line
			(start -1.651 -1.778)
			(end -1.651 1.778)
			(stroke
				(width 0.1524)
				(type default)
			)
			(layer "F.SilkS")
		)
		(fp_line
			(start 1.651 -1.778)
			(end -1.651 -1.778)
			(stroke
				(width 0.1524)
				(type default)
			)
			(layer "F.SilkS")
		)
		(fp_poly
			(pts
				(xy -1.778 1.8796) (xy -1.778 -1.8796) (xy 1.778 -1.8796) (xy 1.778 1.8796)
			)
			(stroke
				(width 0)
				(type default)
			)
			(fill no)
			(layer "F.CrtYd")
		)
		(fp_poly
			(pts
				(xy -1.778 1.8796) (xy -1.778 -1.8796) (xy 1.778 -1.8796) (xy 1.778 1.8796)
			)
			(stroke
				(width 0)
				(type default)
			)
			(fill no)
			(layer "F.Fab")
		)
		(pad "D" smd custom
			(at 0 -0.9525 270)
			(size 0.1905 0.1905)
			(layers "F.Cu" "F.Mask" "F.Paste")
			(net "Q6_G")
			(options
				(clearance outline)
				(anchor circle)
			)
			(primitives
				(gr_poly
					(pts
						(arc
							(start -0.1778 0.5715)
							(mid -0.321484 0.511984)
							(end -0.381 0.3683)
						)
						(arc
							(start -0.381 -0.3683)
							(mid -0.321484 -0.511984)
							(end -0.1778 -0.5715)
						)
						(arc
							(start 0.1778 -0.5715)
							(mid 0.321484 -0.511984)
							(end 0.381 -0.3683)
						)
						(arc
							(start 0.381 0.3683)
							(mid 0.321484 0.511984)
							(end 0.1778 0.5715)
						)
					)
					(width 0)
					(fill yes)
				)
			)
		)
		(pad "G" smd custom
			(at -0.98425 0.9525 270)
			(size 0.1905 0.1905)
			(layers "F.Cu" "F.Mask" "F.Paste")
			(net "Q7_G")
			(options
				(clearance outline)
				(anchor circle)
			)
			(primitives
				(gr_poly
					(pts
						(arc
							(start -0.1778 0.5715)
							(mid -0.321484 0.511984)
							(end -0.381 0.3683)
						)
						(arc
							(start -0.381 -0.3683)
							(mid -0.321484 -0.511984)
							(end -0.1778 -0.5715)
						)
						(arc
							(start 0.1778 -0.5715)
							(mid 0.321484 -0.511984)
							(end 0.381 -0.3683)
						)
						(arc
							(start 0.381 0.3683)
							(mid 0.321484 0.511984)
							(end 0.1778 0.5715)
						)
					)
					(width 0)
					(fill yes)
				)
			)
		)
		(pad "S" smd custom
			(at 0.98425 0.9525 270)
			(size 0.1905 0.1905)
			(layers "F.Cu" "F.Mask" "F.Paste")
			(net "GND")
			(options
				(clearance outline)
				(anchor circle)
			)
			(primitives
				(gr_poly
					(pts
						(arc
							(start -0.1778 0.5715)
							(mid -0.321484 0.511984)
							(end -0.381 0.3683)
						)
						(arc
							(start -0.381 -0.3683)
							(mid -0.321484 -0.511984)
							(end -0.1778 -0.5715)
						)
						(arc
							(start 0.1778 -0.5715)
							(mid 0.321484 -0.511984)
							(end 0.381 -0.3683)
						)
						(arc
							(start 0.381 0.3683)
							(mid 0.321484 0.511984)
							(end 0.1778 0.5715)
						)
					)
					(width 0)
					(fill yes)
				)
			)
		)
	)
	(footprint ""
		(layer "F.Cu")
		(at 49.022 -128.1938 180)
		(property "Reference" "R287"
			(at 0 0 180)
			(layer "F.SilkS")
			(hide yes)
			(effects
				(font
					(size 1.27 1.27)
				)
			)
		)
		(property "Value" "0R2J-2-GP"
			(at 0.064008 -3.993896 180)
			(unlocked yes)
			(layer "F.Fab")
			(hide yes)
			(effects
				(font
					(size 1.016 1.016)
					(thickness 0.1524)
				)
			)
		)
		(property "Device Type" "R402H16"
			(at 0.064008 -5.517896 180)
			(unlocked yes)
			(layer "F.Fab")
			(hide yes)
			(effects
				(font
					(size 1.016 1.016)
					(thickness 0.1524)
				)
			)
		)
		(duplicate_pad_numbers_are_jumpers no)
		(fp_line
			(start 0.508 -0.9398)
			(end -0.508 -0.9398)
			(stroke
				(width 0.1524)
				(type default)
			)
			(layer "F.SilkS")
		)
		(fp_line
			(start -0.508 -0.9398)
			(end -0.508 0.9398)
			(stroke
				(width 0.1524)
				(type default)
			)
			(layer "F.SilkS")
		)
		(fp_rect
			(start -0.508 0.9398)
			(end 0.508 -0.9398)
			(stroke
				(width 0)
				(type default)
			)
			(fill no)
			(layer "F.CrtYd")
		)
		(fp_rect
			(start -0.508 0.9398)
			(end 0.508 -0.9398)
			(stroke
				(width 0)
				(type default)
			)
			(fill no)
			(layer "F.Fab")
		)
		(pad "1" smd custom
			(at 0 -0.4445 180)
			(size 0.1397 0.1397)
			(layers "F.Cu" "F.Mask" "F.Paste")
			(net "SCC_RMT_FULL_PWR_EN")
			(options
				(clearance outline)
				(anchor circle)
			)
			(primitives
				(gr_poly
					(pts
						(arc
							(start -0.1778 -0.2794)
							(mid -0.249642 -0.249642)
							(end -0.2794 -0.1778)
						)
						(arc
							(start -0.2794 0.1778)
							(mid -0.249642 0.249642)
							(end -0.1778 0.2794)
						)
						(arc
							(start 0.1778 0.2794)
							(mid 0.249642 0.249642)
							(end 0.2794 0.1778)
						)
						(arc
							(start 0.2794 -0.1778)
							(mid 0.249642 -0.249642)
							(end 0.1778 -0.2794)
						)
					)
					(width 0)
					(fill yes)
				)
			)
		)
		(pad "2" smd custom
			(at 0 0.4445 180)
			(size 0.1397 0.1397)
			(layers "F.Cu" "F.Mask" "F.Paste")
			(net "SCC_RMT_FULLPWR_EN")
			(options
				(clearance outline)
				(anchor circle)
			)
			(primitives
				(gr_poly
					(pts
						(arc
							(start -0.1778 -0.2794)
							(mid -0.249642 -0.249642)
							(end -0.2794 -0.1778)
						)
						(arc
							(start -0.2794 0.1778)
							(mid -0.249642 0.249642)
							(end -0.1778 0.2794)
						)
						(arc
							(start 0.1778 0.2794)
							(mid 0.249642 0.249642)
							(end 0.2794 0.1778)
						)
						(arc
							(start 0.2794 -0.1778)
							(mid 0.249642 -0.249642)
							(end 0.1778 -0.2794)
						)
					)
					(width 0)
					(fill yes)
				)
			)
		)
	)
	(footprint ""
		(layer "F.Cu")
		(at 10.796524 -138.144504 90)
		(property "Reference" "R230"
			(at 0 0 90)
			(layer "F.SilkS")
			(hide yes)
			(effects
				(font
					(size 1.27 1.27)
				)
			)
		)
		(property "Value" "120R2F-GP"
			(at 0.064008 -3.993896 90)
			(unlocked yes)
			(layer "F.Fab")
			(hide yes)
			(effects
				(font
					(size 1.016 1.016)
					(thickness 0.1524)
				)
			)
		)
		(property "Device Type" "R402H16"
			(at 0.064008 -5.517896 90)
			(unlocked yes)
			(layer "F.Fab")
			(hide yes)
			(effects
				(font
					(size 1.016 1.016)
					(thickness 0.1524)
				)
			)
		)
		(duplicate_pad_numbers_are_jumpers no)
		(fp_line
			(start 0.508 -0.9398)
			(end -0.508 -0.9398)
			(stroke
				(width 0.1524)
				(type default)
			)
			(layer "F.SilkS")
		)
		(fp_line
			(start -0.508 -0.9398)
			(end -0.508 0.9398)
			(stroke
				(width 0.1524)
				(type default)
			)
			(layer "F.SilkS")
		)
		(fp_rect
			(start -0.508 0.9398)
			(end 0.508 -0.9398)
			(stroke
				(width 0)
				(type default)
			)
			(fill no)
			(layer "F.CrtYd")
		)
		(fp_rect
			(start -0.508 0.9398)
			(end 0.508 -0.9398)
			(stroke
				(width 0)
				(type default)
			)
			(fill no)
			(layer "F.Fab")
		)
		(pad "1" smd custom
			(at 0 -0.4445 90)
			(size 0.1397 0.1397)
			(layers "F.Cu" "F.Mask" "F.Paste")
			(net "MEMBA_0")
			(options
				(clearance outline)
				(anchor circle)
			)
			(primitives
				(gr_poly
					(pts
						(arc
							(start -0.1778 -0.2794)
							(mid -0.249642 -0.249642)
							(end -0.2794 -0.1778)
						)
						(arc
							(start -0.2794 0.1778)
							(mid -0.249642 0.249642)
							(end -0.1778 0.2794)
						)
						(arc
							(start 0.1778 0.2794)
							(mid 0.249642 0.249642)
							(end 0.2794 0.1778)
						)
						(arc
							(start 0.2794 -0.1778)
							(mid 0.249642 -0.249642)
							(end 0.1778 -0.2794)
						)
					)
					(width 0)
					(fill yes)
				)
			)
		)
		(pad "2" smd custom
			(at 0 0.4445 90)
			(size 0.1397 0.1397)
			(layers "F.Cu" "F.Mask" "F.Paste")
			(net "P1V2_STBY")
			(options
				(clearance outline)
				(anchor circle)
			)
			(primitives
				(gr_poly
					(pts
						(arc
							(start -0.1778 -0.2794)
							(mid -0.249642 -0.249642)
							(end -0.2794 -0.1778)
						)
						(arc
							(start -0.2794 0.1778)
							(mid -0.249642 0.249642)
							(end -0.1778 0.2794)
						)
						(arc
							(start 0.1778 0.2794)
							(mid 0.249642 0.249642)
							(end 0.2794 0.1778)
						)
						(arc
							(start 0.2794 -0.1778)
							(mid 0.249642 -0.249642)
							(end 0.1778 -0.2794)
						)
					)
					(width 0)
					(fill yes)
				)
			)
		)
	)
	(footprint ""
		(layer "F.Cu")
		(at 11.5824 -167.8178 90)
		(property "Reference" "C228"
			(at 0 0 90)
			(layer "F.SilkS")
			(hide yes)
			(effects
				(font
					(size 1.27 1.27)
				)
			)
		)
		(property "Value" "SC470P50V2KX-3GP"
			(at 1.1811 -2.7051 90)
			(unlocked yes)
			(layer "F.Fab")
			(hide yes)
			(effects
				(font
					(size 1.016 1.016)
					(thickness 0.1524)
				)
			)
		)
		(property "Device Type" "C402H22"
			(at 1.1811 -4.2291 90)
			(unlocked yes)
			(layer "F.Fab")
			(hide yes)
			(effects
				(font
					(size 1.016 1.016)
					(thickness 0.1524)
				)
			)
		)
		(duplicate_pad_numbers_are_jumpers no)
		(fp_rect
			(start -0.4318 0.9525)
			(end 0.4318 -0.9525)
			(stroke
				(width 0)
				(type default)
			)
			(fill no)
			(layer "F.CrtYd")
		)
		(fp_rect
			(start -0.4318 0.9525)
			(end 0.4318 -0.9525)
			(stroke
				(width 0)
				(type default)
			)
			(fill no)
			(layer "F.Fab")
		)
		(pad "1" smd custom
			(at 0 -0.4445 90)
			(size 0.1524 0.1524)
			(layers "F.Cu" "F.Mask" "F.Paste")
			(net "GND")
			(options
				(clearance outline)
				(anchor circle)
			)
			(primitives
				(gr_poly
					(pts
						(arc
							(start 0.3048 -0.2032)
							(mid 0.275042 -0.275042)
							(end 0.2032 -0.3048)
						)
						(arc
							(start -0.2032 -0.3048)
							(mid -0.275042 -0.275042)
							(end -0.3048 -0.2032)
						)
						(arc
							(start -0.3048 0.2032)
							(mid -0.275042 0.275042)
							(end -0.2032 0.3048)
						)
						(arc
							(start 0.2032 0.3048)
							(mid 0.275042 0.275042)
							(end 0.3048 0.2032)
						)
					)
					(width 0)
					(fill yes)
				)
			)
		)
		(pad "2" smd custom
			(at 0 0.4445 90)
			(size 0.1524 0.1524)
			(layers "F.Cu" "F.Mask" "F.Paste")
			(net "TPS74801_P1V2_STBY_SS")
			(options
				(clearance outline)
				(anchor circle)
			)
			(primitives
				(gr_poly
					(pts
						(arc
							(start 0.3048 -0.2032)
							(mid 0.275042 -0.275042)
							(end 0.2032 -0.3048)
						)
						(arc
							(start -0.2032 -0.3048)
							(mid -0.275042 -0.275042)
							(end -0.3048 -0.2032)
						)
						(arc
							(start -0.3048 0.2032)
							(mid -0.275042 0.275042)
							(end -0.2032 0.3048)
						)
						(arc
							(start 0.2032 0.3048)
							(mid 0.275042 0.275042)
							(end 0.3048 0.2032)
						)
					)
					(width 0)
					(fill yes)
				)
			)
		)
	)
	(footprint ""
		(layer "F.Cu")
		(at 88.647016 -46.05782 180)
		(property "Reference" "R10"
			(at 0 0 180)
			(layer "F.SilkS")
			(hide yes)
			(effects
				(font
					(size 1.27 1.27)
				)
			)
		)
		(property "Value" "0R2J-2-GP"
			(at 0.064008 -3.993896 180)
			(unlocked yes)
			(layer "F.Fab")
			(hide yes)
			(effects
				(font
					(size 1.016 1.016)
					(thickness 0.1524)
				)
			)
		)
		(property "Device Type" "R402H16"
			(at 0.064008 -5.517896 180)
			(unlocked yes)
			(layer "F.Fab")
			(hide yes)
			(effects
				(font
					(size 1.016 1.016)
					(thickness 0.1524)
				)
			)
		)
		(duplicate_pad_numbers_are_jumpers no)
		(fp_line
			(start 0.508 -0.9398)
			(end -0.508 -0.9398)
			(stroke
				(width 0.1524)
				(type default)
			)
			(layer "F.SilkS")
		)
		(fp_line
			(start -0.508 -0.9398)
			(end -0.508 0.9398)
			(stroke
				(width 0.1524)
				(type default)
			)
			(layer "F.SilkS")
		)
		(fp_rect
			(start -0.508 0.9398)
			(end 0.508 -0.9398)
			(stroke
				(width 0)
				(type default)
			)
			(fill no)
			(layer "F.CrtYd")
		)
		(fp_rect
			(start -0.508 0.9398)
			(end 0.508 -0.9398)
			(stroke
				(width 0)
				(type default)
			)
			(fill no)
			(layer "F.Fab")
		)
		(pad "1" smd custom
			(at 0 -0.4445 180)
			(size 0.1397 0.1397)
			(layers "F.Cu" "F.Mask" "F.Paste")
			(net "MEZZA_PRSNT1_N")
			(options
				(clearance outline)
				(anchor circle)
			)
			(primitives
				(gr_poly
					(pts
						(arc
							(start -0.1778 -0.2794)
							(mid -0.249642 -0.249642)
							(end -0.2794 -0.1778)
						)
						(arc
							(start -0.2794 0.1778)
							(mid -0.249642 0.249642)
							(end -0.1778 0.2794)
						)
						(arc
							(start 0.1778 0.2794)
							(mid 0.249642 0.249642)
							(end 0.2794 0.1778)
						)
						(arc
							(start 0.2794 -0.1778)
							(mid 0.249642 -0.249642)
							(end 0.1778 -0.2794)
						)
					)
					(width 0)
					(fill yes)
				)
			)
		)
		(pad "2" smd custom
			(at 0 0.4445 180)
			(size 0.1397 0.1397)
			(layers "F.Cu" "F.Mask" "F.Paste")
			(net "GND")
			(options
				(clearance outline)
				(anchor circle)
			)
			(primitives
				(gr_poly
					(pts
						(arc
							(start -0.1778 -0.2794)
							(mid -0.249642 -0.249642)
							(end -0.2794 -0.1778)
						)
						(arc
							(start -0.2794 0.1778)
							(mid -0.249642 0.249642)
							(end -0.1778 0.2794)
						)
						(arc
							(start 0.1778 0.2794)
							(mid 0.249642 0.249642)
							(end 0.2794 0.1778)
						)
						(arc
							(start 0.2794 -0.1778)
							(mid 0.249642 -0.249642)
							(end 0.1778 -0.2794)
						)
					)
					(width 0)
					(fill yes)
				)
			)
		)
	)
	(footprint ""
		(layer "F.Cu")
		(at 32.6898 -134.6962 90)
		(property "Reference" "R369"
			(at 0 0 90)
			(layer "F.SilkS")
			(hide yes)
			(effects
				(font
					(size 1.27 1.27)
				)
			)
		)
		(property "Value" "4K7R2F-GP"
			(at 0.064008 -3.993896 90)
			(unlocked yes)
			(layer "F.Fab")
			(hide yes)
			(effects
				(font
					(size 1.016 1.016)
					(thickness 0.1524)
				)
			)
		)
		(property "Device Type" "R402H16"
			(at 0.064008 -5.517896 90)
			(unlocked yes)
			(layer "F.Fab")
			(hide yes)
			(effects
				(font
					(size 1.016 1.016)
					(thickness 0.1524)
				)
			)
		)
		(duplicate_pad_numbers_are_jumpers no)
		(fp_line
			(start 0.508 -0.9398)
			(end -0.508 -0.9398)
			(stroke
				(width 0.1524)
				(type default)
			)
			(layer "F.SilkS")
		)
		(fp_line
			(start -0.508 -0.9398)
			(end -0.508 0.9398)
			(stroke
				(width 0.1524)
				(type default)
			)
			(layer "F.SilkS")
		)
		(fp_rect
			(start -0.508 0.9398)
			(end 0.508 -0.9398)
			(stroke
				(width 0)
				(type default)
			)
			(fill no)
			(layer "F.CrtYd")
		)
		(fp_rect
			(start -0.508 0.9398)
			(end 0.508 -0.9398)
			(stroke
				(width 0)
				(type default)
			)
			(fill no)
			(layer "F.Fab")
		)
		(pad "1" smd custom
			(at 0 -0.4445 90)
			(size 0.1397 0.1397)
			(layers "F.Cu" "F.Mask" "F.Paste")
			(net "P3V3_STBY")
			(options
				(clearance outline)
				(anchor circle)
			)
			(primitives
				(gr_poly
					(pts
						(arc
							(start -0.1778 -0.2794)
							(mid -0.249642 -0.249642)
							(end -0.2794 -0.1778)
						)
						(arc
							(start -0.2794 0.1778)
							(mid -0.249642 0.249642)
							(end -0.1778 0.2794)
						)
						(arc
							(start 0.1778 0.2794)
							(mid 0.249642 0.249642)
							(end 0.2794 0.1778)
						)
						(arc
							(start 0.2794 -0.1778)
							(mid 0.249642 -0.249642)
							(end 0.1778 -0.2794)
						)
					)
					(width 0)
					(fill yes)
				)
			)
		)
		(pad "2" smd custom
			(at 0 0.4445 90)
			(size 0.1397 0.1397)
			(layers "F.Cu" "F.Mask" "F.Paste")
			(net "BMC_SPI_CLK")
			(options
				(clearance outline)
				(anchor circle)
			)
			(primitives
				(gr_poly
					(pts
						(arc
							(start -0.1778 -0.2794)
							(mid -0.249642 -0.249642)
							(end -0.2794 -0.1778)
						)
						(arc
							(start -0.2794 0.1778)
							(mid -0.249642 0.249642)
							(end -0.1778 0.2794)
						)
						(arc
							(start 0.1778 0.2794)
							(mid 0.249642 0.249642)
							(end 0.2794 0.1778)
						)
						(arc
							(start 0.2794 -0.1778)
							(mid 0.249642 -0.249642)
							(end 0.1778 -0.2794)
						)
					)
					(width 0)
					(fill yes)
				)
			)
		)
	)
	(footprint ""
		(layer "F.Cu")
		(at 184.829704 -149.714966 180)
		(property "Reference" "C163"
			(at 0 0 180)
			(layer "F.SilkS")
			(hide yes)
			(effects
				(font
					(size 1.27 1.27)
				)
			)
		)
		(property "Value" "SC68P50V2JN-2-GP"
			(at 1.1811 -2.7051 180)
			(unlocked yes)
			(layer "F.Fab")
			(hide yes)
			(effects
				(font
					(size 1.016 1.016)
					(thickness 0.1524)
				)
			)
		)
		(property "Device Type" "C402H22"
			(at 1.1811 -4.2291 180)
			(unlocked yes)
			(layer "F.Fab")
			(hide yes)
			(effects
				(font
					(size 1.016 1.016)
					(thickness 0.1524)
				)
			)
		)
		(duplicate_pad_numbers_are_jumpers no)
		(fp_rect
			(start -0.4318 0.9525)
			(end 0.4318 -0.9525)
			(stroke
				(width 0)
				(type default)
			)
			(fill no)
			(layer "F.CrtYd")
		)
		(fp_rect
			(start -0.4318 0.9525)
			(end 0.4318 -0.9525)
			(stroke
				(width 0)
				(type default)
			)
			(fill no)
			(layer "F.Fab")
		)
		(pad "1" smd custom
			(at 0 -0.4445 180)
			(size 0.1524 0.1524)
			(layers "F.Cu" "F.Mask" "F.Paste")
			(net "P5V_VFB")
			(options
				(clearance outline)
				(anchor circle)
			)
			(primitives
				(gr_poly
					(pts
						(arc
							(start 0.3048 -0.2032)
							(mid 0.275042 -0.275042)
							(end 0.2032 -0.3048)
						)
						(arc
							(start -0.2032 -0.3048)
							(mid -0.275042 -0.275042)
							(end -0.3048 -0.2032)
						)
						(arc
							(start -0.3048 0.2032)
							(mid -0.275042 0.275042)
							(end -0.2032 0.3048)
						)
						(arc
							(start 0.2032 0.3048)
							(mid 0.275042 0.275042)
							(end 0.3048 0.2032)
						)
					)
					(width 0)
					(fill yes)
				)
			)
		)
		(pad "2" smd custom
			(at 0 0.4445 180)
			(size 0.1524 0.1524)
			(layers "F.Cu" "F.Mask" "F.Paste")
			(net "P5V_VFB_R")
			(options
				(clearance outline)
				(anchor circle)
			)
			(primitives
				(gr_poly
					(pts
						(arc
							(start 0.3048 -0.2032)
							(mid 0.275042 -0.275042)
							(end 0.2032 -0.3048)
						)
						(arc
							(start -0.2032 -0.3048)
							(mid -0.275042 -0.275042)
							(end -0.3048 -0.2032)
						)
						(arc
							(start -0.3048 0.2032)
							(mid -0.275042 0.275042)
							(end -0.2032 0.3048)
						)
						(arc
							(start 0.2032 0.3048)
							(mid 0.275042 0.275042)
							(end 0.3048 0.2032)
						)
					)
					(width 0)
					(fill yes)
				)
			)
		)
	)
	(footprint ""
		(layer "F.Cu")
		(at 188.2902 -48.387)
		(property "Reference" "R657"
			(at 0 0 0)
			(layer "F.SilkS")
			(hide yes)
			(effects
				(font
					(size 1.27 1.27)
				)
			)
		)
		(property "Value" "10KR2F-2-GP"
			(at 0.064008 -3.993896 0)
			(unlocked yes)
			(layer "F.Fab")
			(hide yes)
			(effects
				(font
					(size 1.016 1.016)
					(thickness 0.1524)
				)
			)
		)
		(property "Device Type" "R402H16"
			(at 0.064008 -5.517896 0)
			(unlocked yes)
			(layer "F.Fab")
			(hide yes)
			(effects
				(font
					(size 1.016 1.016)
					(thickness 0.1524)
				)
			)
		)
		(duplicate_pad_numbers_are_jumpers no)
		(fp_line
			(start -0.508 -0.9398)
			(end -0.508 0.9398)
			(stroke
				(width 0.1524)
				(type default)
			)
			(layer "F.SilkS")
		)
		(fp_line
			(start 0.508 -0.9398)
			(end -0.508 -0.9398)
			(stroke
				(width 0.1524)
				(type default)
			)
			(layer "F.SilkS")
		)
		(fp_rect
			(start -0.508 0.9398)
			(end 0.508 -0.9398)
			(stroke
				(width 0)
				(type default)
			)
			(fill no)
			(layer "F.CrtYd")
		)
		(fp_rect
			(start -0.508 0.9398)
			(end 0.508 -0.9398)
			(stroke
				(width 0)
				(type default)
			)
			(fill no)
			(layer "F.Fab")
		)
		(pad "1" smd custom
			(at 0 -0.4445)
			(size 0.1397 0.1397)
			(layers "F.Cu" "F.Mask" "F.Paste")
			(net "LSI_IDDT")
			(options
				(clearance outline)
				(anchor circle)
			)
			(primitives
				(gr_poly
					(pts
						(arc
							(start -0.1778 -0.2794)
							(mid -0.249642 -0.249642)
							(end -0.2794 -0.1778)
						)
						(arc
							(start -0.2794 0.1778)
							(mid -0.249642 0.249642)
							(end -0.1778 0.2794)
						)
						(arc
							(start 0.1778 0.2794)
							(mid 0.249642 0.249642)
							(end 0.2794 0.1778)
						)
						(arc
							(start 0.2794 -0.1778)
							(mid 0.249642 -0.249642)
							(end 0.1778 -0.2794)
						)
					)
					(width 0)
					(fill yes)
				)
			)
		)
		(pad "2" smd custom
			(at 0 0.4445)
			(size 0.1397 0.1397)
			(layers "F.Cu" "F.Mask" "F.Paste")
			(net "GND")
			(options
				(clearance outline)
				(anchor circle)
			)
			(primitives
				(gr_poly
					(pts
						(arc
							(start -0.1778 -0.2794)
							(mid -0.249642 -0.249642)
							(end -0.2794 -0.1778)
						)
						(arc
							(start -0.2794 0.1778)
							(mid -0.249642 0.249642)
							(end -0.1778 0.2794)
						)
						(arc
							(start 0.1778 0.2794)
							(mid 0.249642 0.249642)
							(end 0.2794 0.1778)
						)
						(arc
							(start 0.2794 -0.1778)
							(mid 0.249642 -0.249642)
							(end 0.1778 -0.2794)
						)
					)
					(width 0)
					(fill yes)
				)
			)
		)
	)
	(footprint ""
		(layer "F.Cu")
		(at 18.2372 -174.9298 180)
		(property "Reference" "C229"
			(at 0 0 180)
			(layer "F.SilkS")
			(hide yes)
			(effects
				(font
					(size 1.27 1.27)
				)
			)
		)
		(property "Value" "SC1U16V3KX-5GP"
			(at 0 -2.8194 180)
			(unlocked yes)
			(layer "F.Fab")
			(hide yes)
			(effects
				(font
					(size 1.016 1.016)
					(thickness 0.1524)
				)
			)
		)
		(property "Device Type" "C603H36"
			(at 0 -4.3434 180)
			(unlocked yes)
			(layer "F.Fab")
			(hide yes)
			(effects
				(font
					(size 1.016 1.016)
					(thickness 0.1524)
				)
			)
		)
		(duplicate_pad_numbers_are_jumpers no)
		(fp_line
			(start 0.508 0)
			(end -0.508 0)
			(stroke
				(width 0.2032)
				(type default)
			)
			(layer "F.SilkS")
		)
		(fp_rect
			(start -0.5842 1.3335)
			(end 0.5842 -1.3335)
			(stroke
				(width 0)
				(type default)
			)
			(fill no)
			(layer "F.CrtYd")
		)
		(fp_rect
			(start -0.5842 1.3335)
			(end 0.5842 -1.3335)
			(stroke
				(width 0)
				(type default)
			)
			(fill no)
			(layer "F.Fab")
		)
		(pad "1" smd custom
			(at 0 -0.762 180)
			(size 0.2159 0.2159)
			(layers "F.Cu" "F.Mask" "F.Paste")
			(net "TPS74801_P1V2_STBY_BIAS")
			(options
				(clearance outline)
				(anchor circle)
			)
			(primitives
				(gr_poly
					(pts
						(arc
							(start -0.3302 -0.4318)
							(mid -0.402042 -0.402042)
							(end -0.4318 -0.3302)
						)
						(arc
							(start -0.4318 0.3302)
							(mid -0.402042 0.402042)
							(end -0.3302 0.4318)
						)
						(arc
							(start 0.3302 0.4318)
							(mid 0.402042 0.402042)
							(end 0.4318 0.3302)
						)
						(arc
							(start 0.4318 -0.3302)
							(mid 0.402042 -0.402042)
							(end 0.3302 -0.4318)
						)
					)
					(width 0)
					(fill yes)
				)
			)
		)
		(pad "2" smd custom
			(at 0 0.762 180)
			(size 0.2159 0.2159)
			(layers "F.Cu" "F.Mask" "F.Paste")
			(net "GND")
			(options
				(clearance outline)
				(anchor circle)
			)
			(primitives
				(gr_poly
					(pts
						(arc
							(start -0.3302 -0.4318)
							(mid -0.402042 -0.402042)
							(end -0.4318 -0.3302)
						)
						(arc
							(start -0.4318 0.3302)
							(mid -0.402042 0.402042)
							(end -0.3302 0.4318)
						)
						(arc
							(start 0.3302 0.4318)
							(mid 0.402042 0.402042)
							(end 0.4318 0.3302)
						)
						(arc
							(start 0.4318 -0.3302)
							(mid 0.402042 -0.402042)
							(end 0.3302 -0.4318)
						)
					)
					(width 0)
					(fill yes)
				)
			)
		)
	)
	(footprint ""
		(layer "F.Cu")
		(at 86.599268 -134.677404)
		(property "Reference" "R134"
			(at 0 0 0)
			(layer "F.SilkS")
			(hide yes)
			(effects
				(font
					(size 1.27 1.27)
				)
			)
		)
		(property "Value" "8K2R2J-3-GP"
			(at 0.064008 -3.993896 0)
			(unlocked yes)
			(layer "F.Fab")
			(hide yes)
			(effects
				(font
					(size 1.016 1.016)
					(thickness 0.1524)
				)
			)
		)
		(property "Device Type" "R402H16"
			(at 0.064008 -5.517896 0)
			(unlocked yes)
			(layer "F.Fab")
			(hide yes)
			(effects
				(font
					(size 1.016 1.016)
					(thickness 0.1524)
				)
			)
		)
		(duplicate_pad_numbers_are_jumpers no)
		(fp_line
			(start -0.508 -0.9398)
			(end -0.508 0.9398)
			(stroke
				(width 0.1524)
				(type default)
			)
			(layer "F.SilkS")
		)
		(fp_line
			(start 0.508 -0.9398)
			(end -0.508 -0.9398)
			(stroke
				(width 0.1524)
				(type default)
			)
			(layer "F.SilkS")
		)
		(fp_rect
			(start -0.508 0.9398)
			(end 0.508 -0.9398)
			(stroke
				(width 0)
				(type default)
			)
			(fill no)
			(layer "F.CrtYd")
		)
		(fp_rect
			(start -0.508 0.9398)
			(end 0.508 -0.9398)
			(stroke
				(width 0)
				(type default)
			)
			(fill no)
			(layer "F.Fab")
		)
		(pad "1" smd custom
			(at 0 -0.4445)
			(size 0.1397 0.1397)
			(layers "F.Cu" "F.Mask" "F.Paste")
			(net "P3V3_STBY")
			(options
				(clearance outline)
				(anchor circle)
			)
			(primitives
				(gr_poly
					(pts
						(arc
							(start -0.1778 -0.2794)
							(mid -0.249642 -0.249642)
							(end -0.2794 -0.1778)
						)
						(arc
							(start -0.2794 0.1778)
							(mid -0.249642 0.249642)
							(end -0.1778 0.2794)
						)
						(arc
							(start 0.1778 0.2794)
							(mid 0.249642 0.249642)
							(end 0.2794 0.1778)
						)
						(arc
							(start 0.2794 -0.1778)
							(mid 0.249642 -0.249642)
							(end 0.1778 -0.2794)
						)
					)
					(width 0)
					(fill yes)
				)
			)
		)
		(pad "2" smd custom
			(at 0 0.4445)
			(size 0.1397 0.1397)
			(layers "F.Cu" "F.Mask" "F.Paste")
			(net "EEPROM_A1")
			(options
				(clearance outline)
				(anchor circle)
			)
			(primitives
				(gr_poly
					(pts
						(arc
							(start -0.1778 -0.2794)
							(mid -0.249642 -0.249642)
							(end -0.2794 -0.1778)
						)
						(arc
							(start -0.2794 0.1778)
							(mid -0.249642 0.249642)
							(end -0.1778 0.2794)
						)
						(arc
							(start 0.1778 0.2794)
							(mid 0.249642 0.249642)
							(end 0.2794 0.1778)
						)
						(arc
							(start 0.2794 -0.1778)
							(mid 0.249642 -0.249642)
							(end 0.1778 -0.2794)
						)
					)
					(width 0)
					(fill yes)
				)
			)
		)
	)
	(footprint ""
		(layer "F.Cu")
		(at 201.5236 -85.7758 135)
		(property "Reference" "VIA18"
			(at 0 0 135)
			(layer "F.SilkS")
			(hide yes)
			(effects
				(font
					(size 1.27 1.27)
				)
			)
		)
		(property "Value" "85OHM-8L-1D6MM-L16L18-GP"
			(at 4.064105 0.609655 135)
			(unlocked yes)
			(layer "F.Fab")
			(hide yes)
			(effects
				(font
					(size 1.016 1.016)
					(thickness 0.1524)
				)
			)
		)
		(property "Device Type" "VIA-PCIE-4P-368076"
			(at 4.064105 -0.914474 135)
			(unlocked yes)
			(layer "F.Fab")
			(hide yes)
			(effects
				(font
					(size 1.016 1.016)
					(thickness 0.1524)
				)
			)
		)
		(duplicate_pad_numbers_are_jumpers no)
		(fp_poly
			(pts
				(xy -1.841491 -0.381057) (xy 1.841509 -0.381058) (xy 1.841508 0.380942) (xy -1.841491 0.380942)
			)
			(stroke
				(width 0)
				(type default)
			)
			(fill no)
			(layer "F.CrtYd")
		)
		(fp_poly
			(pts
				(xy -1.841491 -0.381057) (xy 1.841509 -0.381058) (xy 1.841508 0.380942) (xy -1.841491 0.380942)
			)
			(stroke
				(width 0)
				(type default)
			)
			(fill no)
			(layer "F.Fab")
		)
		(pad "1" thru_hole circle
			(at -1.460499 0 135)
			(size 0.508 0.508)
			(drill 0.254)
			(layers "*.Cu" "*.Mask")
			(remove_unused_layers no)
			(net "GND")
			(clearance 0.127)
			(thermal_gap 0.127)
		)
		(pad "2" thru_hole circle
			(at -0.4445 0 135)
			(size 0.508 0.508)
			(drill 0.254)
			(layers "*.Cu" "*.Mask")
			(remove_unused_layers no)
			(net "PCIE_COMP_TO_IOM_9_DP")
			(clearance 0.127)
			(thermal_gap 0.127)
		)
		(pad "3" thru_hole circle
			(at 0.4445 0 135)
			(size 0.508 0.508)
			(drill 0.254)
			(layers "*.Cu" "*.Mask")
			(remove_unused_layers no)
			(net "PCIE_COMP_TO_IOM_9_DN")
			(clearance 0.127)
			(thermal_gap 0.127)
		)
		(pad "4" thru_hole circle
			(at 1.460499 0 135)
			(size 0.508 0.508)
			(drill 0.254)
			(layers "*.Cu" "*.Mask")
			(remove_unused_layers no)
			(net "GND")
			(clearance 0.127)
			(thermal_gap 0.127)
		)
	)
	(footprint ""
		(layer "F.Cu")
		(at 169.1894 -171.0436 -90)
		(property "Reference" "C168"
			(at 0 0 270)
			(layer "F.SilkS")
			(hide yes)
			(effects
				(font
					(size 1.27 1.27)
				)
			)
		)
		(property "Value" "ST150U16VDM-3-GP"
			(at 0 -9.6012 270)
			(unlocked yes)
			(layer "F.Fab")
			(hide yes)
			(effects
				(font
					(size 1.016 1.016)
					(thickness 0.1524)
				)
			)
		)
		(property "Device Type" "CT7343H119"
			(at 0 -11.1252 270)
			(unlocked yes)
			(layer "F.Fab")
			(hide yes)
			(effects
				(font
					(size 1.016 1.016)
					(thickness 0.1524)
				)
			)
		)
		(duplicate_pad_numbers_are_jumpers no)
		(fp_line
			(start -2.286 4.8768)
			(end -2.286 2.032)
			(stroke
				(width 0.1524)
				(type default)
			)
			(layer "F.SilkS")
		)
		(fp_line
			(start 2.286 4.8768)
			(end -2.286 4.8768)
			(stroke
				(width 0.1524)
				(type default)
			)
			(layer "F.SilkS")
		)
		(fp_line
			(start 2.286 2.032)
			(end 2.286 4.8768)
			(stroke
				(width 0.1524)
				(type default)
			)
			(layer "F.SilkS")
		)
		(fp_line
			(start 2.286 -2.032)
			(end 2.286 -4.8768)
			(stroke
				(width 0.1524)
				(type default)
			)
			(layer "F.SilkS")
		)
		(fp_line
			(start 2.1082 -4.699)
			(end -2.1082 -4.699)
			(stroke
				(width 0.508)
				(type default)
			)
			(layer "F.SilkS")
		)
		(fp_line
			(start -2.286 -4.8768)
			(end -2.286 -2.032)
			(stroke
				(width 0.1524)
				(type default)
			)
			(layer "F.SilkS")
		)
		(fp_line
			(start 2.286 -4.8768)
			(end -2.286 -4.8768)
			(stroke
				(width 0.1524)
				(type default)
			)
			(layer "F.SilkS")
		)
		(fp_rect
			(start -2.1463 3.6449)
			(end 2.1463 -3.6449)
			(stroke
				(width 0)
				(type default)
			)
			(fill no)
			(layer "F.CrtYd")
		)
		(fp_poly
			(pts
				(xy -2.54 4.953) (xy -2.54 4.2926) (xy -3.81 4.2926) (xy -3.81 -4.2926) (xy -2.54 -4.2926) (xy -2.54 -4.953)
				(xy 2.54 -4.953) (xy 2.54 -4.2926) (xy 3.81 -4.2926) (xy 3.81 -1.6256) (xy 2.1463 -1.6256) (xy 2.1463 -3.6449)
				(xy -2.1463 -3.6449) (xy -2.1463 3.6449) (xy 2.1463 3.6449) (xy 2.1463 -1.6129) (xy 3.81 -1.6129)
				(xy 3.81 4.2926) (xy 2.54 4.2926) (xy 2.54 4.953)
			)
			(stroke
				(width 0)
				(type default)
			)
			(fill no)
			(layer "F.CrtYd")
		)
		(fp_rect
			(start -2.54 4.953)
			(end 2.54 -4.953)
			(stroke
				(width 0)
				(type default)
			)
			(fill no)
			(layer "F.Fab")
		)
		(fp_rect
			(start -3.81 4.2926)
			(end -2.54 -4.2926)
			(stroke
				(width 0)
				(type default)
			)
			(fill no)
			(layer "F.Fab")
		)
		(fp_rect
			(start 2.54 4.2926)
			(end 3.81 -4.2926)
			(stroke
				(width 0)
				(type default)
			)
			(fill no)
			(layer "F.Fab")
		)
		(pad "1" smd rect
			(at 0 -3.1496 270)
			(size 2.413 2.286)
			(layers "F.Cu" "F.Mask" "F.Paste")
			(net "P5V_STBY")
		)
		(pad "2" smd rect
			(at 0 3.1496 270)
			(size 2.413 2.286)
			(layers "F.Cu" "F.Mask" "F.Paste")
			(net "GND")
		)
		(zone
			(layer "F.Cu")
			(hatch none 0.5)
			(connect_pads
				(clearance 0)
			)
			(min_thickness 0.25)
			(keepout
				(tracks allowed)
				(vias not_allowed)
				(pads allowed)
				(copperpour not_allowed)
				(footprints allowed)
			)
			(placement
				(enabled no)
				(sheetname "")
			)
			(fill
				(thermal_gap 0.5)
				(thermal_bridge_width 0.5)
				(island_removal_mode 0)
			)
			(polygon
				(pts
					(xy 164.592 -172.5549) (xy 164.592 -169.5323) (xy 167.4876 -169.5323) (xy 167.8178 -169.5323) (xy 167.8178 -172.5549)
					(xy 167.4876 -172.5549)
				)
			)
		)
		(zone
			(layer "F.Cu")
			(hatch none 0.5)
			(connect_pads
				(clearance 0)
			)
			(min_thickness 0.25)
			(keepout
				(tracks allowed)
				(vias not_allowed)
				(pads allowed)
				(copperpour not_allowed)
				(footprints allowed)
			)
			(placement
				(enabled no)
				(sheetname "")
			)
			(fill
				(thermal_gap 0.5)
				(thermal_bridge_width 0.5)
				(island_removal_mode 0)
			)
			(polygon
				(pts
					(xy 170.8785 -169.5323) (xy 173.7868 -169.5323) (xy 173.7868 -172.5549) (xy 170.8912 -172.5549)
					(xy 170.561 -172.5549) (xy 170.561 -169.5323)
				)
			)
		)
	)
	(footprint ""
		(layer "F.Cu")
		(at 92.33154 -173.73092 -90)
		(property "Reference" "U107"
			(at 0 0 270)
			(layer "F.SilkS")
			(hide yes)
			(effects
				(font
					(size 1.27 1.27)
				)
			)
		)
		(property "Value" "SN74CBTLV3245APWR-GP"
			(at -0.889 -6.2738 270)
			(unlocked yes)
			(layer "F.Fab")
			(hide yes)
			(effects
				(font
					(size 1.016 1.016)
					(thickness 0.1524)
				)
			)
		)
		(property "Device Type" "TSOIC20H48"
			(at -0.9144 -7.8994 270)
			(unlocked yes)
			(layer "F.Fab")
			(hide yes)
			(effects
				(font
					(size 1.016 1.016)
					(thickness 0.1524)
				)
			)
		)
		(duplicate_pad_numbers_are_jumpers no)
		(fp_line
			(start -3.556 4.064)
			(end -3.556 1.778)
			(stroke
				(width 0.508)
				(type default)
			)
			(layer "F.SilkS")
		)
		(fp_line
			(start -3.556 1.397)
			(end -3.556 1.778)
			(stroke
				(width 0.2032)
				(type default)
			)
			(layer "F.SilkS")
		)
		(fp_line
			(start 3.175 1.397)
			(end -3.556 1.397)
			(stroke
				(width 0.2032)
				(type default)
			)
			(layer "F.SilkS")
		)
		(fp_line
			(start -2.667 0)
			(end -3.556 0.889)
			(stroke
				(width 0.2032)
				(type default)
			)
			(layer "F.SilkS")
		)
		(fp_line
			(start -2.667 0)
			(end -3.556 -0.889)
			(stroke
				(width 0.2032)
				(type default)
			)
			(layer "F.SilkS")
		)
		(fp_line
			(start -3.556 -1.397)
			(end -3.556 4.064)
			(stroke
				(width 0.2032)
				(type default)
			)
			(layer "F.SilkS")
		)
		(fp_line
			(start -3.556 -1.397)
			(end 3.175 -1.397)
			(stroke
				(width 0.2032)
				(type default)
			)
			(layer "F.SilkS")
		)
		(fp_line
			(start 3.175 -1.397)
			(end 3.175 1.397)
			(stroke
				(width 0.2032)
				(type default)
			)
			(layer "F.SilkS")
		)
		(fp_poly
			(pts
				(xy -3.25628 -1.8542) (xy 3.25628 -1.8542) (xy 3.25628 1.8542) (xy -3.25628 1.8542)
			)
			(stroke
				(width 0)
				(type default)
			)
			(fill yes)
			(layer "F.SilkS")
		)
		(fp_rect
			(start -3.556 3.81)
			(end 3.556 -3.81)
			(stroke
				(width 0)
				(type default)
			)
			(fill no)
			(layer "F.CrtYd")
		)
		(fp_poly
			(pts
				(xy -3.556 -3.81) (xy 3.556 -3.81) (xy 3.556 3.81) (xy -3.556 3.81)
			)
			(stroke
				(width 0)
				(type default)
			)
			(fill no)
			(layer "F.Fab")
		)
		(pad "1" smd rect
			(at -2.92608 2.8194 270)
			(size 0.3556 1.524)
			(layers "F.Cu" "F.Mask" "F.Paste")
			(net "Net_131")
		)
		(pad "2" smd rect
			(at -2.27584 2.8194 270)
			(size 0.3556 1.524)
			(layers "F.Cu" "F.Mask" "F.Paste")
			(net "Net_77")
		)
		(pad "3" smd rect
			(at -1.6256 2.8194 270)
			(size 0.3556 1.524)
			(layers "F.Cu" "F.Mask" "F.Paste")
			(net "Net_79")
		)
		(pad "4" smd rect
			(at -0.97536 2.8194 270)
			(size 0.3556 1.524)
			(layers "F.Cu" "F.Mask" "F.Paste")
			(net "Net_75")
		)
		(pad "5" smd rect
			(at -0.32512 2.8194 270)
			(size 0.3556 1.524)
			(layers "F.Cu" "F.Mask" "F.Paste")
			(net "I2C_DPB_MISC_SCL_OUT")
		)
		(pad "6" smd rect
			(at 0.32512 2.8194 270)
			(size 0.3556 1.524)
			(layers "F.Cu" "F.Mask" "F.Paste")
			(net "I2C_DPB_MISC_SDA_OUT")
		)
		(pad "7" smd rect
			(at 0.97536 2.8194 270)
			(size 0.3556 1.524)
			(layers "F.Cu" "F.Mask" "F.Paste")
			(net "DPB_MISC_ALERT")
		)
		(pad "8" smd rect
			(at 1.6256 2.8194 270)
			(size 0.3556 1.524)
			(layers "F.Cu" "F.Mask" "F.Paste")
			(net "Net_130")
		)
		(pad "9" smd rect
			(at 2.27584 2.8194 270)
			(size 0.3556 1.524)
			(layers "F.Cu" "F.Mask" "F.Paste")
			(net "Net_129")
		)
		(pad "10" smd rect
			(at 2.92608 2.8194 270)
			(size 0.3556 1.524)
			(layers "F.Cu" "F.Mask" "F.Paste")
			(net "GND")
		)
		(pad "11" smd rect
			(at 2.92608 -2.8194 270)
			(size 0.3556 1.524)
			(layers "F.Cu" "F.Mask" "F.Paste")
			(net "Net_128")
		)
		(pad "12" smd rect
			(at 2.27584 -2.8194 270)
			(size 0.3556 1.524)
			(layers "F.Cu" "F.Mask" "F.Paste")
			(net "Net_127")
		)
		(pad "13" smd rect
			(at 1.6256 -2.8194 270)
			(size 0.3556 1.524)
			(layers "F.Cu" "F.Mask" "F.Paste")
			(net "DPB_MISC_ALERT_OUT_R")
		)
		(pad "14" smd rect
			(at 0.97536 -2.8194 270)
			(size 0.3556 1.524)
			(layers "F.Cu" "F.Mask" "F.Paste")
			(net "I2C_DPB_MISC_SDA_R")
		)
		(pad "15" smd rect
			(at 0.32512 -2.8194 270)
			(size 0.3556 1.524)
			(layers "F.Cu" "F.Mask" "F.Paste")
			(net "I2C_DPB_MISC_SCL_R")
		)
		(pad "16" smd rect
			(at -0.32512 -2.8194 270)
			(size 0.3556 1.524)
			(layers "F.Cu" "F.Mask" "F.Paste")
			(net "Net_80")
		)
		(pad "17" smd rect
			(at -0.97536 -2.8194 270)
			(size 0.3556 1.524)
			(layers "F.Cu" "F.Mask" "F.Paste")
			(net "Net_78")
		)
		(pad "18" smd rect
			(at -1.6256 -2.8194 270)
			(size 0.3556 1.524)
			(layers "F.Cu" "F.Mask" "F.Paste")
			(net "Net_76")
		)
		(pad "19" smd rect
			(at -2.27584 -2.8194 270)
			(size 0.3556 1.524)
			(layers "F.Cu" "F.Mask" "F.Paste")
			(net "PWRGD_P3V3_STBY_N_R2")
		)
		(pad "20" smd rect
			(at -2.92608 -2.8194 270)
			(size 0.3556 1.524)
			(layers "F.Cu" "F.Mask" "F.Paste")
			(net "P3V3_STBY")
		)
	)
	(footprint ""
		(layer "F.Cu")
		(at 14.73454 -12.90574 180)
		(property "Reference" "R47"
			(at 0 0 180)
			(layer "F.SilkS")
			(hide yes)
			(effects
				(font
					(size 1.27 1.27)
				)
			)
		)
		(property "Value" "1MR2F-GP"
			(at 0.064008 -3.993896 180)
			(unlocked yes)
			(layer "F.Fab")
			(hide yes)
			(effects
				(font
					(size 1.016 1.016)
					(thickness 0.1524)
				)
			)
		)
		(property "Device Type" "R402H16"
			(at 0.064008 -5.517896 180)
			(unlocked yes)
			(layer "F.Fab")
			(hide yes)
			(effects
				(font
					(size 1.016 1.016)
					(thickness 0.1524)
				)
			)
		)
		(duplicate_pad_numbers_are_jumpers no)
		(fp_line
			(start 0.508 -0.9398)
			(end -0.508 -0.9398)
			(stroke
				(width 0.1524)
				(type default)
			)
			(layer "F.SilkS")
		)
		(fp_line
			(start -0.508 -0.9398)
			(end -0.508 0.9398)
			(stroke
				(width 0.1524)
				(type default)
			)
			(layer "F.SilkS")
		)
		(fp_rect
			(start -0.508 0.9398)
			(end 0.508 -0.9398)
			(stroke
				(width 0)
				(type default)
			)
			(fill no)
			(layer "F.CrtYd")
		)
		(fp_rect
			(start -0.508 0.9398)
			(end 0.508 -0.9398)
			(stroke
				(width 0)
				(type default)
			)
			(fill no)
			(layer "F.Fab")
		)
		(pad "1" smd custom
			(at 0 -0.4445 180)
			(size 0.1397 0.1397)
			(layers "F.Cu" "F.Mask" "F.Paste")
			(net "RST_BTN_GND")
			(options
				(clearance outline)
				(anchor circle)
			)
			(primitives
				(gr_poly
					(pts
						(arc
							(start -0.1778 -0.2794)
							(mid -0.249642 -0.249642)
							(end -0.2794 -0.1778)
						)
						(arc
							(start -0.2794 0.1778)
							(mid -0.249642 0.249642)
							(end -0.1778 0.2794)
						)
						(arc
							(start 0.1778 0.2794)
							(mid 0.249642 0.249642)
							(end 0.2794 0.1778)
						)
						(arc
							(start 0.2794 -0.1778)
							(mid 0.249642 -0.249642)
							(end 0.1778 -0.2794)
						)
					)
					(width 0)
					(fill yes)
				)
			)
		)
		(pad "2" smd custom
			(at 0 0.4445 180)
			(size 0.1397 0.1397)
			(layers "F.Cu" "F.Mask" "F.Paste")
			(net "GND")
			(options
				(clearance outline)
				(anchor circle)
			)
			(primitives
				(gr_poly
					(pts
						(arc
							(start -0.1778 -0.2794)
							(mid -0.249642 -0.249642)
							(end -0.2794 -0.1778)
						)
						(arc
							(start -0.2794 0.1778)
							(mid -0.249642 0.249642)
							(end -0.1778 0.2794)
						)
						(arc
							(start 0.1778 0.2794)
							(mid 0.249642 0.249642)
							(end 0.2794 0.1778)
						)
						(arc
							(start 0.2794 -0.1778)
							(mid 0.249642 -0.249642)
							(end 0.1778 -0.2794)
						)
					)
					(width 0)
					(fill yes)
				)
			)
		)
	)
	(footprint ""
		(layer "F.Cu")
		(at 72.04964 -164.5793 90)
		(property "Reference" "R541"
			(at 0 0 90)
			(layer "F.SilkS")
			(hide yes)
			(effects
				(font
					(size 1.27 1.27)
				)
			)
		)
		(property "Value" "4K75R2F-1-GP"
			(at 0.064008 -3.993896 90)
			(unlocked yes)
			(layer "F.Fab")
			(hide yes)
			(effects
				(font
					(size 1.016 1.016)
					(thickness 0.1524)
				)
			)
		)
		(property "Device Type" "R402H16"
			(at 0.064008 -5.517896 90)
			(unlocked yes)
			(layer "F.Fab")
			(hide yes)
			(effects
				(font
					(size 1.016 1.016)
					(thickness 0.1524)
				)
			)
		)
		(duplicate_pad_numbers_are_jumpers no)
		(fp_line
			(start 0.508 -0.9398)
			(end -0.508 -0.9398)
			(stroke
				(width 0.1524)
				(type default)
			)
			(layer "F.SilkS")
		)
		(fp_line
			(start -0.508 -0.9398)
			(end -0.508 0.9398)
			(stroke
				(width 0.1524)
				(type default)
			)
			(layer "F.SilkS")
		)
		(fp_rect
			(start -0.508 0.9398)
			(end 0.508 -0.9398)
			(stroke
				(width 0)
				(type default)
			)
			(fill no)
			(layer "F.CrtYd")
		)
		(fp_rect
			(start -0.508 0.9398)
			(end 0.508 -0.9398)
			(stroke
				(width 0)
				(type default)
			)
			(fill no)
			(layer "F.Fab")
		)
		(pad "1" smd custom
			(at 0 -0.4445 90)
			(size 0.1397 0.1397)
			(layers "F.Cu" "F.Mask" "F.Paste")
			(net "P3V3_STBY")
			(options
				(clearance outline)
				(anchor circle)
			)
			(primitives
				(gr_poly
					(pts
						(arc
							(start -0.1778 -0.2794)
							(mid -0.249642 -0.249642)
							(end -0.2794 -0.1778)
						)
						(arc
							(start -0.2794 0.1778)
							(mid -0.249642 0.249642)
							(end -0.1778 0.2794)
						)
						(arc
							(start 0.1778 0.2794)
							(mid 0.249642 0.249642)
							(end 0.2794 0.1778)
						)
						(arc
							(start 0.2794 -0.1778)
							(mid 0.249642 -0.249642)
							(end 0.1778 -0.2794)
						)
					)
					(width 0)
					(fill yes)
				)
			)
		)
		(pad "2" smd custom
			(at 0 0.4445 90)
			(size 0.1397 0.1397)
			(layers "F.Cu" "F.Mask" "F.Paste")
			(net "TPS74801_P1V15_STBY_EN")
			(options
				(clearance outline)
				(anchor circle)
			)
			(primitives
				(gr_poly
					(pts
						(arc
							(start -0.1778 -0.2794)
							(mid -0.249642 -0.249642)
							(end -0.2794 -0.1778)
						)
						(arc
							(start -0.2794 0.1778)
							(mid -0.249642 0.249642)
							(end -0.1778 0.2794)
						)
						(arc
							(start 0.1778 0.2794)
							(mid 0.249642 0.249642)
							(end 0.2794 0.1778)
						)
						(arc
							(start 0.2794 -0.1778)
							(mid 0.249642 -0.249642)
							(end 0.1778 -0.2794)
						)
					)
					(width 0)
					(fill yes)
				)
			)
		)
	)
	(footprint ""
		(layer "F.Cu")
		(at 42.7482 -157.9626)
		(property "Reference" "TP187"
			(at 0 0 0)
			(layer "F.SilkS")
			(hide yes)
			(effects
				(font
					(size 1.27 1.27)
				)
			)
		)
		(property "Value" "TPAD28-2-GP"
			(at -0.0127 -1.6637 0)
			(unlocked yes)
			(layer "F.Fab")
			(hide yes)
			(effects
				(font
					(size 1.016 1.016)
					(thickness 0.1524)
				)
			)
		)
		(property "Device Type" "TPAD28"
			(at -0.0127 -3.1877 0)
			(unlocked yes)
			(layer "F.Fab")
			(hide yes)
			(effects
				(font
					(size 1.016 1.016)
					(thickness 0.1524)
				)
			)
		)
		(duplicate_pad_numbers_are_jumpers no)
		(fp_poly
			(pts
				(arc
					(start 0.3556 0)
					(mid -0.3556 0)
					(end 0.3556 0)
				)
			)
			(stroke
				(width 0)
				(type default)
			)
			(fill no)
			(layer "F.CrtYd")
		)
		(fp_poly
			(pts
				(arc
					(start 0.6096 0)
					(mid -0.6096 0)
					(end 0.6096 0)
				)
			)
			(stroke
				(width 0)
				(type default)
			)
			(fill no)
			(layer "F.Fab")
		)
		(pad "1" smd circle
			(at 0 0)
			(size 0.7112 0.7112)
			(layers "F.Cu" "F.Mask" "F.Paste")
			(net "TP_BMC_GPIOL1")
		)
	)
	(footprint ""
		(layer "F.Cu")
		(at 76.1746 -167.4114 180)
		(property "Reference" "C524"
			(at 0 0 180)
			(layer "F.SilkS")
			(hide yes)
			(effects
				(font
					(size 1.27 1.27)
				)
			)
		)
		(property "Value" "SC1U16V2KX-7-GP"
			(at 1.7526 -1.6002 180)
			(unlocked yes)
			(layer "F.Fab")
			(hide yes)
			(effects
				(font
					(size 1.016 1.016)
					(thickness 0.1524)
				)
			)
		)
		(property "Device Type" "C402-TO0D2H24"
			(at 1.7526 -3.1242 180)
			(unlocked yes)
			(layer "F.Fab")
			(hide yes)
			(effects
				(font
					(size 1.016 1.016)
					(thickness 0.1524)
				)
			)
		)
		(duplicate_pad_numbers_are_jumpers no)
		(fp_rect
			(start -0.4826 0.889)
			(end 0.4826 -0.889)
			(stroke
				(width 0)
				(type default)
			)
			(fill no)
			(layer "F.CrtYd")
		)
		(fp_rect
			(start -0.4826 0.889)
			(end 0.4826 -0.889)
			(stroke
				(width 0)
				(type default)
			)
			(fill no)
			(layer "F.Fab")
		)
		(pad "1" smd custom
			(at 0 -0.4572 180)
			(size 0.1524 0.1524)
			(layers "F.Cu" "F.Mask" "F.Paste")
			(net "P1V15_STBY_PG")
			(options
				(clearance outline)
				(anchor circle)
			)
			(primitives
				(gr_poly
					(pts
						(arc
							(start -0.254 0.3048)
							(mid -0.325842 0.275042)
							(end -0.3556 0.2032)
						)
						(arc
							(start -0.3556 -0.2032)
							(mid -0.325842 -0.275042)
							(end -0.254 -0.3048)
						)
						(arc
							(start 0.254 -0.3048)
							(mid 0.325842 -0.275042)
							(end 0.3556 -0.2032)
						)
						(arc
							(start 0.3556 0.2032)
							(mid 0.325842 0.275042)
							(end 0.254 0.3048)
						)
					)
					(width 0)
					(fill yes)
				)
			)
		)
		(pad "2" smd custom
			(at 0 0.4572 180)
			(size 0.1524 0.1524)
			(layers "F.Cu" "F.Mask" "F.Paste")
			(net "GND")
			(options
				(clearance outline)
				(anchor circle)
			)
			(primitives
				(gr_poly
					(pts
						(arc
							(start -0.254 0.3048)
							(mid -0.325842 0.275042)
							(end -0.3556 0.2032)
						)
						(arc
							(start -0.3556 -0.2032)
							(mid -0.325842 -0.275042)
							(end -0.254 -0.3048)
						)
						(arc
							(start 0.254 -0.3048)
							(mid 0.325842 -0.275042)
							(end 0.3556 -0.2032)
						)
						(arc
							(start 0.3556 0.2032)
							(mid 0.325842 0.275042)
							(end 0.254 0.3048)
						)
					)
					(width 0)
					(fill yes)
				)
			)
		)
	)
	(footprint ""
		(layer "F.Cu")
		(at 88.773 -130.0226 -90)
		(property "Reference" "R421"
			(at 0 0 270)
			(layer "F.SilkS")
			(hide yes)
			(effects
				(font
					(size 1.27 1.27)
				)
			)
		)
		(property "Value" "10KR2F-2-GP"
			(at 0.064008 -3.993896 270)
			(unlocked yes)
			(layer "F.Fab")
			(hide yes)
			(effects
				(font
					(size 1.016 1.016)
					(thickness 0.1524)
				)
			)
		)
		(property "Device Type" "R402H16"
			(at 0.064008 -5.517896 270)
			(unlocked yes)
			(layer "F.Fab")
			(hide yes)
			(effects
				(font
					(size 1.016 1.016)
					(thickness 0.1524)
				)
			)
		)
		(duplicate_pad_numbers_are_jumpers no)
		(fp_line
			(start -0.508 -0.9398)
			(end -0.508 0.9398)
			(stroke
				(width 0.1524)
				(type default)
			)
			(layer "F.SilkS")
		)
		(fp_line
			(start 0.508 -0.9398)
			(end -0.508 -0.9398)
			(stroke
				(width 0.1524)
				(type default)
			)
			(layer "F.SilkS")
		)
		(fp_rect
			(start -0.508 0.9398)
			(end 0.508 -0.9398)
			(stroke
				(width 0)
				(type default)
			)
			(fill no)
			(layer "F.CrtYd")
		)
		(fp_rect
			(start -0.508 0.9398)
			(end 0.508 -0.9398)
			(stroke
				(width 0)
				(type default)
			)
			(fill no)
			(layer "F.Fab")
		)
		(pad "1" smd custom
			(at 0 -0.4445 270)
			(size 0.1397 0.1397)
			(layers "F.Cu" "F.Mask" "F.Paste")
			(net "UART_SEL_MUX")
			(options
				(clearance outline)
				(anchor circle)
			)
			(primitives
				(gr_poly
					(pts
						(arc
							(start -0.1778 -0.2794)
							(mid -0.249642 -0.249642)
							(end -0.2794 -0.1778)
						)
						(arc
							(start -0.2794 0.1778)
							(mid -0.249642 0.249642)
							(end -0.1778 0.2794)
						)
						(arc
							(start 0.1778 0.2794)
							(mid 0.249642 0.249642)
							(end 0.2794 0.1778)
						)
						(arc
							(start 0.2794 -0.1778)
							(mid 0.249642 -0.249642)
							(end 0.1778 -0.2794)
						)
					)
					(width 0)
					(fill yes)
				)
			)
		)
		(pad "2" smd custom
			(at 0 0.4445 270)
			(size 0.1397 0.1397)
			(layers "F.Cu" "F.Mask" "F.Paste")
			(net "GND")
			(options
				(clearance outline)
				(anchor circle)
			)
			(primitives
				(gr_poly
					(pts
						(arc
							(start -0.1778 -0.2794)
							(mid -0.249642 -0.249642)
							(end -0.2794 -0.1778)
						)
						(arc
							(start -0.2794 0.1778)
							(mid -0.249642 0.249642)
							(end -0.1778 0.2794)
						)
						(arc
							(start 0.1778 0.2794)
							(mid 0.249642 0.249642)
							(end 0.2794 0.1778)
						)
						(arc
							(start 0.2794 -0.1778)
							(mid 0.249642 -0.249642)
							(end 0.1778 -0.2794)
						)
					)
					(width 0)
					(fill yes)
				)
			)
		)
	)
	(footprint ""
		(layer "F.Cu")
		(at 165.481 -133.858)
		(property "Reference" "C204"
			(at 0 0 0)
			(layer "F.SilkS")
			(hide yes)
			(effects
				(font
					(size 1.27 1.27)
				)
			)
		)
		(property "Value" "SC10U16V5KX-7-GP-U"
			(at -0.0762 -6.1214 0)
			(unlocked yes)
			(layer "F.Fab")
			(hide yes)
			(effects
				(font
					(size 1.016 1.016)
					(thickness 0.1524)
				)
			)
		)
		(property "Device Type" "C805H58"
			(at -0.0762 -8.1534 0)
			(unlocked yes)
			(layer "F.Fab")
			(hide yes)
			(effects
				(font
					(size 1.016 1.016)
					(thickness 0.1524)
				)
			)
		)
		(duplicate_pad_numbers_are_jumpers no)
		(fp_line
			(start 0.635 0)
			(end -0.635 0)
			(stroke
				(width 0.508)
				(type default)
			)
			(layer "F.SilkS")
		)
		(fp_rect
			(start -0.9652 1.778)
			(end 0.9652 -1.778)
			(stroke
				(width 0)
				(type default)
			)
			(fill no)
			(layer "F.CrtYd")
		)
		(fp_poly
			(pts
				(xy -0.9652 -1.778) (xy 0.9652 -1.778) (xy 0.9652 1.778) (xy -0.9652 1.778)
			)
			(stroke
				(width 0)
				(type default)
			)
			(fill no)
			(layer "F.Fab")
		)
		(pad "1" smd rect
			(at 0 -0.9652)
			(size 1.397 1.143)
			(layers "F.Cu" "F.Mask" "F.Paste")
			(net "P12V_STBY_VIN_PU4")
		)
		(pad "2" smd rect
			(at 0 0.9652)
			(size 1.397 1.143)
			(layers "F.Cu" "F.Mask" "F.Paste")
			(net "GND")
		)
	)
	(footprint ""
		(layer "F.Cu")
		(at 205.139036 -122.1486 90)
		(property "Reference" "R545"
			(at 0 0 90)
			(layer "F.SilkS")
			(hide yes)
			(effects
				(font
					(size 1.27 1.27)
				)
			)
		)
		(property "Value" "4K75R2F-1-GP"
			(at 0.064008 -3.993896 90)
			(unlocked yes)
			(layer "F.Fab")
			(hide yes)
			(effects
				(font
					(size 1.016 1.016)
					(thickness 0.1524)
				)
			)
		)
		(property "Device Type" "R402H16"
			(at 0.064008 -5.517896 90)
			(unlocked yes)
			(layer "F.Fab")
			(hide yes)
			(effects
				(font
					(size 1.016 1.016)
					(thickness 0.1524)
				)
			)
		)
		(duplicate_pad_numbers_are_jumpers no)
		(fp_line
			(start 0.508 -0.9398)
			(end -0.508 -0.9398)
			(stroke
				(width 0.1524)
				(type default)
			)
			(layer "F.SilkS")
		)
		(fp_line
			(start -0.508 -0.9398)
			(end -0.508 0.9398)
			(stroke
				(width 0.1524)
				(type default)
			)
			(layer "F.SilkS")
		)
		(fp_rect
			(start -0.508 0.9398)
			(end 0.508 -0.9398)
			(stroke
				(width 0)
				(type default)
			)
			(fill no)
			(layer "F.CrtYd")
		)
		(fp_rect
			(start -0.508 0.9398)
			(end 0.508 -0.9398)
			(stroke
				(width 0)
				(type default)
			)
			(fill no)
			(layer "F.Fab")
		)
		(pad "1" smd custom
			(at 0 -0.4445 90)
			(size 0.1397 0.1397)
			(layers "F.Cu" "F.Mask" "F.Paste")
			(net "TPS74801_P1V5_FB")
			(options
				(clearance outline)
				(anchor circle)
			)
			(primitives
				(gr_poly
					(pts
						(arc
							(start -0.1778 -0.2794)
							(mid -0.249642 -0.249642)
							(end -0.2794 -0.1778)
						)
						(arc
							(start -0.2794 0.1778)
							(mid -0.249642 0.249642)
							(end -0.1778 0.2794)
						)
						(arc
							(start 0.1778 0.2794)
							(mid 0.249642 0.249642)
							(end 0.2794 0.1778)
						)
						(arc
							(start 0.2794 -0.1778)
							(mid 0.249642 -0.249642)
							(end 0.1778 -0.2794)
						)
					)
					(width 0)
					(fill yes)
				)
			)
		)
		(pad "2" smd custom
			(at 0 0.4445 90)
			(size 0.1397 0.1397)
			(layers "F.Cu" "F.Mask" "F.Paste")
			(net "GND")
			(options
				(clearance outline)
				(anchor circle)
			)
			(primitives
				(gr_poly
					(pts
						(arc
							(start -0.1778 -0.2794)
							(mid -0.249642 -0.249642)
							(end -0.2794 -0.1778)
						)
						(arc
							(start -0.2794 0.1778)
							(mid -0.249642 0.249642)
							(end -0.1778 0.2794)
						)
						(arc
							(start 0.1778 0.2794)
							(mid 0.249642 0.249642)
							(end 0.2794 0.1778)
						)
						(arc
							(start 0.2794 -0.1778)
							(mid 0.249642 -0.249642)
							(end 0.1778 -0.2794)
						)
					)
					(width 0)
					(fill yes)
				)
			)
		)
	)
	(footprint ""
		(layer "F.Cu")
		(at 181.229 -90.9066)
		(property "Reference" "R642"
			(at 0 0 0)
			(layer "F.SilkS")
			(hide yes)
			(effects
				(font
					(size 1.27 1.27)
				)
			)
		)
		(property "Value" "4K7R2F-GP"
			(at 0.064008 -3.993896 0)
			(unlocked yes)
			(layer "F.Fab")
			(hide yes)
			(effects
				(font
					(size 1.016 1.016)
					(thickness 0.1524)
				)
			)
		)
		(property "Device Type" "R402H16"
			(at 0.064008 -5.517896 0)
			(unlocked yes)
			(layer "F.Fab")
			(hide yes)
			(effects
				(font
					(size 1.016 1.016)
					(thickness 0.1524)
				)
			)
		)
		(duplicate_pad_numbers_are_jumpers no)
		(fp_line
			(start -0.508 -0.9398)
			(end -0.508 0.9398)
			(stroke
				(width 0.1524)
				(type default)
			)
			(layer "F.SilkS")
		)
		(fp_line
			(start 0.508 -0.9398)
			(end -0.508 -0.9398)
			(stroke
				(width 0.1524)
				(type default)
			)
			(layer "F.SilkS")
		)
		(fp_rect
			(start -0.508 0.9398)
			(end 0.508 -0.9398)
			(stroke
				(width 0)
				(type default)
			)
			(fill no)
			(layer "F.CrtYd")
		)
		(fp_rect
			(start -0.508 0.9398)
			(end 0.508 -0.9398)
			(stroke
				(width 0)
				(type default)
			)
			(fill no)
			(layer "F.Fab")
		)
		(pad "1" smd custom
			(at 0 -0.4445)
			(size 0.1397 0.1397)
			(layers "F.Cu" "F.Mask" "F.Paste")
			(net "P1V8")
			(options
				(clearance outline)
				(anchor circle)
			)
			(primitives
				(gr_poly
					(pts
						(arc
							(start -0.1778 -0.2794)
							(mid -0.249642 -0.249642)
							(end -0.2794 -0.1778)
						)
						(arc
							(start -0.2794 0.1778)
							(mid -0.249642 0.249642)
							(end -0.1778 0.2794)
						)
						(arc
							(start 0.1778 0.2794)
							(mid 0.249642 0.249642)
							(end 0.2794 0.1778)
						)
						(arc
							(start 0.2794 -0.1778)
							(mid 0.249642 -0.249642)
							(end 0.1778 -0.2794)
						)
					)
					(width 0)
					(fill yes)
				)
			)
		)
		(pad "2" smd custom
			(at 0 0.4445)
			(size 0.1397 0.1397)
			(layers "F.Cu" "F.Mask" "F.Paste")
			(net "SYS_DBMODE2")
			(options
				(clearance outline)
				(anchor circle)
			)
			(primitives
				(gr_poly
					(pts
						(arc
							(start -0.1778 -0.2794)
							(mid -0.249642 -0.249642)
							(end -0.2794 -0.1778)
						)
						(arc
							(start -0.2794 0.1778)
							(mid -0.249642 0.249642)
							(end -0.1778 0.2794)
						)
						(arc
							(start 0.1778 0.2794)
							(mid 0.249642 0.249642)
							(end 0.2794 0.1778)
						)
						(arc
							(start 0.2794 -0.1778)
							(mid 0.249642 -0.249642)
							(end 0.1778 -0.2794)
						)
					)
					(width 0)
					(fill yes)
				)
			)
		)
	)
	(footprint ""
		(layer "F.Cu")
		(at 82.529934 -144.339818 90)
		(property "Reference" "U105"
			(at 0 0 90)
			(layer "F.SilkS")
			(hide yes)
			(effects
				(font
					(size 1.27 1.27)
				)
			)
		)
		(property "Value" "SN74CBTLV3245APWR-GP"
			(at -0.889 -6.2738 90)
			(unlocked yes)
			(layer "F.Fab")
			(hide yes)
			(effects
				(font
					(size 1.016 1.016)
					(thickness 0.1524)
				)
			)
		)
		(property "Device Type" "TSOIC20H48"
			(at -0.9144 -7.8994 90)
			(unlocked yes)
			(layer "F.Fab")
			(hide yes)
			(effects
				(font
					(size 1.016 1.016)
					(thickness 0.1524)
				)
			)
		)
		(duplicate_pad_numbers_are_jumpers no)
		(fp_line
			(start 3.175 -1.397)
			(end 3.175 1.397)
			(stroke
				(width 0.2032)
				(type default)
			)
			(layer "F.SilkS")
		)
		(fp_line
			(start -3.556 -1.397)
			(end 3.175 -1.397)
			(stroke
				(width 0.2032)
				(type default)
			)
			(layer "F.SilkS")
		)
		(fp_line
			(start -3.556 -1.397)
			(end -3.556 4.064)
			(stroke
				(width 0.2032)
				(type default)
			)
			(layer "F.SilkS")
		)
		(fp_line
			(start -2.667 0)
			(end -3.556 -0.889)
			(stroke
				(width 0.2032)
				(type default)
			)
			(layer "F.SilkS")
		)
		(fp_line
			(start -2.667 0)
			(end -3.556 0.889)
			(stroke
				(width 0.2032)
				(type default)
			)
			(layer "F.SilkS")
		)
		(fp_line
			(start 3.175 1.397)
			(end -3.556 1.397)
			(stroke
				(width 0.2032)
				(type default)
			)
			(layer "F.SilkS")
		)
		(fp_line
			(start -3.556 1.397)
			(end -3.556 1.778)
			(stroke
				(width 0.2032)
				(type default)
			)
			(layer "F.SilkS")
		)
		(fp_line
			(start -3.556 4.064)
			(end -3.556 1.778)
			(stroke
				(width 0.508)
				(type default)
			)
			(layer "F.SilkS")
		)
		(fp_poly
			(pts
				(xy -3.25628 -1.8542) (xy 3.25628 -1.8542) (xy 3.25628 1.8542) (xy -3.25628 1.8542)
			)
			(stroke
				(width 0)
				(type default)
			)
			(fill yes)
			(layer "F.SilkS")
		)
		(fp_rect
			(start -3.556 3.81)
			(end 3.556 -3.81)
			(stroke
				(width 0)
				(type default)
			)
			(fill no)
			(layer "F.CrtYd")
		)
		(fp_poly
			(pts
				(xy -3.556 -3.81) (xy 3.556 -3.81) (xy 3.556 3.81) (xy -3.556 3.81)
			)
			(stroke
				(width 0)
				(type default)
			)
			(fill no)
			(layer "F.Fab")
		)
		(pad "1" smd rect
			(at -2.92608 2.8194 90)
			(size 0.3556 1.524)
			(layers "F.Cu" "F.Mask" "F.Paste")
			(net "Net_133")
		)
		(pad "2" smd rect
			(at -2.27584 2.8194 90)
			(size 0.3556 1.524)
			(layers "F.Cu" "F.Mask" "F.Paste")
			(net "I2C_EXP_LOC_SCL_OUT")
		)
		(pad "3" smd rect
			(at -1.6256 2.8194 90)
			(size 0.3556 1.524)
			(layers "F.Cu" "F.Mask" "F.Paste")
			(net "I2C_EXP_LOC_SDA_OUT")
		)
		(pad "4" smd rect
			(at -0.97536 2.8194 90)
			(size 0.3556 1.524)
			(layers "F.Cu" "F.Mask" "F.Paste")
			(net "I2C_EXP_RMT_SCL_OUT")
		)
		(pad "5" smd rect
			(at -0.32512 2.8194 90)
			(size 0.3556 1.524)
			(layers "F.Cu" "F.Mask" "F.Paste")
			(net "I2C_EXP_RMT_SDA_OUT")
		)
		(pad "6" smd rect
			(at 0.32512 2.8194 90)
			(size 0.3556 1.524)
			(layers "F.Cu" "F.Mask" "F.Paste")
			(net "I2C_SCC_SCL_OUT")
		)
		(pad "7" smd rect
			(at 0.97536 2.8194 90)
			(size 0.3556 1.524)
			(layers "F.Cu" "F.Mask" "F.Paste")
			(net "I2C_SCC_SDA_OUT")
		)
		(pad "8" smd rect
			(at 1.6256 2.8194 90)
			(size 0.3556 1.524)
			(layers "F.Cu" "F.Mask" "F.Paste")
			(net "I2C_DPB_SCL_OUT")
		)
		(pad "9" smd rect
			(at 2.27584 2.8194 90)
			(size 0.3556 1.524)
			(layers "F.Cu" "F.Mask" "F.Paste")
			(net "I2C_DPB_SDA_OUT")
		)
		(pad "10" smd rect
			(at 2.92608 2.8194 90)
			(size 0.3556 1.524)
			(layers "F.Cu" "F.Mask" "F.Paste")
			(net "GND")
		)
		(pad "11" smd rect
			(at 2.92608 -2.8194 90)
			(size 0.3556 1.524)
			(layers "F.Cu" "F.Mask" "F.Paste")
			(net "I2C_DPB_SDA_R")
		)
		(pad "12" smd rect
			(at 2.27584 -2.8194 90)
			(size 0.3556 1.524)
			(layers "F.Cu" "F.Mask" "F.Paste")
			(net "I2C_DPB_SCL_R")
		)
		(pad "13" smd rect
			(at 1.6256 -2.8194 90)
			(size 0.3556 1.524)
			(layers "F.Cu" "F.Mask" "F.Paste")
			(net "I2C_SCC_SDA_R")
		)
		(pad "14" smd rect
			(at 0.97536 -2.8194 90)
			(size 0.3556 1.524)
			(layers "F.Cu" "F.Mask" "F.Paste")
			(net "I2C_SCC_SCL_R")
		)
		(pad "15" smd rect
			(at 0.32512 -2.8194 90)
			(size 0.3556 1.524)
			(layers "F.Cu" "F.Mask" "F.Paste")
			(net "I2C_EXP_RMT_SDA_R")
		)
		(pad "16" smd rect
			(at -0.32512 -2.8194 90)
			(size 0.3556 1.524)
			(layers "F.Cu" "F.Mask" "F.Paste")
			(net "I2C_EXP_RMT_SCL_R")
		)
		(pad "17" smd rect
			(at -0.97536 -2.8194 90)
			(size 0.3556 1.524)
			(layers "F.Cu" "F.Mask" "F.Paste")
			(net "I2C_EXP_LOC_SDA_R")
		)
		(pad "18" smd rect
			(at -1.6256 -2.8194 90)
			(size 0.3556 1.524)
			(layers "F.Cu" "F.Mask" "F.Paste")
			(net "I2C_EXP_LOC_SCL_R")
		)
		(pad "19" smd rect
			(at -2.27584 -2.8194 90)
			(size 0.3556 1.524)
			(layers "F.Cu" "F.Mask" "F.Paste")
			(net "PWRGD_P3V3_STBY_N_R1")
		)
		(pad "20" smd rect
			(at -2.92608 -2.8194 90)
			(size 0.3556 1.524)
			(layers "F.Cu" "F.Mask" "F.Paste")
			(net "P3V3_STBY")
		)
	)
	(footprint ""
		(layer "F.Cu")
		(at 93.411548 -36.423854 180)
		(property "Reference" "C325"
			(at 0 0 180)
			(layer "F.SilkS")
			(hide yes)
			(effects
				(font
					(size 1.27 1.27)
				)
			)
		)
		(property "Value" "ST150U16VDM-3-GP"
			(at 0 -9.6012 180)
			(unlocked yes)
			(layer "F.Fab")
			(hide yes)
			(effects
				(font
					(size 1.016 1.016)
					(thickness 0.1524)
				)
			)
		)
		(property "Device Type" "CT7343H119"
			(at 0 -11.1252 180)
			(unlocked yes)
			(layer "F.Fab")
			(hide yes)
			(effects
				(font
					(size 1.016 1.016)
					(thickness 0.1524)
				)
			)
		)
		(duplicate_pad_numbers_are_jumpers no)
		(fp_line
			(start 2.286 4.8768)
			(end -2.286 4.8768)
			(stroke
				(width 0.1524)
				(type default)
			)
			(layer "F.SilkS")
		)
		(fp_line
			(start 2.286 2.032)
			(end 2.286 4.8768)
			(stroke
				(width 0.1524)
				(type default)
			)
			(layer "F.SilkS")
		)
		(fp_line
			(start 2.286 -2.032)
			(end 2.286 -4.8768)
			(stroke
				(width 0.1524)
				(type default)
			)
			(layer "F.SilkS")
		)
		(fp_line
			(start 2.286 -4.8768)
			(end -2.286 -4.8768)
			(stroke
				(width 0.1524)
				(type default)
			)
			(layer "F.SilkS")
		)
		(fp_line
			(start 2.1082 -4.699)
			(end -2.1082 -4.699)
			(stroke
				(width 0.508)
				(type default)
			)
			(layer "F.SilkS")
		)
		(fp_line
			(start -2.286 4.8768)
			(end -2.286 2.032)
			(stroke
				(width 0.1524)
				(type default)
			)
			(layer "F.SilkS")
		)
		(fp_line
			(start -2.286 -4.8768)
			(end -2.286 -2.032)
			(stroke
				(width 0.1524)
				(type default)
			)
			(layer "F.SilkS")
		)
		(fp_rect
			(start -2.1463 3.6449)
			(end 2.1463 -3.6449)
			(stroke
				(width 0)
				(type default)
			)
			(fill no)
			(layer "F.CrtYd")
		)
		(fp_poly
			(pts
				(xy -2.54 4.953) (xy -2.54 4.2926) (xy -3.81 4.2926) (xy -3.81 -4.2926) (xy -2.54 -4.2926) (xy -2.54 -4.953)
				(xy 2.54 -4.953) (xy 2.54 -4.2926) (xy 3.81 -4.2926) (xy 3.81 -1.6256) (xy 2.1463 -1.6256) (xy 2.1463 -3.6449)
				(xy -2.1463 -3.6449) (xy -2.1463 3.6449) (xy 2.1463 3.6449) (xy 2.1463 -1.6129) (xy 3.81 -1.6129)
				(xy 3.81 4.2926) (xy 2.54 4.2926) (xy 2.54 4.953)
			)
			(stroke
				(width 0)
				(type default)
			)
			(fill no)
			(layer "F.CrtYd")
		)
		(fp_rect
			(start 2.54 4.2926)
			(end 3.81 -4.2926)
			(stroke
				(width 0)
				(type default)
			)
			(fill no)
			(layer "F.Fab")
		)
		(fp_rect
			(start -2.54 4.953)
			(end 2.54 -4.953)
			(stroke
				(width 0)
				(type default)
			)
			(fill no)
			(layer "F.Fab")
		)
		(fp_rect
			(start -3.81 4.2926)
			(end -2.54 -4.2926)
			(stroke
				(width 0)
				(type default)
			)
			(fill no)
			(layer "F.Fab")
		)
		(pad "1" smd rect
			(at 0 -3.1496 180)
			(size 2.413 2.286)
			(layers "F.Cu" "F.Mask" "F.Paste")
			(net "P5V_USB")
		)
		(pad "2" smd rect
			(at 0 3.1496 180)
			(size 2.413 2.286)
			(layers "F.Cu" "F.Mask" "F.Paste")
			(net "GND")
		)
		(zone
			(layer "F.Cu")
			(hatch none 0.5)
			(connect_pads
				(clearance 0)
			)
			(min_thickness 0.25)
			(keepout
				(tracks allowed)
				(vias not_allowed)
				(pads allowed)
				(copperpour not_allowed)
				(footprints allowed)
			)
			(placement
				(enabled no)
				(sheetname "")
			)
			(fill
				(thermal_gap 0.5)
				(thermal_bridge_width 0.5)
				(island_removal_mode 0)
			)
			(polygon
				(pts
					(xy 91.900248 -34.734754) (xy 91.900248 -31.826454) (xy 94.922848 -31.826454) (xy 94.922848 -34.722054)
					(xy 94.922848 -35.052254) (xy 91.900248 -35.052254)
				)
			)
		)
		(zone
			(layer "F.Cu")
			(hatch none 0.5)
			(connect_pads
				(clearance 0)
			)
			(min_thickness 0.25)
			(keepout
				(tracks allowed)
				(vias not_allowed)
				(pads allowed)
				(copperpour not_allowed)
				(footprints allowed)
			)
			(placement
				(enabled no)
				(sheetname "")
			)
			(fill
				(thermal_gap 0.5)
				(thermal_bridge_width 0.5)
				(island_removal_mode 0)
			)
			(polygon
				(pts
					(xy 94.922848 -41.021254) (xy 91.900248 -41.021254) (xy 91.900248 -38.125654) (xy 91.900248 -37.795454)
					(xy 94.922848 -37.795454) (xy 94.922848 -38.125654)
				)
			)
		)
	)
	(footprint ""
		(layer "F.Cu")
		(at 60.616592 -131.296156 180)
		(property "Reference" "R290"
			(at 0 0 180)
			(layer "F.SilkS")
			(hide yes)
			(effects
				(font
					(size 1.27 1.27)
				)
			)
		)
		(property "Value" "0R2J-2-GP"
			(at 0.064008 -3.993896 180)
			(unlocked yes)
			(layer "F.Fab")
			(hide yes)
			(effects
				(font
					(size 1.016 1.016)
					(thickness 0.1524)
				)
			)
		)
		(property "Device Type" "R402H16"
			(at 0.064008 -5.517896 180)
			(unlocked yes)
			(layer "F.Fab")
			(hide yes)
			(effects
				(font
					(size 1.016 1.016)
					(thickness 0.1524)
				)
			)
		)
		(duplicate_pad_numbers_are_jumpers no)
		(fp_line
			(start 0.508 -0.9398)
			(end -0.508 -0.9398)
			(stroke
				(width 0.1524)
				(type default)
			)
			(layer "F.SilkS")
		)
		(fp_line
			(start -0.508 -0.9398)
			(end -0.508 0.9398)
			(stroke
				(width 0.1524)
				(type default)
			)
			(layer "F.SilkS")
		)
		(fp_rect
			(start -0.508 0.9398)
			(end 0.508 -0.9398)
			(stroke
				(width 0)
				(type default)
			)
			(fill no)
			(layer "F.CrtYd")
		)
		(fp_rect
			(start -0.508 0.9398)
			(end 0.508 -0.9398)
			(stroke
				(width 0)
				(type default)
			)
			(fill no)
			(layer "F.Fab")
		)
		(pad "1" smd custom
			(at 0 -0.4445 180)
			(size 0.1397 0.1397)
			(layers "F.Cu" "F.Mask" "F.Paste")
			(net "SCC_STBY_PWR_EN")
			(options
				(clearance outline)
				(anchor circle)
			)
			(primitives
				(gr_poly
					(pts
						(arc
							(start -0.1778 -0.2794)
							(mid -0.249642 -0.249642)
							(end -0.2794 -0.1778)
						)
						(arc
							(start -0.2794 0.1778)
							(mid -0.249642 0.249642)
							(end -0.1778 0.2794)
						)
						(arc
							(start 0.1778 0.2794)
							(mid 0.249642 0.249642)
							(end 0.2794 0.1778)
						)
						(arc
							(start 0.2794 -0.1778)
							(mid 0.249642 -0.249642)
							(end 0.1778 -0.2794)
						)
					)
					(width 0)
					(fill yes)
				)
			)
		)
		(pad "2" smd custom
			(at 0 0.4445 180)
			(size 0.1397 0.1397)
			(layers "F.Cu" "F.Mask" "F.Paste")
			(net "SCC_PWR_EN_R")
			(options
				(clearance outline)
				(anchor circle)
			)
			(primitives
				(gr_poly
					(pts
						(arc
							(start -0.1778 -0.2794)
							(mid -0.249642 -0.249642)
							(end -0.2794 -0.1778)
						)
						(arc
							(start -0.2794 0.1778)
							(mid -0.249642 0.249642)
							(end -0.1778 0.2794)
						)
						(arc
							(start 0.1778 0.2794)
							(mid 0.249642 0.249642)
							(end 0.2794 0.1778)
						)
						(arc
							(start 0.2794 -0.1778)
							(mid 0.249642 -0.249642)
							(end 0.1778 -0.2794)
						)
					)
					(width 0)
					(fill yes)
				)
			)
		)
	)
	(footprint ""
		(layer "F.Cu")
		(at 172.2374 -38.481)
		(property "Reference" "TP173"
			(at 0 0 0)
			(layer "F.SilkS")
			(hide yes)
			(effects
				(font
					(size 1.27 1.27)
				)
			)
		)
		(property "Value" "TPAD28-2-GP"
			(at -0.0127 -1.6637 0)
			(unlocked yes)
			(layer "F.Fab")
			(hide yes)
			(effects
				(font
					(size 1.016 1.016)
					(thickness 0.1524)
				)
			)
		)
		(property "Device Type" "TPAD28"
			(at -0.0127 -3.1877 0)
			(unlocked yes)
			(layer "F.Fab")
			(hide yes)
			(effects
				(font
					(size 1.016 1.016)
					(thickness 0.1524)
				)
			)
		)
		(duplicate_pad_numbers_are_jumpers no)
		(fp_poly
			(pts
				(arc
					(start 0.3556 0)
					(mid -0.3556 0)
					(end 0.3556 0)
				)
			)
			(stroke
				(width 0)
				(type default)
			)
			(fill no)
			(layer "F.CrtYd")
		)
		(fp_poly
			(pts
				(arc
					(start 0.6096 0)
					(mid -0.6096 0)
					(end 0.6096 0)
				)
			)
			(stroke
				(width 0)
				(type default)
			)
			(fill no)
			(layer "F.Fab")
		)
		(pad "1" smd circle
			(at 0 0)
			(size 0.7112 0.7112)
			(layers "F.Cu" "F.Mask" "F.Paste")
			(net "ZDEF_EXTA_TP_A2")
		)
	)
	(footprint ""
		(layer "F.Cu")
		(at 93.668088 -61.133736 90)
		(property "Reference" "R704"
			(at 0 0 90)
			(layer "F.SilkS")
			(hide yes)
			(effects
				(font
					(size 1.27 1.27)
				)
			)
		)
		(property "Value" "100KR2J-4-GP"
			(at 0.064008 -3.993896 90)
			(unlocked yes)
			(layer "F.Fab")
			(hide yes)
			(effects
				(font
					(size 1.016 1.016)
					(thickness 0.1524)
				)
			)
		)
		(property "Device Type" "R402H15"
			(at 0.064008 -5.517896 90)
			(unlocked yes)
			(layer "F.Fab")
			(hide yes)
			(effects
				(font
					(size 1.016 1.016)
					(thickness 0.1524)
				)
			)
		)
		(duplicate_pad_numbers_are_jumpers no)
		(fp_line
			(start 0.508 -0.9398)
			(end -0.508 -0.9398)
			(stroke
				(width 0.1524)
				(type default)
			)
			(layer "F.SilkS")
		)
		(fp_line
			(start -0.508 -0.9398)
			(end -0.508 0.9398)
			(stroke
				(width 0.1524)
				(type default)
			)
			(layer "F.SilkS")
		)
		(fp_rect
			(start -0.508 0.9398)
			(end 0.508 -0.9398)
			(stroke
				(width 0)
				(type default)
			)
			(fill no)
			(layer "F.CrtYd")
		)
		(fp_rect
			(start -0.508 0.9398)
			(end 0.508 -0.9398)
			(stroke
				(width 0)
				(type default)
			)
			(fill no)
			(layer "F.Fab")
		)
		(pad "1" smd custom
			(at 0 -0.4445 90)
			(size 0.1397 0.1397)
			(layers "F.Cu" "F.Mask" "F.Paste")
			(net "GND")
			(options
				(clearance outline)
				(anchor circle)
			)
			(primitives
				(gr_poly
					(pts
						(arc
							(start -0.1778 -0.2794)
							(mid -0.249642 -0.249642)
							(end -0.2794 -0.1778)
						)
						(arc
							(start -0.2794 0.1778)
							(mid -0.249642 0.249642)
							(end -0.1778 0.2794)
						)
						(arc
							(start 0.1778 0.2794)
							(mid 0.249642 0.249642)
							(end 0.2794 0.1778)
						)
						(arc
							(start 0.2794 -0.1778)
							(mid 0.249642 -0.249642)
							(end 0.1778 -0.2794)
						)
					)
					(width 0)
					(fill yes)
				)
			)
		)
		(pad "2" smd custom
			(at 0 0.4445 90)
			(size 0.1397 0.1397)
			(layers "F.Cu" "F.Mask" "F.Paste")
			(net "IOM_FULL_PWR_EN")
			(options
				(clearance outline)
				(anchor circle)
			)
			(primitives
				(gr_poly
					(pts
						(arc
							(start -0.1778 -0.2794)
							(mid -0.249642 -0.249642)
							(end -0.2794 -0.1778)
						)
						(arc
							(start -0.2794 0.1778)
							(mid -0.249642 0.249642)
							(end -0.1778 0.2794)
						)
						(arc
							(start 0.1778 0.2794)
							(mid 0.249642 0.249642)
							(end 0.2794 0.1778)
						)
						(arc
							(start 0.2794 -0.1778)
							(mid 0.249642 -0.249642)
							(end 0.1778 -0.2794)
						)
					)
					(width 0)
					(fill yes)
				)
			)
		)
	)
	(footprint ""
		(layer "F.Cu")
		(at 206.616046 -17.357344 180)
		(property "Reference" "R614"
			(at 0 0 180)
			(layer "F.SilkS")
			(hide yes)
			(effects
				(font
					(size 1.27 1.27)
				)
			)
		)
		(property "Value" "0R2J-2-GP"
			(at 0.064008 -3.993896 180)
			(unlocked yes)
			(layer "F.Fab")
			(hide yes)
			(effects
				(font
					(size 1.016 1.016)
					(thickness 0.1524)
				)
			)
		)
		(property "Device Type" "R402H16"
			(at 0.064008 -5.517896 180)
			(unlocked yes)
			(layer "F.Fab")
			(hide yes)
			(effects
				(font
					(size 1.016 1.016)
					(thickness 0.1524)
				)
			)
		)
		(duplicate_pad_numbers_are_jumpers no)
		(fp_line
			(start 0.508 -0.9398)
			(end -0.508 -0.9398)
			(stroke
				(width 0.1524)
				(type default)
			)
			(layer "F.SilkS")
		)
		(fp_line
			(start -0.508 -0.9398)
			(end -0.508 0.9398)
			(stroke
				(width 0.1524)
				(type default)
			)
			(layer "F.SilkS")
		)
		(fp_rect
			(start -0.508 0.9398)
			(end 0.508 -0.9398)
			(stroke
				(width 0)
				(type default)
			)
			(fill no)
			(layer "F.CrtYd")
		)
		(fp_rect
			(start -0.508 0.9398)
			(end 0.508 -0.9398)
			(stroke
				(width 0)
				(type default)
			)
			(fill no)
			(layer "F.Fab")
		)
		(pad "1" smd custom
			(at 0 -0.4445 180)
			(size 0.1397 0.1397)
			(layers "F.Cu" "F.Mask" "F.Paste")
			(net "BMC_ML_PWR_BLUE_LED_R")
			(options
				(clearance outline)
				(anchor circle)
			)
			(primitives
				(gr_poly
					(pts
						(arc
							(start -0.1778 -0.2794)
							(mid -0.249642 -0.249642)
							(end -0.2794 -0.1778)
						)
						(arc
							(start -0.2794 0.1778)
							(mid -0.249642 0.249642)
							(end -0.1778 0.2794)
						)
						(arc
							(start 0.1778 0.2794)
							(mid 0.249642 0.249642)
							(end 0.2794 0.1778)
						)
						(arc
							(start 0.2794 -0.1778)
							(mid 0.249642 -0.249642)
							(end 0.1778 -0.2794)
						)
					)
					(width 0)
					(fill yes)
				)
			)
		)
		(pad "2" smd custom
			(at 0 0.4445 180)
			(size 0.1397 0.1397)
			(layers "F.Cu" "F.Mask" "F.Paste")
			(net "BMC_ML_PWR_BLUE_LED")
			(options
				(clearance outline)
				(anchor circle)
			)
			(primitives
				(gr_poly
					(pts
						(arc
							(start -0.1778 -0.2794)
							(mid -0.249642 -0.249642)
							(end -0.2794 -0.1778)
						)
						(arc
							(start -0.2794 0.1778)
							(mid -0.249642 0.249642)
							(end -0.1778 0.2794)
						)
						(arc
							(start 0.1778 0.2794)
							(mid 0.249642 0.249642)
							(end 0.2794 0.1778)
						)
						(arc
							(start 0.2794 -0.1778)
							(mid 0.249642 -0.249642)
							(end 0.1778 -0.2794)
						)
					)
					(width 0)
					(fill yes)
				)
			)
		)
	)
	(footprint ""
		(layer "F.Cu")
		(at 206.5401 -132.957316 180)
		(property "Reference" "C256"
			(at 0 0 180)
			(layer "F.SilkS")
			(hide yes)
			(effects
				(font
					(size 1.27 1.27)
				)
			)
		)
		(property "Value" "SC10U6D3V5KX-4GP"
			(at -0.0762 -6.1214 180)
			(unlocked yes)
			(layer "F.Fab")
			(hide yes)
			(effects
				(font
					(size 1.016 1.016)
					(thickness 0.1524)
				)
			)
		)
		(property "Device Type" "C805H58"
			(at -0.0762 -8.1534 180)
			(unlocked yes)
			(layer "F.Fab")
			(hide yes)
			(effects
				(font
					(size 1.016 1.016)
					(thickness 0.1524)
				)
			)
		)
		(duplicate_pad_numbers_are_jumpers no)
		(fp_line
			(start 0.635 0)
			(end -0.635 0)
			(stroke
				(width 0.508)
				(type default)
			)
			(layer "F.SilkS")
		)
		(fp_rect
			(start -0.9652 1.778)
			(end 0.9652 -1.778)
			(stroke
				(width 0)
				(type default)
			)
			(fill no)
			(layer "F.CrtYd")
		)
		(fp_poly
			(pts
				(xy -0.9652 -1.778) (xy 0.9652 -1.778) (xy 0.9652 1.778) (xy -0.9652 1.778)
			)
			(stroke
				(width 0)
				(type default)
			)
			(fill no)
			(layer "F.Fab")
		)
		(pad "1" smd rect
			(at 0 -0.9652 180)
			(size 1.397 1.143)
			(layers "F.Cu" "F.Mask" "F.Paste")
			(net "P1V8_STBY")
		)
		(pad "2" smd rect
			(at 0 0.9652 180)
			(size 1.397 1.143)
			(layers "F.Cu" "F.Mask" "F.Paste")
			(net "GND")
		)
	)
	(footprint ""
		(layer "F.Cu")
		(at 194.005454 -124.591826 180)
		(property "Reference" "C279"
			(at 0 0 180)
			(layer "F.SilkS")
			(hide yes)
			(effects
				(font
					(size 1.27 1.27)
				)
			)
		)
		(property "Value" "SC6K8P50V2KX-GP"
			(at 1.1811 -2.7051 180)
			(unlocked yes)
			(layer "F.Fab")
			(hide yes)
			(effects
				(font
					(size 1.016 1.016)
					(thickness 0.1524)
				)
			)
		)
		(property "Device Type" "C402H22"
			(at 1.1811 -4.2291 180)
			(unlocked yes)
			(layer "F.Fab")
			(hide yes)
			(effects
				(font
					(size 1.016 1.016)
					(thickness 0.1524)
				)
			)
		)
		(duplicate_pad_numbers_are_jumpers no)
		(fp_rect
			(start -0.4318 0.9525)
			(end 0.4318 -0.9525)
			(stroke
				(width 0)
				(type default)
			)
			(fill no)
			(layer "F.CrtYd")
		)
		(fp_rect
			(start -0.4318 0.9525)
			(end 0.4318 -0.9525)
			(stroke
				(width 0)
				(type default)
			)
			(fill no)
			(layer "F.Fab")
		)
		(pad "1" smd custom
			(at 0 -0.4445 180)
			(size 0.1524 0.1524)
			(layers "F.Cu" "F.Mask" "F.Paste")
			(net "VT235_VFB")
			(options
				(clearance outline)
				(anchor circle)
			)
			(primitives
				(gr_poly
					(pts
						(arc
							(start 0.3048 -0.2032)
							(mid 0.275042 -0.275042)
							(end 0.2032 -0.3048)
						)
						(arc
							(start -0.2032 -0.3048)
							(mid -0.275042 -0.275042)
							(end -0.3048 -0.2032)
						)
						(arc
							(start -0.3048 0.2032)
							(mid -0.275042 0.275042)
							(end -0.2032 0.3048)
						)
						(arc
							(start 0.2032 0.3048)
							(mid 0.275042 0.275042)
							(end 0.3048 0.2032)
						)
					)
					(width 0)
					(fill yes)
				)
			)
		)
		(pad "2" smd custom
			(at 0 0.4445 180)
			(size 0.1524 0.1524)
			(layers "F.Cu" "F.Mask" "F.Paste")
			(net "VT235_VDES")
			(options
				(clearance outline)
				(anchor circle)
			)
			(primitives
				(gr_poly
					(pts
						(arc
							(start 0.3048 -0.2032)
							(mid 0.275042 -0.275042)
							(end 0.2032 -0.3048)
						)
						(arc
							(start -0.2032 -0.3048)
							(mid -0.275042 -0.275042)
							(end -0.3048 -0.2032)
						)
						(arc
							(start -0.3048 0.2032)
							(mid -0.275042 0.275042)
							(end -0.2032 0.3048)
						)
						(arc
							(start 0.2032 0.3048)
							(mid 0.275042 0.275042)
							(end 0.3048 0.2032)
						)
					)
					(width 0)
					(fill yes)
				)
			)
		)
	)
	(footprint ""
		(layer "F.Cu")
		(at 142.113 -18.415)
		(property "Reference" "Q22"
			(at 0 0 0)
			(layer "F.SilkS")
			(hide yes)
			(effects
				(font
					(size 1.27 1.27)
				)
			)
		)
		(property "Value" "SSM3K324R-GP"
			(at 0.127 -8.9662 0)
			(unlocked yes)
			(layer "F.Fab")
			(hide yes)
			(effects
				(font
					(size 1.016 1.016)
					(thickness 0.1524)
				)
			)
		)
		(property "Device Type" "SOT23DGS2D4H35"
			(at 0.127 -10.4902 0)
			(unlocked yes)
			(layer "F.Fab")
			(hide yes)
			(effects
				(font
					(size 1.016 1.016)
					(thickness 0.1524)
				)
			)
		)
		(duplicate_pad_numbers_are_jumpers no)
		(fp_line
			(start -1.651 -1.778)
			(end -1.651 1.778)
			(stroke
				(width 0.1524)
				(type default)
			)
			(layer "F.SilkS")
		)
		(fp_line
			(start -1.651 1.778)
			(end 1.651 1.778)
			(stroke
				(width 0.1524)
				(type default)
			)
			(layer "F.SilkS")
		)
		(fp_line
			(start 1.651 -1.778)
			(end -1.651 -1.778)
			(stroke
				(width 0.1524)
				(type default)
			)
			(layer "F.SilkS")
		)
		(fp_line
			(start 1.651 1.778)
			(end 1.651 -1.778)
			(stroke
				(width 0.1524)
				(type default)
			)
			(layer "F.SilkS")
		)
		(fp_poly
			(pts
				(xy -1.778 1.8796) (xy -1.778 -1.8796) (xy 1.778 -1.8796) (xy 1.778 1.8796)
			)
			(stroke
				(width 0)
				(type default)
			)
			(fill no)
			(layer "F.CrtYd")
		)
		(fp_poly
			(pts
				(xy -1.778 1.8796) (xy -1.778 -1.8796) (xy 1.778 -1.8796) (xy 1.778 1.8796)
			)
			(stroke
				(width 0)
				(type default)
			)
			(fill no)
			(layer "F.Fab")
		)
		(pad "D" smd custom
			(at 0 -0.9525)
			(size 0.1905 0.1905)
			(layers "F.Cu" "F.Mask" "F.Paste")
			(net "EXT2_LED_YELLOW_D")
			(options
				(clearance outline)
				(anchor circle)
			)
			(primitives
				(gr_poly
					(pts
						(arc
							(start -0.1778 0.5715)
							(mid -0.321484 0.511984)
							(end -0.381 0.3683)
						)
						(arc
							(start -0.381 -0.3683)
							(mid -0.321484 -0.511984)
							(end -0.1778 -0.5715)
						)
						(arc
							(start 0.1778 -0.5715)
							(mid 0.321484 -0.511984)
							(end 0.381 -0.3683)
						)
						(arc
							(start 0.381 0.3683)
							(mid 0.321484 0.511984)
							(end 0.1778 0.5715)
						)
					)
					(width 0)
					(fill yes)
				)
			)
		)
		(pad "G" smd custom
			(at -0.98425 0.9525)
			(size 0.1905 0.1905)
			(layers "F.Cu" "F.Mask" "F.Paste")
			(net "IOC_EXT2_LED_Y_XOR")
			(options
				(clearance outline)
				(anchor circle)
			)
			(primitives
				(gr_poly
					(pts
						(arc
							(start -0.1778 0.5715)
							(mid -0.321484 0.511984)
							(end -0.381 0.3683)
						)
						(arc
							(start -0.381 -0.3683)
							(mid -0.321484 -0.511984)
							(end -0.1778 -0.5715)
						)
						(arc
							(start 0.1778 -0.5715)
							(mid 0.321484 -0.511984)
							(end 0.381 -0.3683)
						)
						(arc
							(start 0.381 0.3683)
							(mid 0.321484 0.511984)
							(end 0.1778 0.5715)
						)
					)
					(width 0)
					(fill yes)
				)
			)
		)
		(pad "S" smd custom
			(at 0.98425 0.9525)
			(size 0.1905 0.1905)
			(layers "F.Cu" "F.Mask" "F.Paste")
			(net "GND")
			(options
				(clearance outline)
				(anchor circle)
			)
			(primitives
				(gr_poly
					(pts
						(arc
							(start -0.1778 0.5715)
							(mid -0.321484 0.511984)
							(end -0.381 0.3683)
						)
						(arc
							(start -0.381 -0.3683)
							(mid -0.321484 -0.511984)
							(end -0.1778 -0.5715)
						)
						(arc
							(start 0.1778 -0.5715)
							(mid 0.321484 -0.511984)
							(end 0.381 -0.3683)
						)
						(arc
							(start 0.381 0.3683)
							(mid 0.321484 0.511984)
							(end 0.1778 0.5715)
						)
					)
					(width 0)
					(fill yes)
				)
			)
		)
	)
	(footprint ""
		(layer "F.Cu")
		(at 45.44568 -121.868692 180)
		(property "Reference" "R91"
			(at 0 0 180)
			(layer "F.SilkS")
			(hide yes)
			(effects
				(font
					(size 1.27 1.27)
				)
			)
		)
		(property "Value" "300R2F-GP"
			(at 0.064008 -3.993896 180)
			(unlocked yes)
			(layer "F.Fab")
			(hide yes)
			(effects
				(font
					(size 1.016 1.016)
					(thickness 0.1524)
				)
			)
		)
		(property "Device Type" "R402H16"
			(at 0.064008 -5.517896 180)
			(unlocked yes)
			(layer "F.Fab")
			(hide yes)
			(effects
				(font
					(size 1.016 1.016)
					(thickness 0.1524)
				)
			)
		)
		(duplicate_pad_numbers_are_jumpers no)
		(fp_line
			(start 0.508 -0.9398)
			(end -0.508 -0.9398)
			(stroke
				(width 0.1524)
				(type default)
			)
			(layer "F.SilkS")
		)
		(fp_line
			(start -0.508 -0.9398)
			(end -0.508 0.9398)
			(stroke
				(width 0.1524)
				(type default)
			)
			(layer "F.SilkS")
		)
		(fp_rect
			(start -0.508 0.9398)
			(end 0.508 -0.9398)
			(stroke
				(width 0)
				(type default)
			)
			(fill no)
			(layer "F.CrtYd")
		)
		(fp_rect
			(start -0.508 0.9398)
			(end 0.508 -0.9398)
			(stroke
				(width 0)
				(type default)
			)
			(fill no)
			(layer "F.Fab")
		)
		(pad "1" smd custom
			(at 0 -0.4445 180)
			(size 0.1397 0.1397)
			(layers "F.Cu" "F.Mask" "F.Paste")
			(net "GND")
			(options
				(clearance outline)
				(anchor circle)
			)
			(primitives
				(gr_poly
					(pts
						(arc
							(start -0.1778 -0.2794)
							(mid -0.249642 -0.249642)
							(end -0.2794 -0.1778)
						)
						(arc
							(start -0.2794 0.1778)
							(mid -0.249642 0.249642)
							(end -0.1778 0.2794)
						)
						(arc
							(start 0.1778 0.2794)
							(mid 0.249642 0.249642)
							(end 0.2794 0.1778)
						)
						(arc
							(start 0.2794 -0.1778)
							(mid 0.249642 -0.249642)
							(end 0.1778 -0.2794)
						)
					)
					(width 0)
					(fill yes)
				)
			)
		)
		(pad "2" smd custom
			(at 0 0.4445 180)
			(size 0.1397 0.1397)
			(layers "F.Cu" "F.Mask" "F.Paste")
			(net "BMC_CPU_DIS")
			(options
				(clearance outline)
				(anchor circle)
			)
			(primitives
				(gr_poly
					(pts
						(arc
							(start -0.1778 -0.2794)
							(mid -0.249642 -0.249642)
							(end -0.2794 -0.1778)
						)
						(arc
							(start -0.2794 0.1778)
							(mid -0.249642 0.249642)
							(end -0.1778 0.2794)
						)
						(arc
							(start 0.1778 0.2794)
							(mid 0.249642 0.249642)
							(end 0.2794 0.1778)
						)
						(arc
							(start 0.2794 -0.1778)
							(mid 0.249642 -0.249642)
							(end 0.1778 -0.2794)
						)
					)
					(width 0)
					(fill yes)
				)
			)
		)
	)
	(footprint ""
		(layer "F.Cu")
		(at 16.041116 -162.5473 -90)
		(property "Reference" "R530"
			(at 0 0 270)
			(layer "F.SilkS")
			(hide yes)
			(effects
				(font
					(size 1.27 1.27)
				)
			)
		)
		(property "Value" "2K49R2F-GP"
			(at 0.064008 -3.993896 270)
			(unlocked yes)
			(layer "F.Fab")
			(hide yes)
			(effects
				(font
					(size 1.016 1.016)
					(thickness 0.1524)
				)
			)
		)
		(property "Device Type" "R402H16"
			(at 0.064008 -5.517896 270)
			(unlocked yes)
			(layer "F.Fab")
			(hide yes)
			(effects
				(font
					(size 1.016 1.016)
					(thickness 0.1524)
				)
			)
		)
		(duplicate_pad_numbers_are_jumpers no)
		(fp_line
			(start -0.508 -0.9398)
			(end -0.508 0.9398)
			(stroke
				(width 0.1524)
				(type default)
			)
			(layer "F.SilkS")
		)
		(fp_line
			(start 0.508 -0.9398)
			(end -0.508 -0.9398)
			(stroke
				(width 0.1524)
				(type default)
			)
			(layer "F.SilkS")
		)
		(fp_rect
			(start -0.508 0.9398)
			(end 0.508 -0.9398)
			(stroke
				(width 0)
				(type default)
			)
			(fill no)
			(layer "F.CrtYd")
		)
		(fp_rect
			(start -0.508 0.9398)
			(end 0.508 -0.9398)
			(stroke
				(width 0)
				(type default)
			)
			(fill no)
			(layer "F.Fab")
		)
		(pad "1" smd custom
			(at 0 -0.4445 270)
			(size 0.1397 0.1397)
			(layers "F.Cu" "F.Mask" "F.Paste")
			(net "TPS74801_P1V2_STBY_OUT")
			(options
				(clearance outline)
				(anchor circle)
			)
			(primitives
				(gr_poly
					(pts
						(arc
							(start -0.1778 -0.2794)
							(mid -0.249642 -0.249642)
							(end -0.2794 -0.1778)
						)
						(arc
							(start -0.2794 0.1778)
							(mid -0.249642 0.249642)
							(end -0.1778 0.2794)
						)
						(arc
							(start 0.1778 0.2794)
							(mid 0.249642 0.249642)
							(end 0.2794 0.1778)
						)
						(arc
							(start 0.2794 -0.1778)
							(mid 0.249642 -0.249642)
							(end 0.1778 -0.2794)
						)
					)
					(width 0)
					(fill yes)
				)
			)
		)
		(pad "2" smd custom
			(at 0 0.4445 270)
			(size 0.1397 0.1397)
			(layers "F.Cu" "F.Mask" "F.Paste")
			(net "TPS74801_P1V2_STBY_FB")
			(options
				(clearance outline)
				(anchor circle)
			)
			(primitives
				(gr_poly
					(pts
						(arc
							(start -0.1778 -0.2794)
							(mid -0.249642 -0.249642)
							(end -0.2794 -0.1778)
						)
						(arc
							(start -0.2794 0.1778)
							(mid -0.249642 0.249642)
							(end -0.1778 0.2794)
						)
						(arc
							(start 0.1778 0.2794)
							(mid 0.249642 0.249642)
							(end 0.2794 0.1778)
						)
						(arc
							(start 0.2794 -0.1778)
							(mid 0.249642 -0.249642)
							(end 0.1778 -0.2794)
						)
					)
					(width 0)
					(fill yes)
				)
			)
		)
	)
	(footprint ""
		(layer "F.Cu")
		(at 68.4022 -153.797 -90)
		(property "Reference" "R306"
			(at 0 0 270)
			(layer "F.SilkS")
			(hide yes)
			(effects
				(font
					(size 1.27 1.27)
				)
			)
		)
		(property "Value" "33R2J-2-GP"
			(at 0.064008 -3.993896 270)
			(unlocked yes)
			(layer "F.Fab")
			(hide yes)
			(effects
				(font
					(size 1.016 1.016)
					(thickness 0.1524)
				)
			)
		)
		(property "Device Type" "R402H16"
			(at 0.064008 -5.517896 270)
			(unlocked yes)
			(layer "F.Fab")
			(hide yes)
			(effects
				(font
					(size 1.016 1.016)
					(thickness 0.1524)
				)
			)
		)
		(duplicate_pad_numbers_are_jumpers no)
		(fp_line
			(start -0.508 -0.9398)
			(end -0.508 0.9398)
			(stroke
				(width 0.1524)
				(type default)
			)
			(layer "F.SilkS")
		)
		(fp_line
			(start 0.508 -0.9398)
			(end -0.508 -0.9398)
			(stroke
				(width 0.1524)
				(type default)
			)
			(layer "F.SilkS")
		)
		(fp_rect
			(start -0.508 0.9398)
			(end 0.508 -0.9398)
			(stroke
				(width 0)
				(type default)
			)
			(fill no)
			(layer "F.CrtYd")
		)
		(fp_rect
			(start -0.508 0.9398)
			(end 0.508 -0.9398)
			(stroke
				(width 0)
				(type default)
			)
			(fill no)
			(layer "F.Fab")
		)
		(pad "1" smd custom
			(at 0 -0.4445 270)
			(size 0.1397 0.1397)
			(layers "F.Cu" "F.Mask" "F.Paste")
			(net "50M_CLK_OUT")
			(options
				(clearance outline)
				(anchor circle)
			)
			(primitives
				(gr_poly
					(pts
						(arc
							(start -0.1778 -0.2794)
							(mid -0.249642 -0.249642)
							(end -0.2794 -0.1778)
						)
						(arc
							(start -0.2794 0.1778)
							(mid -0.249642 0.249642)
							(end -0.1778 0.2794)
						)
						(arc
							(start 0.1778 0.2794)
							(mid 0.249642 0.249642)
							(end 0.2794 0.1778)
						)
						(arc
							(start 0.2794 -0.1778)
							(mid 0.249642 -0.249642)
							(end 0.1778 -0.2794)
						)
					)
					(width 0)
					(fill yes)
				)
			)
		)
		(pad "2" smd custom
			(at 0 0.4445 270)
			(size 0.1397 0.1397)
			(layers "F.Cu" "F.Mask" "F.Paste")
			(net "50M_CLK_OUT_R")
			(options
				(clearance outline)
				(anchor circle)
			)
			(primitives
				(gr_poly
					(pts
						(arc
							(start -0.1778 -0.2794)
							(mid -0.249642 -0.249642)
							(end -0.2794 -0.1778)
						)
						(arc
							(start -0.2794 0.1778)
							(mid -0.249642 0.249642)
							(end -0.1778 0.2794)
						)
						(arc
							(start 0.1778 0.2794)
							(mid 0.249642 0.249642)
							(end 0.2794 0.1778)
						)
						(arc
							(start 0.2794 -0.1778)
							(mid 0.249642 -0.249642)
							(end 0.1778 -0.2794)
						)
					)
					(width 0)
					(fill yes)
				)
			)
		)
	)
	(footprint ""
		(layer "F.Cu")
		(at 66.929 -165.735 -90)
		(property "Reference" "Q2"
			(at 0 0 270)
			(layer "F.SilkS")
			(hide yes)
			(effects
				(font
					(size 1.27 1.27)
				)
			)
		)
		(property "Value" "MMBT3904-3-GP"
			(at 0.10287 -10.29843 270)
			(unlocked yes)
			(layer "F.Fab")
			(hide yes)
			(effects
				(font
					(size 1.016 1.016)
					(thickness 0.1524)
				)
			)
		)
		(property "Device Type" "SOT23CBE2D4H44"
			(at 0.10287 -12.20343 270)
			(unlocked yes)
			(layer "F.Fab")
			(hide yes)
			(effects
				(font
					(size 1.016 1.016)
					(thickness 0.1524)
				)
			)
		)
		(duplicate_pad_numbers_are_jumpers no)
		(fp_line
			(start -1.651 1.778)
			(end 1.651 1.778)
			(stroke
				(width 0.1524)
				(type default)
			)
			(layer "F.SilkS")
		)
		(fp_line
			(start 1.651 1.778)
			(end 1.651 -1.778)
			(stroke
				(width 0.1524)
				(type default)
			)
			(layer "F.SilkS")
		)
		(fp_line
			(start -1.651 -1.778)
			(end -1.651 1.778)
			(stroke
				(width 0.1524)
				(type default)
			)
			(layer "F.SilkS")
		)
		(fp_line
			(start 1.651 -1.778)
			(end -1.651 -1.778)
			(stroke
				(width 0.1524)
				(type default)
			)
			(layer "F.SilkS")
		)
		(fp_poly
			(pts
				(xy -1.778 1.8796) (xy -1.778 -1.8796) (xy 1.778 -1.8796) (xy 1.778 1.8796)
			)
			(stroke
				(width 0)
				(type default)
			)
			(fill no)
			(layer "F.CrtYd")
		)
		(fp_poly
			(pts
				(xy -1.778 1.8796) (xy -1.778 -1.8796) (xy 1.778 -1.8796) (xy 1.778 1.8796)
			)
			(stroke
				(width 0)
				(type default)
			)
			(fill no)
			(layer "F.Fab")
		)
		(pad "B" smd custom
			(at -0.98425 0.9525 270)
			(size 0.1905 0.1905)
			(layers "F.Cu" "F.Mask" "F.Paste")
			(net "FM_TPM_PRSNT_RST")
			(options
				(clearance outline)
				(anchor circle)
			)
			(primitives
				(gr_poly
					(pts
						(arc
							(start -0.1778 0.5715)
							(mid -0.321484 0.511984)
							(end -0.381 0.3683)
						)
						(arc
							(start -0.381 -0.3683)
							(mid -0.321484 -0.511984)
							(end -0.1778 -0.5715)
						)
						(arc
							(start 0.1778 -0.5715)
							(mid 0.321484 -0.511984)
							(end 0.381 -0.3683)
						)
						(arc
							(start 0.381 0.3683)
							(mid 0.321484 0.511984)
							(end 0.1778 0.5715)
						)
					)
					(width 0)
					(fill yes)
				)
			)
		)
		(pad "C" smd custom
			(at 0 -0.9525 270)
			(size 0.1905 0.1905)
			(layers "F.Cu" "F.Mask" "F.Paste")
			(net "BMC_TPM_RST_N")
			(options
				(clearance outline)
				(anchor circle)
			)
			(primitives
				(gr_poly
					(pts
						(arc
							(start -0.1778 0.5715)
							(mid -0.321484 0.511984)
							(end -0.381 0.3683)
						)
						(arc
							(start -0.381 -0.3683)
							(mid -0.321484 -0.511984)
							(end -0.1778 -0.5715)
						)
						(arc
							(start 0.1778 -0.5715)
							(mid 0.321484 -0.511984)
							(end 0.381 -0.3683)
						)
						(arc
							(start 0.381 0.3683)
							(mid 0.321484 0.511984)
							(end 0.1778 0.5715)
						)
					)
					(width 0)
					(fill yes)
				)
			)
		)
		(pad "E" smd custom
			(at 0.98425 0.9525 270)
			(size 0.1905 0.1905)
			(layers "F.Cu" "F.Mask" "F.Paste")
			(net "GND")
			(options
				(clearance outline)
				(anchor circle)
			)
			(primitives
				(gr_poly
					(pts
						(arc
							(start -0.1778 0.5715)
							(mid -0.321484 0.511984)
							(end -0.381 0.3683)
						)
						(arc
							(start -0.381 -0.3683)
							(mid -0.321484 -0.511984)
							(end -0.1778 -0.5715)
						)
						(arc
							(start 0.1778 -0.5715)
							(mid 0.321484 -0.511984)
							(end 0.381 -0.3683)
						)
						(arc
							(start 0.381 0.3683)
							(mid 0.321484 0.511984)
							(end 0.1778 0.5715)
						)
					)
					(width 0)
					(fill yes)
				)
			)
		)
	)
	(footprint ""
		(layer "F.Cu")
		(at 63.126874 -175.139096)
		(property "Reference" "U9"
			(at 0 0 0)
			(layer "F.SilkS")
			(hide yes)
			(effects
				(font
					(size 1.27 1.27)
				)
			)
		)
		(property "Value" "SN74LVC1G07DCKRG4-2-GP"
			(at -2.3368 -8.6868 0)
			(unlocked yes)
			(layer "F.Fab")
			(hide yes)
			(effects
				(font
					(size 1.016 1.016)
					(thickness 0.1524)
				)
			)
		)
		(property "Device Type" "SC70-5H44"
			(at -2.3114 -10.414 0)
			(unlocked yes)
			(layer "F.Fab")
			(hide yes)
			(effects
				(font
					(size 1.016 1.016)
					(thickness 0.1524)
				)
			)
		)
		(duplicate_pad_numbers_are_jumpers no)
		(fp_line
			(start -1.27 -1.7018)
			(end 1.27 -1.7018)
			(stroke
				(width 0.1524)
				(type default)
			)
			(layer "F.SilkS")
		)
		(fp_line
			(start -1.27 1.7018)
			(end -1.27 -1.7018)
			(stroke
				(width 0.1524)
				(type default)
			)
			(layer "F.SilkS")
		)
		(fp_line
			(start 0.6604 -1.8034)
			(end 1.3843 -1.8034)
			(stroke
				(width 0.3302)
				(type default)
			)
			(layer "F.SilkS")
		)
		(fp_line
			(start 1.27 -1.7018)
			(end 1.27 1.7018)
			(stroke
				(width 0.1524)
				(type default)
			)
			(layer "F.SilkS")
		)
		(fp_line
			(start 1.27 1.7018)
			(end -1.27 1.7018)
			(stroke
				(width 0.1524)
				(type default)
			)
			(layer "F.SilkS")
		)
		(fp_line
			(start 1.3843 -1.8034)
			(end 1.3843 -1.1176)
			(stroke
				(width 0.3302)
				(type default)
			)
			(layer "F.SilkS")
		)
		(fp_rect
			(start -1.524 1.9558)
			(end 1.524 -1.9558)
			(stroke
				(width 0)
				(type default)
			)
			(fill no)
			(layer "F.CrtYd")
		)
		(fp_poly
			(pts
				(xy -1.524 -1.9558) (xy 1.524 -1.9558) (xy 1.524 1.9558) (xy -1.524 1.9558)
			)
			(stroke
				(width 0)
				(type default)
			)
			(fill no)
			(layer "F.Fab")
		)
		(pad "1" smd rect
			(at 0.65024 -0.8255)
			(size 0.4064 1.2192)
			(layers "F.Cu" "F.Mask" "F.Paste")
			(net "Net_312")
		)
		(pad "2" smd rect
			(at 0 -0.8255)
			(size 0.4064 1.2192)
			(layers "F.Cu" "F.Mask" "F.Paste")
			(net "FM_BMC_RESET_N")
		)
		(pad "3" smd rect
			(at -0.65024 -0.8255)
			(size 0.4064 1.2192)
			(layers "F.Cu" "F.Mask" "F.Paste")
			(net "GND")
		)
		(pad "4" smd rect
			(at -0.65024 0.8255)
			(size 0.4064 1.2192)
			(layers "F.Cu" "F.Mask" "F.Paste")
			(net "FM_TPM_PRSNT_RST_N_C")
		)
		(pad "5" smd rect
			(at 0.65024 0.8255)
			(size 0.4064 1.2192)
			(layers "F.Cu" "F.Mask" "F.Paste")
			(net "P3V3_STBY")
		)
	)
	(footprint ""
		(layer "F.Cu")
		(at 63.2841 -146.8882 90)
		(property "Reference" "R190"
			(at 0 0 90)
			(layer "F.SilkS")
			(hide yes)
			(effects
				(font
					(size 1.27 1.27)
				)
			)
		)
		(property "Value" "499R2F-2-GP"
			(at 0.064008 -3.993896 90)
			(unlocked yes)
			(layer "F.Fab")
			(hide yes)
			(effects
				(font
					(size 1.016 1.016)
					(thickness 0.1524)
				)
			)
		)
		(property "Device Type" "R402H16"
			(at 0.064008 -5.517896 90)
			(unlocked yes)
			(layer "F.Fab")
			(hide yes)
			(effects
				(font
					(size 1.016 1.016)
					(thickness 0.1524)
				)
			)
		)
		(duplicate_pad_numbers_are_jumpers no)
		(fp_line
			(start 0.508 -0.9398)
			(end -0.508 -0.9398)
			(stroke
				(width 0.1524)
				(type default)
			)
			(layer "F.SilkS")
		)
		(fp_line
			(start -0.508 -0.9398)
			(end -0.508 0.9398)
			(stroke
				(width 0.1524)
				(type default)
			)
			(layer "F.SilkS")
		)
		(fp_rect
			(start -0.508 0.9398)
			(end 0.508 -0.9398)
			(stroke
				(width 0)
				(type default)
			)
			(fill no)
			(layer "F.CrtYd")
		)
		(fp_rect
			(start -0.508 0.9398)
			(end 0.508 -0.9398)
			(stroke
				(width 0)
				(type default)
			)
			(fill no)
			(layer "F.Fab")
		)
		(pad "1" smd custom
			(at 0 -0.4445 90)
			(size 0.1397 0.1397)
			(layers "F.Cu" "F.Mask" "F.Paste")
			(net "I2C_BMC_COMP_SDA_OUT")
			(options
				(clearance outline)
				(anchor circle)
			)
			(primitives
				(gr_poly
					(pts
						(arc
							(start -0.1778 -0.2794)
							(mid -0.249642 -0.249642)
							(end -0.2794 -0.1778)
						)
						(arc
							(start -0.2794 0.1778)
							(mid -0.249642 0.249642)
							(end -0.1778 0.2794)
						)
						(arc
							(start 0.1778 0.2794)
							(mid 0.249642 0.249642)
							(end 0.2794 0.1778)
						)
						(arc
							(start 0.2794 -0.1778)
							(mid 0.249642 -0.249642)
							(end 0.1778 -0.2794)
						)
					)
					(width 0)
					(fill yes)
				)
			)
		)
		(pad "2" smd custom
			(at 0 0.4445 90)
			(size 0.1397 0.1397)
			(layers "F.Cu" "F.Mask" "F.Paste")
			(net "P3V3_STBY")
			(options
				(clearance outline)
				(anchor circle)
			)
			(primitives
				(gr_poly
					(pts
						(arc
							(start -0.1778 -0.2794)
							(mid -0.249642 -0.249642)
							(end -0.2794 -0.1778)
						)
						(arc
							(start -0.2794 0.1778)
							(mid -0.249642 0.249642)
							(end -0.1778 0.2794)
						)
						(arc
							(start 0.1778 0.2794)
							(mid 0.249642 0.249642)
							(end 0.2794 0.1778)
						)
						(arc
							(start 0.2794 -0.1778)
							(mid 0.249642 -0.249642)
							(end 0.1778 -0.2794)
						)
					)
					(width 0)
					(fill yes)
				)
			)
		)
	)
	(footprint ""
		(layer "F.Cu")
		(at 94.810072 -13.671042 90)
		(property "Reference" "D15"
			(at 0 0 90)
			(layer "F.SilkS")
			(hide yes)
			(effects
				(font
					(size 1.27 1.27)
				)
			)
		)
		(property "Value" "PESD5V0S1BL-1-GP"
			(at 1.8923 -1.5621 90)
			(unlocked yes)
			(layer "F.Fab")
			(hide yes)
			(effects
				(font
					(size 1.016 1.016)
					(thickness 0.1524)
				)
			)
		)
		(property "Device Type" "SOD882-10D6-1H20"
			(at 1.8923 -3.0861 90)
			(unlocked yes)
			(layer "F.Fab")
			(hide yes)
			(effects
				(font
					(size 1.016 1.016)
					(thickness 0.1524)
				)
			)
		)
		(duplicate_pad_numbers_are_jumpers no)
		(fp_line
			(start -0.3048 -0.9271)
			(end 0.3048 -0.9271)
			(stroke
				(width 0.254)
				(type default)
			)
			(layer "F.SilkS")
		)
		(fp_rect
			(start -0.2921 0.4953)
			(end 0.2921 -0.4953)
			(stroke
				(width 0)
				(type default)
			)
			(fill no)
			(layer "F.CrtYd")
		)
		(fp_poly
			(pts
				(xy -0.4318 0.8001) (xy -0.4318 -0.266192) (xy -0.2921 -0.266192) (xy -0.2921 0.4953) (xy 0.2921 0.4953)
				(xy 0.2921 -0.4953) (xy -0.2921 -0.4953) (xy -0.2921 -0.2667) (xy -0.4318 -0.2667) (xy -0.4318 -0.8001)
				(xy 0.4318 -0.8001) (xy 0.4318 0.8001)
			)
			(stroke
				(width 0)
				(type default)
			)
			(fill no)
			(layer "F.CrtYd")
		)
		(fp_rect
			(start -0.4318 0.8001)
			(end 0.4318 -0.8001)
			(stroke
				(width 0)
				(type default)
			)
			(fill no)
			(layer "F.Fab")
		)
		(pad "1" smd custom
			(at 0 -0.4445 90)
			(size 0.1143 0.1143)
			(layers "F.Cu" "F.Mask" "F.Paste")
			(net "I2C_DEBUG_SDA")
			(options
				(clearance outline)
				(anchor circle)
			)
			(primitives
				(gr_poly
					(pts
						(arc
							(start -0.2032 0.2286)
							(mid -0.275042 0.198842)
							(end -0.3048 0.127)
						)
						(arc
							(start -0.3048 -0.127)
							(mid -0.275042 -0.198842)
							(end -0.2032 -0.2286)
						)
						(arc
							(start 0.2032 -0.2286)
							(mid 0.275042 -0.198842)
							(end 0.3048 -0.127)
						)
						(arc
							(start 0.3048 0.127)
							(mid 0.275042 0.198842)
							(end 0.2032 0.2286)
						)
					)
					(width 0)
					(fill yes)
				)
			)
		)
		(pad "2" smd custom
			(at 0 0.4445 90)
			(size 0.1143 0.1143)
			(layers "F.Cu" "F.Mask" "F.Paste")
			(net "GND")
			(options
				(clearance outline)
				(anchor circle)
			)
			(primitives
				(gr_poly
					(pts
						(arc
							(start 0.2032 -0.2286)
							(mid 0.275042 -0.198842)
							(end 0.3048 -0.127)
						)
						(arc
							(start 0.3048 0.127)
							(mid 0.275042 0.198842)
							(end 0.2032 0.2286)
						)
						(arc
							(start -0.2032 0.2286)
							(mid -0.275042 0.198842)
							(end -0.3048 0.127)
						)
						(arc
							(start -0.3048 -0.127)
							(mid -0.275042 -0.198842)
							(end -0.2032 -0.2286)
						)
					)
					(width 0)
					(fill yes)
				)
			)
		)
	)
	(footprint ""
		(layer "F.Cu")
		(at 53.773324 -162.481768 180)
		(property "Reference" "R412"
			(at 0 0 180)
			(layer "F.SilkS")
			(hide yes)
			(effects
				(font
					(size 1.27 1.27)
				)
			)
		)
		(property "Value" "1KR2F-3-GP"
			(at 0.064008 -3.993896 180)
			(unlocked yes)
			(layer "F.Fab")
			(hide yes)
			(effects
				(font
					(size 1.016 1.016)
					(thickness 0.1524)
				)
			)
		)
		(property "Device Type" "R402H16"
			(at 0.064008 -5.517896 180)
			(unlocked yes)
			(layer "F.Fab")
			(hide yes)
			(effects
				(font
					(size 1.016 1.016)
					(thickness 0.1524)
				)
			)
		)
		(duplicate_pad_numbers_are_jumpers no)
		(fp_line
			(start 0.508 -0.9398)
			(end -0.508 -0.9398)
			(stroke
				(width 0.1524)
				(type default)
			)
			(layer "F.SilkS")
		)
		(fp_line
			(start -0.508 -0.9398)
			(end -0.508 0.9398)
			(stroke
				(width 0.1524)
				(type default)
			)
			(layer "F.SilkS")
		)
		(fp_rect
			(start -0.508 0.9398)
			(end 0.508 -0.9398)
			(stroke
				(width 0)
				(type default)
			)
			(fill no)
			(layer "F.CrtYd")
		)
		(fp_rect
			(start -0.508 0.9398)
			(end 0.508 -0.9398)
			(stroke
				(width 0)
				(type default)
			)
			(fill no)
			(layer "F.Fab")
		)
		(pad "1" smd custom
			(at 0 -0.4445 180)
			(size 0.1397 0.1397)
			(layers "F.Cu" "F.Mask" "F.Paste")
			(net "ADC_P3V3")
			(options
				(clearance outline)
				(anchor circle)
			)
			(primitives
				(gr_poly
					(pts
						(arc
							(start -0.1778 -0.2794)
							(mid -0.249642 -0.249642)
							(end -0.2794 -0.1778)
						)
						(arc
							(start -0.2794 0.1778)
							(mid -0.249642 0.249642)
							(end -0.1778 0.2794)
						)
						(arc
							(start 0.1778 0.2794)
							(mid 0.249642 0.249642)
							(end 0.2794 0.1778)
						)
						(arc
							(start 0.2794 -0.1778)
							(mid 0.249642 -0.249642)
							(end 0.1778 -0.2794)
						)
					)
					(width 0)
					(fill yes)
				)
			)
		)
		(pad "2" smd custom
			(at 0 0.4445 180)
			(size 0.1397 0.1397)
			(layers "F.Cu" "F.Mask" "F.Paste")
			(net "GND")
			(options
				(clearance outline)
				(anchor circle)
			)
			(primitives
				(gr_poly
					(pts
						(arc
							(start -0.1778 -0.2794)
							(mid -0.249642 -0.249642)
							(end -0.2794 -0.1778)
						)
						(arc
							(start -0.2794 0.1778)
							(mid -0.249642 0.249642)
							(end -0.1778 0.2794)
						)
						(arc
							(start 0.1778 0.2794)
							(mid 0.249642 0.249642)
							(end 0.2794 0.1778)
						)
						(arc
							(start 0.2794 -0.1778)
							(mid 0.249642 -0.249642)
							(end 0.1778 -0.2794)
						)
					)
					(width 0)
					(fill yes)
				)
			)
		)
	)
	(footprint ""
		(layer "F.Cu")
		(at 188.930788 -122.010932 90)
		(property "Reference" "PU8"
			(at 0 0 90)
			(layer "F.SilkS")
			(hide yes)
			(effects
				(font
					(size 1.27 1.27)
				)
			)
		)
		(property "Value" "VT235WFQX-ADJ-1-GP"
			(at -5.8166 -7.7216 90)
			(unlocked yes)
			(layer "F.Fab")
			(hide yes)
			(effects
				(font
					(size 1.016 1.016)
					(thickness 0.1524)
				)
			)
		)
		(property "Device Type" "QFN19-1H40"
			(at -5.8166 -9.2456 90)
			(unlocked yes)
			(layer "F.Fab")
			(hide yes)
			(effects
				(font
					(size 1.016 1.016)
					(thickness 0.1524)
				)
			)
		)
		(duplicate_pad_numbers_are_jumpers no)
		(fp_line
			(start -1.4859 -3.0734)
			(end -2.7559 -3.0734)
			(stroke
				(width 0.1524)
				(type default)
			)
			(layer "F.SilkS")
		)
		(fp_line
			(start -2.7559 -3.0734)
			(end -2.7559 -1.8034)
			(stroke
				(width 0.1524)
				(type default)
			)
			(layer "F.SilkS")
		)
		(fp_line
			(start -1.253236 -2.821432)
			(end -1.253236 -3.329432)
			(stroke
				(width 0.1524)
				(type default)
			)
			(layer "F.SilkS")
		)
		(fp_line
			(start 2.821432 0.23876)
			(end 3.329432 0.23876)
			(stroke
				(width 0.1524)
				(type default)
			)
			(layer "F.SilkS")
		)
		(fp_line
			(start -2.7559 1.8034)
			(end -2.7559 3.0734)
			(stroke
				(width 0.1524)
				(type default)
			)
			(layer "F.SilkS")
		)
		(fp_line
			(start 0.766064 2.796032)
			(end 0.766064 3.558032)
			(stroke
				(width 0.1524)
				(type default)
			)
			(layer "F.SilkS")
		)
		(fp_line
			(start 3.0861 3.0734)
			(end 3.0861 1.8034)
			(stroke
				(width 0.1524)
				(type default)
			)
			(layer "F.SilkS")
		)
		(fp_line
			(start 1.8161 3.0734)
			(end 3.0861 3.0734)
			(stroke
				(width 0.1524)
				(type default)
			)
			(layer "F.SilkS")
		)
		(fp_line
			(start -2.7559 3.0734)
			(end -1.4859 3.0734)
			(stroke
				(width 0.1524)
				(type default)
			)
			(layer "F.SilkS")
		)
		(fp_poly
			(pts
				(xy 3.0861 -3.0734) (xy 1.8161 -3.0734) (xy 3.0861 -1.8034)
			)
			(stroke
				(width 0)
				(type default)
			)
			(fill yes)
			(layer "F.SilkS")
		)
		(fp_rect
			(start -2.2479 2.2479)
			(end 2.2479 -2.2479)
			(stroke
				(width 0)
				(type default)
			)
			(fill no)
			(layer "F.CrtYd")
		)
		(fp_poly
			(pts
				(xy -2.7559 -3.0734) (xy -2.7559 3.0734) (xy 3.0861 3.0734) (xy 3.0861 2.0193) (xy 2.2479 2.0193)
				(xy 2.2479 2.2479) (xy -2.2479 2.2479) (xy -2.2479 -2.2479) (xy 2.2479 -2.2479) (xy 2.2479 2.0066)
				(xy 3.0861 2.0066) (xy 3.0861 -3.0734)
			)
			(stroke
				(width 0)
				(type default)
			)
			(fill no)
			(layer "F.CrtYd")
		)
		(fp_rect
			(start -2.7559 3.0734)
			(end 3.0861 -3.0734)
			(stroke
				(width 0)
				(type default)
			)
			(fill no)
			(layer "F.Fab")
		)
		(pad "1" smd rect
			(at 1.249934 -2.135632 90)
			(size 0.3556 0.8382)
			(layers "F.Cu" "F.Mask" "F.Paste")
			(net "AGND_P0V975")
		)
		(pad "2" smd rect
			(at 0.750062 -2.135632 90)
			(size 0.3556 0.8382)
			(layers "F.Cu" "F.Mask" "F.Paste")
			(net "Net_658")
		)
		(pad "3" smd rect
			(at 0.249936 -2.135632 90)
			(size 0.3556 0.8382)
			(layers "F.Cu" "F.Mask" "F.Paste")
			(net "VT235_AVDD")
		)
		(pad "4" smd rect
			(at -0.249936 -0.687832 90)
			(size 0.3556 3.7338)
			(layers "F.Cu" "F.Mask" "F.Paste")
			(net "VT235_VDDH")
		)
		(pad "5" smd rect
			(at -1.249934 -1.335532 90)
			(size 0.3556 2.4384)
			(layers "F.Cu" "F.Mask" "F.Paste")
			(net "GND")
		)
		(pad "6" smd rect
			(at -1.75006 1.335532 90)
			(size 0.3556 2.4384)
			(layers "F.Cu" "F.Mask" "F.Paste")
			(net "VT235_VX")
		)
		(pad "7" smd rect
			(at -0.750062 1.335532 90)
			(size 0.3556 2.4384)
			(layers "F.Cu" "F.Mask" "F.Paste")
			(net "VT235_VX")
		)
		(pad "8" smd rect
			(at -0.249936 2.135632 90)
			(size 0.3556 0.8382)
			(layers "F.Cu" "F.Mask" "F.Paste")
			(net "VT235_BST")
		)
		(pad "9" smd rect
			(at 0.249936 2.135632 90)
			(size 0.3556 0.8382)
			(layers "F.Cu" "F.Mask" "F.Paste")
			(net "VT235_VDDL")
		)
		(pad "10" smd rect
			(at 0.750062 2.135632 90)
			(size 0.3556 0.8382)
			(layers "F.Cu" "F.Mask" "F.Paste")
			(net "VT235_AVDD")
		)
		(pad "11" smd rect
			(at 1.249934 2.135632 90)
			(size 0.3556 0.8382)
			(layers "F.Cu" "F.Mask" "F.Paste")
			(net "VT235_VFB")
		)
		(pad "12" smd rect
			(at 2.135632 1.75006 90)
			(size 0.8382 0.3556)
			(layers "F.Cu" "F.Mask" "F.Paste")
			(net "VT235_PGIN")
		)
		(pad "13" smd rect
			(at 2.135632 1.249934 90)
			(size 0.8382 0.3556)
			(layers "F.Cu" "F.Mask" "F.Paste")
			(net "VT235_VDES")
		)
		(pad "14" smd rect
			(at 2.135632 0.750062 90)
			(size 0.8382 0.3556)
			(layers "F.Cu" "F.Mask" "F.Paste")
			(net "VT235_VREF")
		)
		(pad "15" smd rect
			(at 2.135632 0.249936 90)
			(size 0.8382 0.3556)
			(layers "F.Cu" "F.Mask" "F.Paste")
			(net "VT235_BIAS")
		)
		(pad "16" smd rect
			(at 2.135632 -0.249936 90)
			(size 0.8382 0.3556)
			(layers "F.Cu" "F.Mask" "F.Paste")
			(net "VT235_IMAX")
		)
		(pad "17" smd rect
			(at 2.135632 -0.750062 90)
			(size 0.8382 0.3556)
			(layers "F.Cu" "F.Mask" "F.Paste")
			(net "IOM_FULL_PGOOD")
		)
		(pad "18" smd rect
			(at 2.135632 -1.249934 90)
			(size 0.8382 0.3556)
			(layers "F.Cu" "F.Mask" "F.Paste")
			(net "VT235_EN")
		)
		(pad "19" smd rect
			(at 2.135632 -1.75006 90)
			(size 0.8382 0.3556)
			(layers "F.Cu" "F.Mask" "F.Paste")
			(net "VT235_IRIP")
		)
	)
	(footprint ""
		(layer "F.Cu")
		(at 42.3164 -131.7498 180)
		(property "Reference" "R263"
			(at 0 0 180)
			(layer "F.SilkS")
			(hide yes)
			(effects
				(font
					(size 1.27 1.27)
				)
			)
		)
		(property "Value" "4K7R2F-GP"
			(at 0.064008 -3.993896 180)
			(unlocked yes)
			(layer "F.Fab")
			(hide yes)
			(effects
				(font
					(size 1.016 1.016)
					(thickness 0.1524)
				)
			)
		)
		(property "Device Type" "R402H16"
			(at 0.064008 -5.517896 180)
			(unlocked yes)
			(layer "F.Fab")
			(hide yes)
			(effects
				(font
					(size 1.016 1.016)
					(thickness 0.1524)
				)
			)
		)
		(duplicate_pad_numbers_are_jumpers no)
		(fp_line
			(start 0.508 -0.9398)
			(end -0.508 -0.9398)
			(stroke
				(width 0.1524)
				(type default)
			)
			(layer "F.SilkS")
		)
		(fp_line
			(start -0.508 -0.9398)
			(end -0.508 0.9398)
			(stroke
				(width 0.1524)
				(type default)
			)
			(layer "F.SilkS")
		)
		(fp_rect
			(start -0.508 0.9398)
			(end 0.508 -0.9398)
			(stroke
				(width 0)
				(type default)
			)
			(fill no)
			(layer "F.CrtYd")
		)
		(fp_rect
			(start -0.508 0.9398)
			(end 0.508 -0.9398)
			(stroke
				(width 0)
				(type default)
			)
			(fill no)
			(layer "F.Fab")
		)
		(pad "1" smd custom
			(at 0 -0.4445 180)
			(size 0.1397 0.1397)
			(layers "F.Cu" "F.Mask" "F.Paste")
			(net "P3V3_STBY")
			(options
				(clearance outline)
				(anchor circle)
			)
			(primitives
				(gr_poly
					(pts
						(arc
							(start -0.1778 -0.2794)
							(mid -0.249642 -0.249642)
							(end -0.2794 -0.1778)
						)
						(arc
							(start -0.2794 0.1778)
							(mid -0.249642 0.249642)
							(end -0.1778 0.2794)
						)
						(arc
							(start 0.1778 0.2794)
							(mid 0.249642 0.249642)
							(end 0.2794 0.1778)
						)
						(arc
							(start 0.2794 -0.1778)
							(mid 0.249642 -0.249642)
							(end 0.1778 -0.2794)
						)
					)
					(width 0)
					(fill yes)
				)
			)
		)
		(pad "2" smd custom
			(at 0 0.4445 180)
			(size 0.1397 0.1397)
			(layers "F.Cu" "F.Mask" "F.Paste")
			(net "BMC_GPIOY1")
			(options
				(clearance outline)
				(anchor circle)
			)
			(primitives
				(gr_poly
					(pts
						(arc
							(start -0.1778 -0.2794)
							(mid -0.249642 -0.249642)
							(end -0.2794 -0.1778)
						)
						(arc
							(start -0.2794 0.1778)
							(mid -0.249642 0.249642)
							(end -0.1778 0.2794)
						)
						(arc
							(start 0.1778 0.2794)
							(mid 0.249642 0.249642)
							(end 0.2794 0.1778)
						)
						(arc
							(start 0.2794 -0.1778)
							(mid 0.249642 -0.249642)
							(end 0.1778 -0.2794)
						)
					)
					(width 0)
					(fill yes)
				)
			)
		)
	)
	(footprint ""
		(layer "F.Cu")
		(at 61.543184 -142.417292 90)
		(property "Reference" "R155"
			(at 0 0 90)
			(layer "F.SilkS")
			(hide yes)
			(effects
				(font
					(size 1.27 1.27)
				)
			)
		)
		(property "Value" "0R2J-2-GP"
			(at 0.064008 -3.993896 90)
			(unlocked yes)
			(layer "F.Fab")
			(hide yes)
			(effects
				(font
					(size 1.016 1.016)
					(thickness 0.1524)
				)
			)
		)
		(property "Device Type" "R402H16"
			(at 0.064008 -5.517896 90)
			(unlocked yes)
			(layer "F.Fab")
			(hide yes)
			(effects
				(font
					(size 1.016 1.016)
					(thickness 0.1524)
				)
			)
		)
		(duplicate_pad_numbers_are_jumpers no)
		(fp_line
			(start 0.508 -0.9398)
			(end -0.508 -0.9398)
			(stroke
				(width 0.1524)
				(type default)
			)
			(layer "F.SilkS")
		)
		(fp_line
			(start -0.508 -0.9398)
			(end -0.508 0.9398)
			(stroke
				(width 0.1524)
				(type default)
			)
			(layer "F.SilkS")
		)
		(fp_rect
			(start -0.508 0.9398)
			(end 0.508 -0.9398)
			(stroke
				(width 0)
				(type default)
			)
			(fill no)
			(layer "F.CrtYd")
		)
		(fp_rect
			(start -0.508 0.9398)
			(end 0.508 -0.9398)
			(stroke
				(width 0)
				(type default)
			)
			(fill no)
			(layer "F.Fab")
		)
		(pad "1" smd custom
			(at 0 -0.4445 90)
			(size 0.1397 0.1397)
			(layers "F.Cu" "F.Mask" "F.Paste")
			(net "BMC_SMB11_CLK")
			(options
				(clearance outline)
				(anchor circle)
			)
			(primitives
				(gr_poly
					(pts
						(arc
							(start -0.1778 -0.2794)
							(mid -0.249642 -0.249642)
							(end -0.2794 -0.1778)
						)
						(arc
							(start -0.2794 0.1778)
							(mid -0.249642 0.249642)
							(end -0.1778 0.2794)
						)
						(arc
							(start 0.1778 0.2794)
							(mid 0.249642 0.249642)
							(end 0.2794 0.1778)
						)
						(arc
							(start 0.2794 -0.1778)
							(mid 0.249642 -0.249642)
							(end 0.1778 -0.2794)
						)
					)
					(width 0)
					(fill yes)
				)
			)
		)
		(pad "2" smd custom
			(at 0 0.4445 90)
			(size 0.1397 0.1397)
			(layers "F.Cu" "F.Mask" "F.Paste")
			(net "I2C_EXP_RMT_SCL_OUT")
			(options
				(clearance outline)
				(anchor circle)
			)
			(primitives
				(gr_poly
					(pts
						(arc
							(start -0.1778 -0.2794)
							(mid -0.249642 -0.249642)
							(end -0.2794 -0.1778)
						)
						(arc
							(start -0.2794 0.1778)
							(mid -0.249642 0.249642)
							(end -0.1778 0.2794)
						)
						(arc
							(start 0.1778 0.2794)
							(mid 0.249642 0.249642)
							(end 0.2794 0.1778)
						)
						(arc
							(start 0.2794 -0.1778)
							(mid 0.249642 -0.249642)
							(end 0.1778 -0.2794)
						)
					)
					(width 0)
					(fill yes)
				)
			)
		)
	)
	(footprint ""
		(layer "F.Cu")
		(at 68.199 -145.3134 -90)
		(property "Reference" "R380"
			(at 0 0 270)
			(layer "F.SilkS")
			(hide yes)
			(effects
				(font
					(size 1.27 1.27)
				)
			)
		)
		(property "Value" "4K7R2F-GP"
			(at 0.064008 -3.993896 270)
			(unlocked yes)
			(layer "F.Fab")
			(hide yes)
			(effects
				(font
					(size 1.016 1.016)
					(thickness 0.1524)
				)
			)
		)
		(property "Device Type" "R402H16"
			(at 0.064008 -5.517896 270)
			(unlocked yes)
			(layer "F.Fab")
			(hide yes)
			(effects
				(font
					(size 1.016 1.016)
					(thickness 0.1524)
				)
			)
		)
		(duplicate_pad_numbers_are_jumpers no)
		(fp_line
			(start -0.508 -0.9398)
			(end -0.508 0.9398)
			(stroke
				(width 0.1524)
				(type default)
			)
			(layer "F.SilkS")
		)
		(fp_line
			(start 0.508 -0.9398)
			(end -0.508 -0.9398)
			(stroke
				(width 0.1524)
				(type default)
			)
			(layer "F.SilkS")
		)
		(fp_rect
			(start -0.508 0.9398)
			(end 0.508 -0.9398)
			(stroke
				(width 0)
				(type default)
			)
			(fill no)
			(layer "F.CrtYd")
		)
		(fp_rect
			(start -0.508 0.9398)
			(end 0.508 -0.9398)
			(stroke
				(width 0)
				(type default)
			)
			(fill no)
			(layer "F.Fab")
		)
		(pad "1" smd custom
			(at 0 -0.4445 270)
			(size 0.1397 0.1397)
			(layers "F.Cu" "F.Mask" "F.Paste")
			(net "P3V3_STBY")
			(options
				(clearance outline)
				(anchor circle)
			)
			(primitives
				(gr_poly
					(pts
						(arc
							(start -0.1778 -0.2794)
							(mid -0.249642 -0.249642)
							(end -0.2794 -0.1778)
						)
						(arc
							(start -0.2794 0.1778)
							(mid -0.249642 0.249642)
							(end -0.1778 0.2794)
						)
						(arc
							(start 0.1778 0.2794)
							(mid 0.249642 0.249642)
							(end 0.2794 0.1778)
						)
						(arc
							(start 0.2794 -0.1778)
							(mid 0.249642 -0.249642)
							(end 0.1778 -0.2794)
						)
					)
					(width 0)
					(fill yes)
				)
			)
		)
		(pad "2" smd custom
			(at 0 0.4445 270)
			(size 0.1397 0.1397)
			(layers "F.Cu" "F.Mask" "F.Paste")
			(net "NCSI_TXEN")
			(options
				(clearance outline)
				(anchor circle)
			)
			(primitives
				(gr_poly
					(pts
						(arc
							(start -0.1778 -0.2794)
							(mid -0.249642 -0.249642)
							(end -0.2794 -0.1778)
						)
						(arc
							(start -0.2794 0.1778)
							(mid -0.249642 0.249642)
							(end -0.1778 0.2794)
						)
						(arc
							(start 0.1778 0.2794)
							(mid 0.249642 0.249642)
							(end 0.2794 0.1778)
						)
						(arc
							(start 0.2794 -0.1778)
							(mid 0.249642 -0.249642)
							(end 0.1778 -0.2794)
						)
					)
					(width 0)
					(fill yes)
				)
			)
		)
	)
	(footprint ""
		(layer "F.Cu")
		(at 159.644588 -93.504512 -90)
		(property "Reference" "C482"
			(at 0 0 270)
			(layer "F.SilkS")
			(hide yes)
			(effects
				(font
					(size 1.27 1.27)
				)
			)
		)
		(property "Value" "SCD1U16V2KX-3GP"
			(at 1.1811 -2.7051 270)
			(unlocked yes)
			(layer "F.Fab")
			(hide yes)
			(effects
				(font
					(size 1.016 1.016)
					(thickness 0.1524)
				)
			)
		)
		(property "Device Type" "C402H22"
			(at 1.1811 -4.2291 270)
			(unlocked yes)
			(layer "F.Fab")
			(hide yes)
			(effects
				(font
					(size 1.016 1.016)
					(thickness 0.1524)
				)
			)
		)
		(duplicate_pad_numbers_are_jumpers no)
		(fp_rect
			(start -0.4318 0.9525)
			(end 0.4318 -0.9525)
			(stroke
				(width 0)
				(type default)
			)
			(fill no)
			(layer "F.CrtYd")
		)
		(fp_rect
			(start -0.4318 0.9525)
			(end 0.4318 -0.9525)
			(stroke
				(width 0)
				(type default)
			)
			(fill no)
			(layer "F.Fab")
		)
		(pad "1" smd custom
			(at 0 -0.4445 270)
			(size 0.1524 0.1524)
			(layers "F.Cu" "F.Mask" "F.Paste")
			(net "U43_VREF2")
			(options
				(clearance outline)
				(anchor circle)
			)
			(primitives
				(gr_poly
					(pts
						(arc
							(start 0.3048 -0.2032)
							(mid 0.275042 -0.275042)
							(end 0.2032 -0.3048)
						)
						(arc
							(start -0.2032 -0.3048)
							(mid -0.275042 -0.275042)
							(end -0.3048 -0.2032)
						)
						(arc
							(start -0.3048 0.2032)
							(mid -0.275042 0.275042)
							(end -0.2032 0.3048)
						)
						(arc
							(start 0.2032 0.3048)
							(mid 0.275042 0.275042)
							(end 0.3048 0.2032)
						)
					)
					(width 0)
					(fill yes)
				)
			)
		)
		(pad "2" smd custom
			(at 0 0.4445 270)
			(size 0.1524 0.1524)
			(layers "F.Cu" "F.Mask" "F.Paste")
			(net "GND")
			(options
				(clearance outline)
				(anchor circle)
			)
			(primitives
				(gr_poly
					(pts
						(arc
							(start 0.3048 -0.2032)
							(mid 0.275042 -0.275042)
							(end 0.2032 -0.3048)
						)
						(arc
							(start -0.2032 -0.3048)
							(mid -0.275042 -0.275042)
							(end -0.3048 -0.2032)
						)
						(arc
							(start -0.3048 0.2032)
							(mid -0.275042 0.275042)
							(end -0.2032 0.3048)
						)
						(arc
							(start 0.2032 0.3048)
							(mid 0.275042 0.275042)
							(end 0.3048 0.2032)
						)
					)
					(width 0)
					(fill yes)
				)
			)
		)
	)
	(footprint ""
		(layer "F.Cu")
		(at 29.832046 -176.618138 180)
		(property "Reference" "R494"
			(at 0 0 180)
			(layer "F.SilkS")
			(hide yes)
			(effects
				(font
					(size 1.27 1.27)
				)
			)
		)
		(property "Value" "57K6R2D-GP"
			(at 0.064008 -3.993896 180)
			(unlocked yes)
			(layer "F.Fab")
			(hide yes)
			(effects
				(font
					(size 1.016 1.016)
					(thickness 0.1524)
				)
			)
		)
		(property "Device Type" "R402H16"
			(at 0.064008 -5.517896 180)
			(unlocked yes)
			(layer "F.Fab")
			(hide yes)
			(effects
				(font
					(size 1.016 1.016)
					(thickness 0.1524)
				)
			)
		)
		(duplicate_pad_numbers_are_jumpers no)
		(fp_line
			(start 0.508 -0.9398)
			(end -0.508 -0.9398)
			(stroke
				(width 0.1524)
				(type default)
			)
			(layer "F.SilkS")
		)
		(fp_line
			(start -0.508 -0.9398)
			(end -0.508 0.9398)
			(stroke
				(width 0.1524)
				(type default)
			)
			(layer "F.SilkS")
		)
		(fp_rect
			(start -0.508 0.9398)
			(end 0.508 -0.9398)
			(stroke
				(width 0)
				(type default)
			)
			(fill no)
			(layer "F.CrtYd")
		)
		(fp_rect
			(start -0.508 0.9398)
			(end 0.508 -0.9398)
			(stroke
				(width 0)
				(type default)
			)
			(fill no)
			(layer "F.Fab")
		)
		(pad "1" smd custom
			(at 0 -0.4445 180)
			(size 0.1397 0.1397)
			(layers "F.Cu" "F.Mask" "F.Paste")
			(net "AGND_P3V3_STBY")
			(options
				(clearance outline)
				(anchor circle)
			)
			(primitives
				(gr_poly
					(pts
						(arc
							(start -0.1778 -0.2794)
							(mid -0.249642 -0.249642)
							(end -0.2794 -0.1778)
						)
						(arc
							(start -0.2794 0.1778)
							(mid -0.249642 0.249642)
							(end -0.1778 0.2794)
						)
						(arc
							(start 0.1778 0.2794)
							(mid 0.249642 0.249642)
							(end 0.2794 0.1778)
						)
						(arc
							(start 0.2794 -0.1778)
							(mid 0.249642 -0.249642)
							(end 0.1778 -0.2794)
						)
					)
					(width 0)
					(fill yes)
				)
			)
		)
		(pad "2" smd custom
			(at 0 0.4445 180)
			(size 0.1397 0.1397)
			(layers "F.Cu" "F.Mask" "F.Paste")
			(net "P3V3_STBY_TRIP")
			(options
				(clearance outline)
				(anchor circle)
			)
			(primitives
				(gr_poly
					(pts
						(arc
							(start -0.1778 -0.2794)
							(mid -0.249642 -0.249642)
							(end -0.2794 -0.1778)
						)
						(arc
							(start -0.2794 0.1778)
							(mid -0.249642 0.249642)
							(end -0.1778 0.2794)
						)
						(arc
							(start 0.1778 0.2794)
							(mid 0.249642 0.249642)
							(end 0.2794 0.1778)
						)
						(arc
							(start 0.2794 -0.1778)
							(mid 0.249642 -0.249642)
							(end 0.1778 -0.2794)
						)
					)
					(width 0)
					(fill yes)
				)
			)
		)
	)
	(footprint ""
		(layer "F.Cu")
		(at 82.94116 -155.321 90)
		(property "Reference" "C236"
			(at 0 0 90)
			(layer "F.SilkS")
			(hide yes)
			(effects
				(font
					(size 1.27 1.27)
				)
			)
		)
		(property "Value" "SC10U6D3V5KX-4GP"
			(at -0.0762 -6.1214 90)
			(unlocked yes)
			(layer "F.Fab")
			(hide yes)
			(effects
				(font
					(size 1.016 1.016)
					(thickness 0.1524)
				)
			)
		)
		(property "Device Type" "C805H58"
			(at -0.0762 -8.1534 90)
			(unlocked yes)
			(layer "F.Fab")
			(hide yes)
			(effects
				(font
					(size 1.016 1.016)
					(thickness 0.1524)
				)
			)
		)
		(duplicate_pad_numbers_are_jumpers no)
		(fp_line
			(start 0.635 0)
			(end -0.635 0)
			(stroke
				(width 0.508)
				(type default)
			)
			(layer "F.SilkS")
		)
		(fp_rect
			(start -0.9652 1.778)
			(end 0.9652 -1.778)
			(stroke
				(width 0)
				(type default)
			)
			(fill no)
			(layer "F.CrtYd")
		)
		(fp_poly
			(pts
				(xy -0.9652 -1.778) (xy 0.9652 -1.778) (xy 0.9652 1.778) (xy -0.9652 1.778)
			)
			(stroke
				(width 0)
				(type default)
			)
			(fill no)
			(layer "F.Fab")
		)
		(pad "1" smd rect
			(at 0 -0.9652 90)
			(size 1.397 1.143)
			(layers "F.Cu" "F.Mask" "F.Paste")
			(net "TPS74801_P1V15_STBY_OUT")
		)
		(pad "2" smd rect
			(at 0 0.9652 90)
			(size 1.397 1.143)
			(layers "F.Cu" "F.Mask" "F.Paste")
			(net "GND")
		)
	)
	(footprint ""
		(layer "F.Cu")
		(at 23.368 -130.9878 180)
		(property "Reference" "R214"
			(at 0 0 180)
			(layer "F.SilkS")
			(hide yes)
			(effects
				(font
					(size 1.27 1.27)
				)
			)
		)
		(property "Value" "2K7R2F-GP"
			(at 0.064008 -3.993896 180)
			(unlocked yes)
			(layer "F.Fab")
			(hide yes)
			(effects
				(font
					(size 1.016 1.016)
					(thickness 0.1524)
				)
			)
		)
		(property "Device Type" "R402H16"
			(at 0.064008 -5.517896 180)
			(unlocked yes)
			(layer "F.Fab")
			(hide yes)
			(effects
				(font
					(size 1.016 1.016)
					(thickness 0.1524)
				)
			)
		)
		(duplicate_pad_numbers_are_jumpers no)
		(fp_line
			(start 0.508 -0.9398)
			(end -0.508 -0.9398)
			(stroke
				(width 0.1524)
				(type default)
			)
			(layer "F.SilkS")
		)
		(fp_line
			(start -0.508 -0.9398)
			(end -0.508 0.9398)
			(stroke
				(width 0.1524)
				(type default)
			)
			(layer "F.SilkS")
		)
		(fp_rect
			(start -0.508 0.9398)
			(end 0.508 -0.9398)
			(stroke
				(width 0)
				(type default)
			)
			(fill no)
			(layer "F.CrtYd")
		)
		(fp_rect
			(start -0.508 0.9398)
			(end 0.508 -0.9398)
			(stroke
				(width 0)
				(type default)
			)
			(fill no)
			(layer "F.Fab")
		)
		(pad "1" smd custom
			(at 0 -0.4445 180)
			(size 0.1397 0.1397)
			(layers "F.Cu" "F.Mask" "F.Paste")
			(net "DDR4_ALERT")
			(options
				(clearance outline)
				(anchor circle)
			)
			(primitives
				(gr_poly
					(pts
						(arc
							(start -0.1778 -0.2794)
							(mid -0.249642 -0.249642)
							(end -0.2794 -0.1778)
						)
						(arc
							(start -0.2794 0.1778)
							(mid -0.249642 0.249642)
							(end -0.1778 0.2794)
						)
						(arc
							(start 0.1778 0.2794)
							(mid 0.249642 0.249642)
							(end 0.2794 0.1778)
						)
						(arc
							(start 0.2794 -0.1778)
							(mid 0.249642 -0.249642)
							(end 0.1778 -0.2794)
						)
					)
					(width 0)
					(fill yes)
				)
			)
		)
		(pad "2" smd custom
			(at 0 0.4445 180)
			(size 0.1397 0.1397)
			(layers "F.Cu" "F.Mask" "F.Paste")
			(net "P1V2_STBY")
			(options
				(clearance outline)
				(anchor circle)
			)
			(primitives
				(gr_poly
					(pts
						(arc
							(start -0.1778 -0.2794)
							(mid -0.249642 -0.249642)
							(end -0.2794 -0.1778)
						)
						(arc
							(start -0.2794 0.1778)
							(mid -0.249642 0.249642)
							(end -0.1778 0.2794)
						)
						(arc
							(start 0.1778 0.2794)
							(mid 0.249642 0.249642)
							(end 0.2794 0.1778)
						)
						(arc
							(start 0.2794 -0.1778)
							(mid 0.249642 -0.249642)
							(end 0.1778 -0.2794)
						)
					)
					(width 0)
					(fill yes)
				)
			)
		)
	)
	(footprint ""
		(layer "F.Cu")
		(at 164.13988 -100.391976)
		(property "Reference" "Q15"
			(at 0 0 0)
			(layer "F.SilkS")
			(hide yes)
			(effects
				(font
					(size 1.27 1.27)
				)
			)
		)
		(property "Value" "SSM3K324R-GP"
			(at 0.127 -8.9662 0)
			(unlocked yes)
			(layer "F.Fab")
			(hide yes)
			(effects
				(font
					(size 1.016 1.016)
					(thickness 0.1524)
				)
			)
		)
		(property "Device Type" "SOT23DGS2D4H35"
			(at 0.127 -10.4902 0)
			(unlocked yes)
			(layer "F.Fab")
			(hide yes)
			(effects
				(font
					(size 1.016 1.016)
					(thickness 0.1524)
				)
			)
		)
		(duplicate_pad_numbers_are_jumpers no)
		(fp_line
			(start -1.651 -1.778)
			(end -1.651 1.778)
			(stroke
				(width 0.1524)
				(type default)
			)
			(layer "F.SilkS")
		)
		(fp_line
			(start -1.651 1.778)
			(end 1.651 1.778)
			(stroke
				(width 0.1524)
				(type default)
			)
			(layer "F.SilkS")
		)
		(fp_line
			(start 1.651 -1.778)
			(end -1.651 -1.778)
			(stroke
				(width 0.1524)
				(type default)
			)
			(layer "F.SilkS")
		)
		(fp_line
			(start 1.651 1.778)
			(end 1.651 -1.778)
			(stroke
				(width 0.1524)
				(type default)
			)
			(layer "F.SilkS")
		)
		(fp_poly
			(pts
				(xy -1.778 1.8796) (xy -1.778 -1.8796) (xy 1.778 -1.8796) (xy 1.778 1.8796)
			)
			(stroke
				(width 0)
				(type default)
			)
			(fill no)
			(layer "F.CrtYd")
		)
		(fp_poly
			(pts
				(xy -1.778 1.8796) (xy -1.778 -1.8796) (xy 1.778 -1.8796) (xy 1.778 1.8796)
			)
			(stroke
				(width 0)
				(type default)
			)
			(fill no)
			(layer "F.Fab")
		)
		(pad "D" smd custom
			(at 0 -0.9525)
			(size 0.1905 0.1905)
			(layers "F.Cu" "F.Mask" "F.Paste")
			(net "SYS_HB_LED_D")
			(options
				(clearance outline)
				(anchor circle)
			)
			(primitives
				(gr_poly
					(pts
						(arc
							(start -0.1778 0.5715)
							(mid -0.321484 0.511984)
							(end -0.381 0.3683)
						)
						(arc
							(start -0.381 -0.3683)
							(mid -0.321484 -0.511984)
							(end -0.1778 -0.5715)
						)
						(arc
							(start 0.1778 -0.5715)
							(mid 0.321484 -0.511984)
							(end 0.381 -0.3683)
						)
						(arc
							(start 0.381 0.3683)
							(mid 0.321484 0.511984)
							(end 0.1778 0.5715)
						)
					)
					(width 0)
					(fill yes)
				)
			)
		)
		(pad "G" smd custom
			(at -0.98425 0.9525)
			(size 0.1905 0.1905)
			(layers "F.Cu" "F.Mask" "F.Paste")
			(net "SYS_HB_LED")
			(options
				(clearance outline)
				(anchor circle)
			)
			(primitives
				(gr_poly
					(pts
						(arc
							(start -0.1778 0.5715)
							(mid -0.321484 0.511984)
							(end -0.381 0.3683)
						)
						(arc
							(start -0.381 -0.3683)
							(mid -0.321484 -0.511984)
							(end -0.1778 -0.5715)
						)
						(arc
							(start 0.1778 -0.5715)
							(mid 0.321484 -0.511984)
							(end 0.381 -0.3683)
						)
						(arc
							(start 0.381 0.3683)
							(mid 0.321484 0.511984)
							(end 0.1778 0.5715)
						)
					)
					(width 0)
					(fill yes)
				)
			)
		)
		(pad "S" smd custom
			(at 0.98425 0.9525)
			(size 0.1905 0.1905)
			(layers "F.Cu" "F.Mask" "F.Paste")
			(net "GND")
			(options
				(clearance outline)
				(anchor circle)
			)
			(primitives
				(gr_poly
					(pts
						(arc
							(start -0.1778 0.5715)
							(mid -0.321484 0.511984)
							(end -0.381 0.3683)
						)
						(arc
							(start -0.381 -0.3683)
							(mid -0.321484 -0.511984)
							(end -0.1778 -0.5715)
						)
						(arc
							(start 0.1778 -0.5715)
							(mid 0.321484 -0.511984)
							(end 0.381 -0.3683)
						)
						(arc
							(start 0.381 0.3683)
							(mid 0.321484 0.511984)
							(end 0.1778 0.5715)
						)
					)
					(width 0)
					(fill yes)
				)
			)
		)
	)
	(footprint ""
		(layer "F.Cu")
		(at 162.31616 -40.49014 180)
		(property "Reference" "R44"
			(at 0 0 180)
			(layer "F.SilkS")
			(hide yes)
			(effects
				(font
					(size 1.27 1.27)
				)
			)
		)
		(property "Value" "1MR2F-GP"
			(at 0.064008 -3.993896 180)
			(unlocked yes)
			(layer "F.Fab")
			(hide yes)
			(effects
				(font
					(size 1.016 1.016)
					(thickness 0.1524)
				)
			)
		)
		(property "Device Type" "R402H16"
			(at 0.064008 -5.517896 180)
			(unlocked yes)
			(layer "F.Fab")
			(hide yes)
			(effects
				(font
					(size 1.016 1.016)
					(thickness 0.1524)
				)
			)
		)
		(duplicate_pad_numbers_are_jumpers no)
		(fp_line
			(start 0.508 -0.9398)
			(end -0.508 -0.9398)
			(stroke
				(width 0.1524)
				(type default)
			)
			(layer "F.SilkS")
		)
		(fp_line
			(start -0.508 -0.9398)
			(end -0.508 0.9398)
			(stroke
				(width 0.1524)
				(type default)
			)
			(layer "F.SilkS")
		)
		(fp_rect
			(start -0.508 0.9398)
			(end 0.508 -0.9398)
			(stroke
				(width 0)
				(type default)
			)
			(fill no)
			(layer "F.CrtYd")
		)
		(fp_rect
			(start -0.508 0.9398)
			(end 0.508 -0.9398)
			(stroke
				(width 0)
				(type default)
			)
			(fill no)
			(layer "F.Fab")
		)
		(pad "1" smd custom
			(at 0 -0.4445 180)
			(size 0.1397 0.1397)
			(layers "F.Cu" "F.Mask" "F.Paste")
			(net "EXT2_CONN_GND")
			(options
				(clearance outline)
				(anchor circle)
			)
			(primitives
				(gr_poly
					(pts
						(arc
							(start -0.1778 -0.2794)
							(mid -0.249642 -0.249642)
							(end -0.2794 -0.1778)
						)
						(arc
							(start -0.2794 0.1778)
							(mid -0.249642 0.249642)
							(end -0.1778 0.2794)
						)
						(arc
							(start 0.1778 0.2794)
							(mid 0.249642 0.249642)
							(end 0.2794 0.1778)
						)
						(arc
							(start 0.2794 -0.1778)
							(mid 0.249642 -0.249642)
							(end 0.1778 -0.2794)
						)
					)
					(width 0)
					(fill yes)
				)
			)
		)
		(pad "2" smd custom
			(at 0 0.4445 180)
			(size 0.1397 0.1397)
			(layers "F.Cu" "F.Mask" "F.Paste")
			(net "GND")
			(options
				(clearance outline)
				(anchor circle)
			)
			(primitives
				(gr_poly
					(pts
						(arc
							(start -0.1778 -0.2794)
							(mid -0.249642 -0.249642)
							(end -0.2794 -0.1778)
						)
						(arc
							(start -0.2794 0.1778)
							(mid -0.249642 0.249642)
							(end -0.1778 0.2794)
						)
						(arc
							(start 0.1778 0.2794)
							(mid 0.249642 0.249642)
							(end 0.2794 0.1778)
						)
						(arc
							(start 0.2794 -0.1778)
							(mid 0.249642 -0.249642)
							(end 0.1778 -0.2794)
						)
					)
					(width 0)
					(fill yes)
				)
			)
		)
	)
	(footprint ""
		(layer "F.Cu")
		(at 79.98968 -172.90288)
		(property "Reference" "C195"
			(at 0 0 0)
			(layer "F.SilkS")
			(hide yes)
			(effects
				(font
					(size 1.27 1.27)
				)
			)
		)
		(property "Value" "SCD1U16V2KX-3GP"
			(at 1.1811 -2.7051 0)
			(unlocked yes)
			(layer "F.Fab")
			(hide yes)
			(effects
				(font
					(size 1.016 1.016)
					(thickness 0.1524)
				)
			)
		)
		(property "Device Type" "C402H22"
			(at 1.1811 -4.2291 0)
			(unlocked yes)
			(layer "F.Fab")
			(hide yes)
			(effects
				(font
					(size 1.016 1.016)
					(thickness 0.1524)
				)
			)
		)
		(duplicate_pad_numbers_are_jumpers no)
		(fp_rect
			(start -0.4318 0.9525)
			(end 0.4318 -0.9525)
			(stroke
				(width 0)
				(type default)
			)
			(fill no)
			(layer "F.CrtYd")
		)
		(fp_rect
			(start -0.4318 0.9525)
			(end 0.4318 -0.9525)
			(stroke
				(width 0)
				(type default)
			)
			(fill no)
			(layer "F.Fab")
		)
		(pad "1" smd custom
			(at 0 -0.4445)
			(size 0.1524 0.1524)
			(layers "F.Cu" "F.Mask" "F.Paste")
			(net "TPS74801_P2V5_STBY_OUT")
			(options
				(clearance outline)
				(anchor circle)
			)
			(primitives
				(gr_poly
					(pts
						(arc
							(start 0.3048 -0.2032)
							(mid 0.275042 -0.275042)
							(end 0.2032 -0.3048)
						)
						(arc
							(start -0.2032 -0.3048)
							(mid -0.275042 -0.275042)
							(end -0.3048 -0.2032)
						)
						(arc
							(start -0.3048 0.2032)
							(mid -0.275042 0.275042)
							(end -0.2032 0.3048)
						)
						(arc
							(start 0.2032 0.3048)
							(mid 0.275042 0.275042)
							(end 0.3048 0.2032)
						)
					)
					(width 0)
					(fill yes)
				)
			)
		)
		(pad "2" smd custom
			(at 0 0.4445)
			(size 0.1524 0.1524)
			(layers "F.Cu" "F.Mask" "F.Paste")
			(net "GND")
			(options
				(clearance outline)
				(anchor circle)
			)
			(primitives
				(gr_poly
					(pts
						(arc
							(start 0.3048 -0.2032)
							(mid 0.275042 -0.275042)
							(end 0.2032 -0.3048)
						)
						(arc
							(start -0.2032 -0.3048)
							(mid -0.275042 -0.275042)
							(end -0.3048 -0.2032)
						)
						(arc
							(start -0.3048 0.2032)
							(mid -0.275042 0.275042)
							(end -0.2032 0.3048)
						)
						(arc
							(start 0.2032 0.3048)
							(mid 0.275042 0.275042)
							(end 0.3048 0.2032)
						)
					)
					(width 0)
					(fill yes)
				)
			)
		)
	)
	(footprint ""
		(layer "F.Cu")
		(at 172.586904 -147.211034 90)
		(property "Reference" "R469"
			(at 0 0 90)
			(layer "F.SilkS")
			(hide yes)
			(effects
				(font
					(size 1.27 1.27)
				)
			)
		)
		(property "Value" "3D01R5F-GP"
			(at 0 -8.9535 90)
			(unlocked yes)
			(layer "F.Fab")
			(hide yes)
			(effects
				(font
					(size 1.27 1.016)
					(thickness 0.1524)
				)
			)
		)
		(property "Device Type" "R805H24"
			(at 0 -10.6299 90)
			(unlocked yes)
			(layer "F.Fab")
			(hide yes)
			(effects
				(font
					(size 1.27 1.016)
					(thickness 0.1524)
				)
			)
		)
		(duplicate_pad_numbers_are_jumpers no)
		(fp_line
			(start 0.889 -1.7018)
			(end -0.889 -1.7018)
			(stroke
				(width 0.1524)
				(type default)
			)
			(layer "F.SilkS")
		)
		(fp_line
			(start 0.889 -1.7018)
			(end 0.889 -0.381)
			(stroke
				(width 0.1524)
				(type default)
			)
			(layer "F.SilkS")
		)
		(fp_line
			(start -0.889 -1.7018)
			(end -0.889 0.2794)
			(stroke
				(width 0.1524)
				(type default)
			)
			(layer "F.SilkS")
		)
		(fp_line
			(start -0.889 0.0762)
			(end -0.889 1.7018)
			(stroke
				(width 0.1524)
				(type default)
			)
			(layer "F.SilkS")
		)
		(fp_line
			(start 0.889 1.7018)
			(end 0.889 -0.508)
			(stroke
				(width 0.1524)
				(type default)
			)
			(layer "F.SilkS")
		)
		(fp_line
			(start -0.889 1.7018)
			(end 0.889 1.7018)
			(stroke
				(width 0.1524)
				(type default)
			)
			(layer "F.SilkS")
		)
		(fp_poly
			(pts
				(xy 0.9652 -1.778) (xy 0.9652 1.778) (xy -0.9652 1.778) (xy -0.9652 -1.778)
			)
			(stroke
				(width 0)
				(type default)
			)
			(fill no)
			(layer "F.CrtYd")
		)
		(fp_rect
			(start -0.9652 1.778)
			(end 0.9652 -1.778)
			(stroke
				(width 0)
				(type default)
			)
			(fill no)
			(layer "F.Fab")
		)
		(pad "1" smd rect
			(at 0 -0.9652 90)
			(size 1.397 1.143)
			(layers "F.Cu" "F.Mask" "F.Paste")
			(net "P5V_SNB")
		)
		(pad "2" smd rect
			(at 0 0.9652 90)
			(size 1.397 1.143)
			(layers "F.Cu" "F.Mask" "F.Paste")
			(net "GND")
		)
	)
	(footprint ""
		(layer "F.Cu")
		(at 60.375546 -182.561738 -90)
		(property "Reference" "R481"
			(at 0 0 270)
			(layer "F.SilkS")
			(hide yes)
			(effects
				(font
					(size 1.27 1.27)
				)
			)
		)
		(property "Value" "0R6J-3-GP"
			(at -0.0508 -4.8514 270)
			(unlocked yes)
			(layer "F.Fab")
			(hide yes)
			(effects
				(font
					(size 1.016 1.016)
					(thickness 0.1524)
				)
			)
		)
		(property "Device Type" "R1206H28"
			(at 0 -6.3754 270)
			(unlocked yes)
			(layer "F.Fab")
			(hide yes)
			(effects
				(font
					(size 1.016 1.016)
					(thickness 0.1524)
				)
			)
		)
		(duplicate_pad_numbers_are_jumpers no)
		(fp_line
			(start -1.016 2.2352)
			(end -1.016 -2.2352)
			(stroke
				(width 0.1524)
				(type default)
			)
			(layer "F.SilkS")
		)
		(fp_line
			(start 1.016 2.2352)
			(end -1.016 2.2352)
			(stroke
				(width 0.1524)
				(type default)
			)
			(layer "F.SilkS")
		)
		(fp_line
			(start -1.016 -2.2352)
			(end 1.016 -2.2352)
			(stroke
				(width 0.1524)
				(type default)
			)
			(layer "F.SilkS")
		)
		(fp_line
			(start 1.016 -2.2352)
			(end 1.016 2.2352)
			(stroke
				(width 0.1524)
				(type default)
			)
			(layer "F.SilkS")
		)
		(fp_rect
			(start -1.0922 2.3114)
			(end 1.0922 -2.3114)
			(stroke
				(width 0)
				(type default)
			)
			(fill no)
			(layer "F.CrtYd")
		)
		(fp_poly
			(pts
				(xy -1.0922 -2.3114) (xy 1.0922 -2.3114) (xy 1.0922 2.3114) (xy -1.0922 2.3114)
			)
			(stroke
				(width 0)
				(type default)
			)
			(fill no)
			(layer "F.Fab")
		)
		(pad "1" smd rect
			(at 0 -1.397 270)
			(size 1.651 1.27)
			(layers "F.Cu" "F.Mask" "F.Paste")
			(net "P3V3_STBY")
		)
		(pad "2" smd rect
			(at 0 1.397 270)
			(size 1.651 1.27)
			(layers "F.Cu" "F.Mask" "F.Paste")
			(net "P3V3_STBY_OUT")
		)
	)
	(footprint ""
		(layer "F.Cu")
		(at 197.5358 -19.2786 180)
		(property "Reference" "R696"
			(at 0 0 180)
			(layer "F.SilkS")
			(hide yes)
			(effects
				(font
					(size 1.27 1.27)
				)
			)
		)
		(property "Value" "1KR2F-3-GP"
			(at 0.064008 -3.993896 180)
			(unlocked yes)
			(layer "F.Fab")
			(hide yes)
			(effects
				(font
					(size 1.016 1.016)
					(thickness 0.1524)
				)
			)
		)
		(property "Device Type" "R402H16"
			(at 0.064008 -5.517896 180)
			(unlocked yes)
			(layer "F.Fab")
			(hide yes)
			(effects
				(font
					(size 1.016 1.016)
					(thickness 0.1524)
				)
			)
		)
		(duplicate_pad_numbers_are_jumpers no)
		(fp_line
			(start 0.508 -0.9398)
			(end -0.508 -0.9398)
			(stroke
				(width 0.1524)
				(type default)
			)
			(layer "F.SilkS")
		)
		(fp_line
			(start -0.508 -0.9398)
			(end -0.508 0.9398)
			(stroke
				(width 0.1524)
				(type default)
			)
			(layer "F.SilkS")
		)
		(fp_rect
			(start -0.508 0.9398)
			(end 0.508 -0.9398)
			(stroke
				(width 0)
				(type default)
			)
			(fill no)
			(layer "F.CrtYd")
		)
		(fp_rect
			(start -0.508 0.9398)
			(end 0.508 -0.9398)
			(stroke
				(width 0)
				(type default)
			)
			(fill no)
			(layer "F.Fab")
		)
		(pad "1" smd custom
			(at 0 -0.4445 180)
			(size 0.1397 0.1397)
			(layers "F.Cu" "F.Mask" "F.Paste")
			(net "P3V3_STBY")
			(options
				(clearance outline)
				(anchor circle)
			)
			(primitives
				(gr_poly
					(pts
						(arc
							(start -0.1778 -0.2794)
							(mid -0.249642 -0.249642)
							(end -0.2794 -0.1778)
						)
						(arc
							(start -0.2794 0.1778)
							(mid -0.249642 0.249642)
							(end -0.1778 0.2794)
						)
						(arc
							(start 0.1778 0.2794)
							(mid 0.249642 0.249642)
							(end 0.2794 0.1778)
						)
						(arc
							(start 0.2794 -0.1778)
							(mid 0.249642 -0.249642)
							(end 0.1778 -0.2794)
						)
					)
					(width 0)
					(fill yes)
				)
			)
		)
		(pad "2" smd custom
			(at 0 0.4445 180)
			(size 0.1397 0.1397)
			(layers "F.Cu" "F.Mask" "F.Paste")
			(net "EXT1_LED_YELLOW_D")
			(options
				(clearance outline)
				(anchor circle)
			)
			(primitives
				(gr_poly
					(pts
						(arc
							(start -0.1778 -0.2794)
							(mid -0.249642 -0.249642)
							(end -0.2794 -0.1778)
						)
						(arc
							(start -0.2794 0.1778)
							(mid -0.249642 0.249642)
							(end -0.1778 0.2794)
						)
						(arc
							(start 0.1778 0.2794)
							(mid 0.249642 0.249642)
							(end 0.2794 0.1778)
						)
						(arc
							(start 0.2794 -0.1778)
							(mid 0.249642 -0.249642)
							(end 0.1778 -0.2794)
						)
					)
					(width 0)
					(fill yes)
				)
			)
		)
	)
	(footprint ""
		(layer "F.Cu")
		(at 213.6902 -15.13332 180)
		(property "Reference" "R746"
			(at 0 0 180)
			(layer "F.SilkS")
			(hide yes)
			(effects
				(font
					(size 1.27 1.27)
				)
			)
		)
		(property "Value" "1KR2F-3-GP"
			(at 0.064008 -3.993896 180)
			(unlocked yes)
			(layer "F.Fab")
			(hide yes)
			(effects
				(font
					(size 1.016 1.016)
					(thickness 0.1524)
				)
			)
		)
		(property "Device Type" "R402H16"
			(at 0.064008 -5.517896 180)
			(unlocked yes)
			(layer "F.Fab")
			(hide yes)
			(effects
				(font
					(size 1.016 1.016)
					(thickness 0.1524)
				)
			)
		)
		(duplicate_pad_numbers_are_jumpers no)
		(fp_line
			(start 0.508 -0.9398)
			(end -0.508 -0.9398)
			(stroke
				(width 0.1524)
				(type default)
			)
			(layer "F.SilkS")
		)
		(fp_line
			(start -0.508 -0.9398)
			(end -0.508 0.9398)
			(stroke
				(width 0.1524)
				(type default)
			)
			(layer "F.SilkS")
		)
		(fp_rect
			(start -0.508 0.9398)
			(end 0.508 -0.9398)
			(stroke
				(width 0)
				(type default)
			)
			(fill no)
			(layer "F.CrtYd")
		)
		(fp_rect
			(start -0.508 0.9398)
			(end 0.508 -0.9398)
			(stroke
				(width 0)
				(type default)
			)
			(fill no)
			(layer "F.Fab")
		)
		(pad "1" smd custom
			(at 0 -0.4445 180)
			(size 0.1397 0.1397)
			(layers "F.Cu" "F.Mask" "F.Paste")
			(net "P5V_STBY")
			(options
				(clearance outline)
				(anchor circle)
			)
			(primitives
				(gr_poly
					(pts
						(arc
							(start -0.1778 -0.2794)
							(mid -0.249642 -0.249642)
							(end -0.2794 -0.1778)
						)
						(arc
							(start -0.2794 0.1778)
							(mid -0.249642 0.249642)
							(end -0.1778 0.2794)
						)
						(arc
							(start 0.1778 0.2794)
							(mid 0.249642 0.249642)
							(end 0.2794 0.1778)
						)
						(arc
							(start 0.2794 -0.1778)
							(mid 0.249642 -0.249642)
							(end 0.1778 -0.2794)
						)
					)
					(width 0)
					(fill yes)
				)
			)
		)
		(pad "2" smd custom
			(at 0 0.4445 180)
			(size 0.1397 0.1397)
			(layers "F.Cu" "F.Mask" "F.Paste")
			(net "BMC_ML_PWR_BLUE_LED_L")
			(options
				(clearance outline)
				(anchor circle)
			)
			(primitives
				(gr_poly
					(pts
						(arc
							(start -0.1778 -0.2794)
							(mid -0.249642 -0.249642)
							(end -0.2794 -0.1778)
						)
						(arc
							(start -0.2794 0.1778)
							(mid -0.249642 0.249642)
							(end -0.1778 0.2794)
						)
						(arc
							(start 0.1778 0.2794)
							(mid 0.249642 0.249642)
							(end 0.2794 0.1778)
						)
						(arc
							(start 0.2794 -0.1778)
							(mid 0.249642 -0.249642)
							(end 0.1778 -0.2794)
						)
					)
					(width 0)
					(fill yes)
				)
			)
		)
	)
	(footprint ""
		(layer "F.Cu")
		(at 142.0368 -10.7442)
		(property "Reference" "C517"
			(at 0 0 0)
			(layer "F.SilkS")
			(hide yes)
			(effects
				(font
					(size 1.27 1.27)
				)
			)
		)
		(property "Value" "SCD1U16V2KX-3GP"
			(at 1.1811 -2.7051 0)
			(unlocked yes)
			(layer "F.Fab")
			(hide yes)
			(effects
				(font
					(size 1.016 1.016)
					(thickness 0.1524)
				)
			)
		)
		(property "Device Type" "C402H22"
			(at 1.1811 -4.2291 0)
			(unlocked yes)
			(layer "F.Fab")
			(hide yes)
			(effects
				(font
					(size 1.016 1.016)
					(thickness 0.1524)
				)
			)
		)
		(duplicate_pad_numbers_are_jumpers no)
		(fp_rect
			(start -0.4318 0.9525)
			(end 0.4318 -0.9525)
			(stroke
				(width 0)
				(type default)
			)
			(fill no)
			(layer "F.CrtYd")
		)
		(fp_rect
			(start -0.4318 0.9525)
			(end 0.4318 -0.9525)
			(stroke
				(width 0)
				(type default)
			)
			(fill no)
			(layer "F.Fab")
		)
		(pad "1" smd custom
			(at 0 -0.4445)
			(size 0.1524 0.1524)
			(layers "F.Cu" "F.Mask" "F.Paste")
			(net "P1V8")
			(options
				(clearance outline)
				(anchor circle)
			)
			(primitives
				(gr_poly
					(pts
						(arc
							(start 0.3048 -0.2032)
							(mid 0.275042 -0.275042)
							(end 0.2032 -0.3048)
						)
						(arc
							(start -0.2032 -0.3048)
							(mid -0.275042 -0.275042)
							(end -0.3048 -0.2032)
						)
						(arc
							(start -0.3048 0.2032)
							(mid -0.275042 0.275042)
							(end -0.2032 0.3048)
						)
						(arc
							(start 0.2032 0.3048)
							(mid 0.275042 0.275042)
							(end 0.3048 0.2032)
						)
					)
					(width 0)
					(fill yes)
				)
			)
		)
		(pad "2" smd custom
			(at 0 0.4445)
			(size 0.1524 0.1524)
			(layers "F.Cu" "F.Mask" "F.Paste")
			(net "GND")
			(options
				(clearance outline)
				(anchor circle)
			)
			(primitives
				(gr_poly
					(pts
						(arc
							(start 0.3048 -0.2032)
							(mid 0.275042 -0.275042)
							(end 0.2032 -0.3048)
						)
						(arc
							(start -0.2032 -0.3048)
							(mid -0.275042 -0.275042)
							(end -0.3048 -0.2032)
						)
						(arc
							(start -0.3048 0.2032)
							(mid -0.275042 0.275042)
							(end -0.2032 0.3048)
						)
						(arc
							(start 0.2032 0.3048)
							(mid 0.275042 0.275042)
							(end 0.3048 0.2032)
						)
					)
					(width 0)
					(fill yes)
				)
			)
		)
	)
	(footprint ""
		(layer "F.Cu")
		(at 171.753276 -149.333966)
		(property "Reference" "C159"
			(at 0 0 0)
			(layer "F.SilkS")
			(hide yes)
			(effects
				(font
					(size 1.27 1.27)
				)
			)
		)
		(property "Value" "SC2200P50V2KX-2GP"
			(at 1.1811 -2.7051 0)
			(unlocked yes)
			(layer "F.Fab")
			(hide yes)
			(effects
				(font
					(size 1.016 1.016)
					(thickness 0.1524)
				)
			)
		)
		(property "Device Type" "C402H22"
			(at 1.1811 -4.2291 0)
			(unlocked yes)
			(layer "F.Fab")
			(hide yes)
			(effects
				(font
					(size 1.016 1.016)
					(thickness 0.1524)
				)
			)
		)
		(duplicate_pad_numbers_are_jumpers no)
		(fp_rect
			(start -0.4318 0.9525)
			(end 0.4318 -0.9525)
			(stroke
				(width 0)
				(type default)
			)
			(fill no)
			(layer "F.CrtYd")
		)
		(fp_rect
			(start -0.4318 0.9525)
			(end 0.4318 -0.9525)
			(stroke
				(width 0)
				(type default)
			)
			(fill no)
			(layer "F.Fab")
		)
		(pad "1" smd custom
			(at 0 -0.4445)
			(size 0.1524 0.1524)
			(layers "F.Cu" "F.Mask" "F.Paste")
			(net "P5V_LL")
			(options
				(clearance outline)
				(anchor circle)
			)
			(primitives
				(gr_poly
					(pts
						(arc
							(start 0.3048 -0.2032)
							(mid 0.275042 -0.275042)
							(end 0.2032 -0.3048)
						)
						(arc
							(start -0.2032 -0.3048)
							(mid -0.275042 -0.275042)
							(end -0.3048 -0.2032)
						)
						(arc
							(start -0.3048 0.2032)
							(mid -0.275042 0.275042)
							(end -0.2032 0.3048)
						)
						(arc
							(start 0.2032 0.3048)
							(mid 0.275042 0.275042)
							(end 0.3048 0.2032)
						)
					)
					(width 0)
					(fill yes)
				)
			)
		)
		(pad "2" smd custom
			(at 0 0.4445)
			(size 0.1524 0.1524)
			(layers "F.Cu" "F.Mask" "F.Paste")
			(net "P5V_SNB")
			(options
				(clearance outline)
				(anchor circle)
			)
			(primitives
				(gr_poly
					(pts
						(arc
							(start 0.3048 -0.2032)
							(mid 0.275042 -0.275042)
							(end 0.2032 -0.3048)
						)
						(arc
							(start -0.2032 -0.3048)
							(mid -0.275042 -0.275042)
							(end -0.3048 -0.2032)
						)
						(arc
							(start -0.3048 0.2032)
							(mid -0.275042 0.275042)
							(end -0.2032 0.3048)
						)
						(arc
							(start 0.2032 0.3048)
							(mid 0.275042 0.275042)
							(end 0.3048 0.2032)
						)
					)
					(width 0)
					(fill yes)
				)
			)
		)
	)
	(footprint ""
		(layer "F.Cu")
		(at 36.76904 -121.360946 90)
		(property "Reference" "U11"
			(at 0 0 90)
			(layer "F.SilkS")
			(hide yes)
			(effects
				(font
					(size 1.27 1.27)
				)
			)
		)
		(property "Value" "W25Q256FVFIQ-GP"
			(at -6.7945 -2.2098 90)
			(unlocked yes)
			(layer "F.Fab")
			(hide yes)
			(effects
				(font
					(size 1.016 1.016)
					(thickness 0.1524)
				)
			)
		)
		(property "Device Type" "SOIC16-6H104"
			(at -6.7945 -3.7338 90)
			(unlocked yes)
			(layer "F.Fab")
			(hide yes)
			(effects
				(font
					(size 1.016 1.016)
					(thickness 0.1524)
				)
			)
		)
		(duplicate_pad_numbers_are_jumpers no)
		(fp_line
			(start 4.7498 -3.2258)
			(end 4.7498 3.2258)
			(stroke
				(width 0.1524)
				(type default)
			)
			(layer "F.SilkS")
		)
		(fp_line
			(start -5.588 -3.2258)
			(end 4.7498 -3.2258)
			(stroke
				(width 0.1524)
				(type default)
			)
			(layer "F.SilkS")
		)
		(fp_line
			(start -5.588 -0.50038)
			(end -5.08762 0)
			(stroke
				(width 0.1524)
				(type default)
			)
			(layer "F.SilkS")
		)
		(fp_line
			(start -5.08762 0)
			(end -5.588 0.50038)
			(stroke
				(width 0.1524)
				(type default)
			)
			(layer "F.SilkS")
		)
		(fp_line
			(start 4.7498 3.2258)
			(end -5.588 3.2258)
			(stroke
				(width 0.1524)
				(type default)
			)
			(layer "F.SilkS")
		)
		(fp_line
			(start -5.4102 3.2258)
			(end -5.4102 5.7912)
			(stroke
				(width 0.508)
				(type default)
			)
			(layer "F.SilkS")
		)
		(fp_line
			(start -5.588 3.2258)
			(end -5.588 -3.2258)
			(stroke
				(width 0.1524)
				(type default)
			)
			(layer "F.SilkS")
		)
		(fp_poly
			(pts
				(xy -4.764786 -3.2258) (xy 4.7625 -3.2258) (xy 4.7625 3.2258) (xy -4.764786 3.2258)
			)
			(stroke
				(width 0)
				(type default)
			)
			(fill yes)
			(layer "F.SilkS")
		)
		(fp_rect
			(start -5.1435 5.1562)
			(end 5.1435 -5.1562)
			(stroke
				(width 0)
				(type default)
			)
			(fill no)
			(layer "F.CrtYd")
		)
		(fp_poly
			(pts
				(xy -5.6642 6.0452) (xy -5.6642 -6.0452) (xy 5.6642 -6.0452) (xy 5.6642 -1.7653) (xy 5.1435 -1.7653)
				(xy 5.1435 -5.1562) (xy -5.1435 -5.1562) (xy -5.1435 5.1562) (xy 5.1435 5.1562) (xy 5.1435 -1.7526)
				(xy 5.6642 -1.7526) (xy 5.6642 6.0452)
			)
			(stroke
				(width 0)
				(type default)
			)
			(fill no)
			(layer "F.CrtYd")
		)
		(fp_rect
			(start -5.6642 6.0452)
			(end 5.6642 -6.0452)
			(stroke
				(width 0)
				(type default)
			)
			(fill no)
			(layer "F.Fab")
		)
		(pad "1" smd rect
			(at -4.445 4.71805 90)
			(size 0.635 1.651)
			(layers "F.Cu" "F.Mask" "F.Paste")
			(net "FLA0_SPI_HOLD_N")
		)
		(pad "2" smd rect
			(at -3.175 4.71805 90)
			(size 0.635 1.651)
			(layers "F.Cu" "F.Mask" "F.Paste")
			(net "P3V3_STBY")
		)
		(pad "3" smd rect
			(at -1.905 4.71805 90)
			(size 0.635 1.651)
			(layers "F.Cu" "F.Mask" "F.Paste")
			(net "FLA0_SPI_RST")
		)
		(pad "4" smd rect
			(at -0.635 4.71805 90)
			(size 0.635 1.651)
			(layers "F.Cu" "F.Mask" "F.Paste")
			(net "Net_340")
		)
		(pad "5" smd rect
			(at 0.635 4.71805 90)
			(size 0.635 1.651)
			(layers "F.Cu" "F.Mask" "F.Paste")
			(net "Net_341")
		)
		(pad "6" smd rect
			(at 1.905 4.71805 90)
			(size 0.635 1.651)
			(layers "F.Cu" "F.Mask" "F.Paste")
			(net "Net_342")
		)
		(pad "7" smd rect
			(at 3.175 4.71805 90)
			(size 0.635 1.651)
			(layers "F.Cu" "F.Mask" "F.Paste")
			(net "FLA_CS_0_R")
		)
		(pad "8" smd rect
			(at 4.445 4.71805 90)
			(size 0.635 1.651)
			(layers "F.Cu" "F.Mask" "F.Paste")
			(net "BMC_SPI_MISO_TPM")
		)
		(pad "9" smd rect
			(at 4.445 -4.71805 90)
			(size 0.635 1.651)
			(layers "F.Cu" "F.Mask" "F.Paste")
			(net "FLA0_WP_N")
		)
		(pad "10" smd rect
			(at 3.175 -4.71805 90)
			(size 0.635 1.651)
			(layers "F.Cu" "F.Mask" "F.Paste")
			(net "GND")
		)
		(pad "11" smd rect
			(at 1.905 -4.71805 90)
			(size 0.635 1.651)
			(layers "F.Cu" "F.Mask" "F.Paste")
			(net "Net_336")
		)
		(pad "12" smd rect
			(at 0.635 -4.71805 90)
			(size 0.635 1.651)
			(layers "F.Cu" "F.Mask" "F.Paste")
			(net "Net_337")
		)
		(pad "13" smd rect
			(at -0.635 -4.71805 90)
			(size 0.635 1.651)
			(layers "F.Cu" "F.Mask" "F.Paste")
			(net "Net_338")
		)
		(pad "14" smd rect
			(at -1.905 -4.71805 90)
			(size 0.635 1.651)
			(layers "F.Cu" "F.Mask" "F.Paste")
			(net "Net_339")
		)
		(pad "15" smd rect
			(at -3.175 -4.71805 90)
			(size 0.635 1.651)
			(layers "F.Cu" "F.Mask" "F.Paste")
			(net "BMC_SPI_MOSI_R")
		)
		(pad "16" smd rect
			(at -4.445 -4.71805 90)
			(size 0.635 1.651)
			(layers "F.Cu" "F.Mask" "F.Paste")
			(net "BMC_SPI_CLK_R")
		)
	)
	(footprint ""
		(layer "F.Cu")
		(at 46.02988 -120.395492 90)
		(property "Reference" "R765"
			(at 0 0 90)
			(layer "F.SilkS")
			(hide yes)
			(effects
				(font
					(size 1.27 1.27)
				)
			)
		)
		(property "Value" "0R2J-2-GP"
			(at 0.064008 -3.993896 90)
			(unlocked yes)
			(layer "F.Fab")
			(hide yes)
			(effects
				(font
					(size 1.016 1.016)
					(thickness 0.1524)
				)
			)
		)
		(property "Device Type" "R402H16"
			(at 0.064008 -5.517896 90)
			(unlocked yes)
			(layer "F.Fab")
			(hide yes)
			(effects
				(font
					(size 1.016 1.016)
					(thickness 0.1524)
				)
			)
		)
		(duplicate_pad_numbers_are_jumpers no)
		(fp_line
			(start 0.508 -0.9398)
			(end -0.508 -0.9398)
			(stroke
				(width 0.1524)
				(type default)
			)
			(layer "F.SilkS")
		)
		(fp_line
			(start -0.508 -0.9398)
			(end -0.508 0.9398)
			(stroke
				(width 0.1524)
				(type default)
			)
			(layer "F.SilkS")
		)
		(fp_rect
			(start -0.508 0.9398)
			(end 0.508 -0.9398)
			(stroke
				(width 0)
				(type default)
			)
			(fill no)
			(layer "F.CrtYd")
		)
		(fp_rect
			(start -0.508 0.9398)
			(end 0.508 -0.9398)
			(stroke
				(width 0)
				(type default)
			)
			(fill no)
			(layer "F.Fab")
		)
		(pad "1" smd custom
			(at 0 -0.4445 90)
			(size 0.1397 0.1397)
			(layers "F.Cu" "F.Mask" "F.Paste")
			(net "FLA0_SPI_RST")
			(options
				(clearance outline)
				(anchor circle)
			)
			(primitives
				(gr_poly
					(pts
						(arc
							(start -0.1778 -0.2794)
							(mid -0.249642 -0.249642)
							(end -0.2794 -0.1778)
						)
						(arc
							(start -0.2794 0.1778)
							(mid -0.249642 0.249642)
							(end -0.1778 0.2794)
						)
						(arc
							(start 0.1778 0.2794)
							(mid 0.249642 0.249642)
							(end 0.2794 0.1778)
						)
						(arc
							(start 0.2794 -0.1778)
							(mid 0.249642 -0.249642)
							(end 0.1778 -0.2794)
						)
					)
					(width 0)
					(fill yes)
				)
			)
		)
		(pad "2" smd custom
			(at 0 0.4445 90)
			(size 0.1397 0.1397)
			(layers "F.Cu" "F.Mask" "F.Paste")
			(net "RST_BMC_EXTRST_N")
			(options
				(clearance outline)
				(anchor circle)
			)
			(primitives
				(gr_poly
					(pts
						(arc
							(start -0.1778 -0.2794)
							(mid -0.249642 -0.249642)
							(end -0.2794 -0.1778)
						)
						(arc
							(start -0.2794 0.1778)
							(mid -0.249642 0.249642)
							(end -0.1778 0.2794)
						)
						(arc
							(start 0.1778 0.2794)
							(mid 0.249642 0.249642)
							(end 0.2794 0.1778)
						)
						(arc
							(start 0.2794 -0.1778)
							(mid 0.249642 -0.249642)
							(end 0.1778 -0.2794)
						)
					)
					(width 0)
					(fill yes)
				)
			)
		)
	)
	(footprint ""
		(layer "F.Cu")
		(at 153.203656 -137.795762 180)
		(property "Reference" "R522"
			(at 0 0 180)
			(layer "F.SilkS")
			(hide yes)
			(effects
				(font
					(size 1.27 1.27)
				)
			)
		)
		(property "Value" "0R2J-2-GP"
			(at 0.064008 -3.993896 180)
			(unlocked yes)
			(layer "F.Fab")
			(hide yes)
			(effects
				(font
					(size 1.016 1.016)
					(thickness 0.1524)
				)
			)
		)
		(property "Device Type" "R402H16"
			(at 0.064008 -5.517896 180)
			(unlocked yes)
			(layer "F.Fab")
			(hide yes)
			(effects
				(font
					(size 1.016 1.016)
					(thickness 0.1524)
				)
			)
		)
		(duplicate_pad_numbers_are_jumpers no)
		(fp_line
			(start 0.508 -0.9398)
			(end -0.508 -0.9398)
			(stroke
				(width 0.1524)
				(type default)
			)
			(layer "F.SilkS")
		)
		(fp_line
			(start -0.508 -0.9398)
			(end -0.508 0.9398)
			(stroke
				(width 0.1524)
				(type default)
			)
			(layer "F.SilkS")
		)
		(fp_rect
			(start -0.508 0.9398)
			(end 0.508 -0.9398)
			(stroke
				(width 0)
				(type default)
			)
			(fill no)
			(layer "F.CrtYd")
		)
		(fp_rect
			(start -0.508 0.9398)
			(end 0.508 -0.9398)
			(stroke
				(width 0)
				(type default)
			)
			(fill no)
			(layer "F.Fab")
		)
		(pad "1" smd custom
			(at 0 -0.4445 180)
			(size 0.1397 0.1397)
			(layers "F.Cu" "F.Mask" "F.Paste")
			(net "P1V8_STBY_EN_R")
			(options
				(clearance outline)
				(anchor circle)
			)
			(primitives
				(gr_poly
					(pts
						(arc
							(start -0.1778 -0.2794)
							(mid -0.249642 -0.249642)
							(end -0.2794 -0.1778)
						)
						(arc
							(start -0.2794 0.1778)
							(mid -0.249642 0.249642)
							(end -0.1778 0.2794)
						)
						(arc
							(start 0.1778 0.2794)
							(mid 0.249642 0.249642)
							(end 0.2794 0.1778)
						)
						(arc
							(start 0.2794 -0.1778)
							(mid 0.249642 -0.249642)
							(end 0.1778 -0.2794)
						)
					)
					(width 0)
					(fill yes)
				)
			)
		)
		(pad "2" smd custom
			(at 0 0.4445 180)
			(size 0.1397 0.1397)
			(layers "F.Cu" "F.Mask" "F.Paste")
			(net "PWRGD_P2V5_STBY")
			(options
				(clearance outline)
				(anchor circle)
			)
			(primitives
				(gr_poly
					(pts
						(arc
							(start -0.1778 -0.2794)
							(mid -0.249642 -0.249642)
							(end -0.2794 -0.1778)
						)
						(arc
							(start -0.2794 0.1778)
							(mid -0.249642 0.249642)
							(end -0.1778 0.2794)
						)
						(arc
							(start 0.1778 0.2794)
							(mid 0.249642 0.249642)
							(end 0.2794 0.1778)
						)
						(arc
							(start 0.2794 -0.1778)
							(mid 0.249642 -0.249642)
							(end 0.1778 -0.2794)
						)
					)
					(width 0)
					(fill yes)
				)
			)
		)
	)
	(footprint ""
		(layer "F.Cu")
		(at 98.552 -144.399 90)
		(property "Reference" "R428"
			(at 0 0 90)
			(layer "F.SilkS")
			(hide yes)
			(effects
				(font
					(size 1.27 1.27)
				)
			)
		)
		(property "Value" "4K7R2F-GP"
			(at 0.064008 -3.993896 90)
			(unlocked yes)
			(layer "F.Fab")
			(hide yes)
			(effects
				(font
					(size 1.016 1.016)
					(thickness 0.1524)
				)
			)
		)
		(property "Device Type" "R402H16"
			(at 0.064008 -5.517896 90)
			(unlocked yes)
			(layer "F.Fab")
			(hide yes)
			(effects
				(font
					(size 1.016 1.016)
					(thickness 0.1524)
				)
			)
		)
		(duplicate_pad_numbers_are_jumpers no)
		(fp_line
			(start 0.508 -0.9398)
			(end -0.508 -0.9398)
			(stroke
				(width 0.1524)
				(type default)
			)
			(layer "F.SilkS")
		)
		(fp_line
			(start -0.508 -0.9398)
			(end -0.508 0.9398)
			(stroke
				(width 0.1524)
				(type default)
			)
			(layer "F.SilkS")
		)
		(fp_rect
			(start -0.508 0.9398)
			(end 0.508 -0.9398)
			(stroke
				(width 0)
				(type default)
			)
			(fill no)
			(layer "F.CrtYd")
		)
		(fp_rect
			(start -0.508 0.9398)
			(end 0.508 -0.9398)
			(stroke
				(width 0)
				(type default)
			)
			(fill no)
			(layer "F.Fab")
		)
		(pad "1" smd custom
			(at 0 -0.4445 90)
			(size 0.1397 0.1397)
			(layers "F.Cu" "F.Mask" "F.Paste")
			(net "TCA9555_A0")
			(options
				(clearance outline)
				(anchor circle)
			)
			(primitives
				(gr_poly
					(pts
						(arc
							(start -0.1778 -0.2794)
							(mid -0.249642 -0.249642)
							(end -0.2794 -0.1778)
						)
						(arc
							(start -0.2794 0.1778)
							(mid -0.249642 0.249642)
							(end -0.1778 0.2794)
						)
						(arc
							(start 0.1778 0.2794)
							(mid 0.249642 0.249642)
							(end 0.2794 0.1778)
						)
						(arc
							(start 0.2794 -0.1778)
							(mid 0.249642 -0.249642)
							(end 0.1778 -0.2794)
						)
					)
					(width 0)
					(fill yes)
				)
			)
		)
		(pad "2" smd custom
			(at 0 0.4445 90)
			(size 0.1397 0.1397)
			(layers "F.Cu" "F.Mask" "F.Paste")
			(net "GND")
			(options
				(clearance outline)
				(anchor circle)
			)
			(primitives
				(gr_poly
					(pts
						(arc
							(start -0.1778 -0.2794)
							(mid -0.249642 -0.249642)
							(end -0.2794 -0.1778)
						)
						(arc
							(start -0.2794 0.1778)
							(mid -0.249642 0.249642)
							(end -0.1778 0.2794)
						)
						(arc
							(start 0.1778 0.2794)
							(mid 0.249642 0.249642)
							(end 0.2794 0.1778)
						)
						(arc
							(start 0.2794 -0.1778)
							(mid 0.249642 -0.249642)
							(end 0.1778 -0.2794)
						)
					)
					(width 0)
					(fill yes)
				)
			)
		)
	)
	(footprint ""
		(layer "F.Cu")
		(at 53.4416 -126.8222 -90)
		(property "Reference" "R610"
			(at 0 0 270)
			(layer "F.SilkS")
			(hide yes)
			(effects
				(font
					(size 1.27 1.27)
				)
			)
		)
		(property "Value" "100KR2F-L1-GP"
			(at 0.064008 -3.993896 270)
			(unlocked yes)
			(layer "F.Fab")
			(hide yes)
			(effects
				(font
					(size 1.016 1.016)
					(thickness 0.1524)
				)
			)
		)
		(property "Device Type" "R402H16"
			(at 0.064008 -5.517896 270)
			(unlocked yes)
			(layer "F.Fab")
			(hide yes)
			(effects
				(font
					(size 1.016 1.016)
					(thickness 0.1524)
				)
			)
		)
		(duplicate_pad_numbers_are_jumpers no)
		(fp_line
			(start -0.508 -0.9398)
			(end -0.508 0.9398)
			(stroke
				(width 0.1524)
				(type default)
			)
			(layer "F.SilkS")
		)
		(fp_line
			(start 0.508 -0.9398)
			(end -0.508 -0.9398)
			(stroke
				(width 0.1524)
				(type default)
			)
			(layer "F.SilkS")
		)
		(fp_rect
			(start -0.508 0.9398)
			(end 0.508 -0.9398)
			(stroke
				(width 0)
				(type default)
			)
			(fill no)
			(layer "F.CrtYd")
		)
		(fp_rect
			(start -0.508 0.9398)
			(end 0.508 -0.9398)
			(stroke
				(width 0)
				(type default)
			)
			(fill no)
			(layer "F.Fab")
		)
		(pad "1" smd custom
			(at 0 -0.4445 270)
			(size 0.1397 0.1397)
			(layers "F.Cu" "F.Mask" "F.Paste")
			(net "FLA1_WP_N")
			(options
				(clearance outline)
				(anchor circle)
			)
			(primitives
				(gr_poly
					(pts
						(arc
							(start -0.1778 -0.2794)
							(mid -0.249642 -0.249642)
							(end -0.2794 -0.1778)
						)
						(arc
							(start -0.2794 0.1778)
							(mid -0.249642 0.249642)
							(end -0.1778 0.2794)
						)
						(arc
							(start 0.1778 0.2794)
							(mid 0.249642 0.249642)
							(end 0.2794 0.1778)
						)
						(arc
							(start 0.2794 -0.1778)
							(mid 0.249642 -0.249642)
							(end 0.1778 -0.2794)
						)
					)
					(width 0)
					(fill yes)
				)
			)
		)
		(pad "2" smd custom
			(at 0 0.4445 270)
			(size 0.1397 0.1397)
			(layers "F.Cu" "F.Mask" "F.Paste")
			(net "GND")
			(options
				(clearance outline)
				(anchor circle)
			)
			(primitives
				(gr_poly
					(pts
						(arc
							(start -0.1778 -0.2794)
							(mid -0.249642 -0.249642)
							(end -0.2794 -0.1778)
						)
						(arc
							(start -0.2794 0.1778)
							(mid -0.249642 0.249642)
							(end -0.1778 0.2794)
						)
						(arc
							(start 0.1778 0.2794)
							(mid 0.249642 0.249642)
							(end 0.2794 0.1778)
						)
						(arc
							(start 0.2794 -0.1778)
							(mid 0.249642 -0.249642)
							(end 0.1778 -0.2794)
						)
					)
					(width 0)
					(fill yes)
				)
			)
		)
	)
	(footprint ""
		(layer "F.Cu")
		(at 92.751656 -155.60548 90)
		(property "Reference" "U99"
			(at 0 0 90)
			(layer "F.SilkS")
			(hide yes)
			(effects
				(font
					(size 1.27 1.27)
				)
			)
		)
		(property "Value" "USB2514B-AEZC-TR-GP-U"
			(at -5.5372 -5.2832 90)
			(unlocked yes)
			(layer "F.Fab")
			(hide yes)
			(effects
				(font
					(size 1.016 1.016)
					(thickness 0.1524)
				)
			)
		)
		(property "Device Type" "QFN36-G3D85H40"
			(at -5.5372 -6.8072 90)
			(unlocked yes)
			(layer "F.Fab")
			(hide yes)
			(effects
				(font
					(size 1.016 1.016)
					(thickness 0.1524)
				)
			)
		)
		(duplicate_pad_numbers_are_jumpers no)
		(fp_line
			(start -4.0132 -4.0132)
			(end -2.7432 -4.0132)
			(stroke
				(width 0.1524)
				(type default)
			)
			(layer "F.SilkS")
		)
		(fp_line
			(start -0.0254 -3.7846)
			(end -0.0254 -4.2926)
			(stroke
				(width 0.1524)
				(type default)
			)
			(layer "F.SilkS")
		)
		(fp_line
			(start -4.0132 -2.7432)
			(end -4.0132 -4.0132)
			(stroke
				(width 0.1524)
				(type default)
			)
			(layer "F.SilkS")
		)
		(fp_line
			(start -3.7846 -2.0066)
			(end -4.4704 -2.0066)
			(stroke
				(width 0.1524)
				(type default)
			)
			(layer "F.SilkS")
		)
		(fp_line
			(start 4.3434 -1.524)
			(end 3.8608 -1.524)
			(stroke
				(width 0.1524)
				(type default)
			)
			(layer "F.SilkS")
		)
		(fp_line
			(start -3.8608 0.4826)
			(end -4.318 0.4826)
			(stroke
				(width 0.1524)
				(type default)
			)
			(layer "F.SilkS")
		)
		(fp_line
			(start 4.4958 0.9652)
			(end 3.81 0.9652)
			(stroke
				(width 0.1524)
				(type default)
			)
			(layer "F.SilkS")
		)
		(fp_line
			(start -1.4986 3.8354)
			(end -1.4986 4.445)
			(stroke
				(width 0.1524)
				(type default)
			)
			(layer "F.SilkS")
		)
		(fp_line
			(start 4.0132 4.0132)
			(end 4.0132 2.7432)
			(stroke
				(width 0.1524)
				(type default)
			)
			(layer "F.SilkS")
		)
		(fp_line
			(start 2.7432 4.0132)
			(end 4.0132 4.0132)
			(stroke
				(width 0.1524)
				(type default)
			)
			(layer "F.SilkS")
		)
		(fp_line
			(start -2.7432 4.0132)
			(end -4.0132 4.0132)
			(stroke
				(width 0.1524)
				(type default)
			)
			(layer "F.SilkS")
		)
		(fp_line
			(start -4.0132 4.0132)
			(end -4.0132 2.7432)
			(stroke
				(width 0.1524)
				(type default)
			)
			(layer "F.SilkS")
		)
		(fp_line
			(start 0.9906 4.318)
			(end 0.9906 3.81)
			(stroke
				(width 0.1524)
				(type default)
			)
			(layer "F.SilkS")
		)
		(fp_poly
			(pts
				(xy 2.7432 -4.0132) (xy 4.0132 -2.7432) (xy 4.0132 -4.0132)
			)
			(stroke
				(width 0)
				(type default)
			)
			(fill yes)
			(layer "F.SilkS")
		)
		(fp_rect
			(start -4.0132 4.0132)
			(end 4.0132 -4.0132)
			(stroke
				(width 0)
				(type default)
			)
			(fill no)
			(layer "F.CrtYd")
		)
		(fp_rect
			(start -4.0132 4.0132)
			(end 4.0132 -4.0132)
			(stroke
				(width 0)
				(type default)
			)
			(fill no)
			(layer "F.Fab")
		)
		(pad "1" smd rect
			(at 1.999996 -2.9591 90)
			(size 0.3048 1.0922)
			(layers "F.Cu" "F.Mask" "F.Paste")
			(net "USB_P1_DN")
		)
		(pad "2" smd rect
			(at 1.500124 -2.8702 90)
			(size 0.3048 1.27)
			(layers "F.Cu" "F.Mask" "F.Paste")
			(net "USB_P1_DP")
		)
		(pad "3" smd rect
			(at 0.999998 -2.8702 90)
			(size 0.3048 1.27)
			(layers "F.Cu" "F.Mask" "F.Paste")
			(net "USB_P2_DN")
		)
		(pad "4" smd rect
			(at 0.500126 -2.8702 90)
			(size 0.3048 1.27)
			(layers "F.Cu" "F.Mask" "F.Paste")
			(net "USB_P2_DP")
		)
		(pad "5" smd rect
			(at 0 -2.8702 90)
			(size 0.3048 1.27)
			(layers "F.Cu" "F.Mask" "F.Paste")
			(net "P3V3_STBY")
		)
		(pad "6" smd rect
			(at -0.500126 -2.8702 90)
			(size 0.3048 1.27)
			(layers "F.Cu" "F.Mask" "F.Paste")
			(net "USB_P3_DN")
		)
		(pad "7" smd rect
			(at -0.999998 -2.8702 90)
			(size 0.3048 1.27)
			(layers "F.Cu" "F.Mask" "F.Paste")
			(net "USB_P3_DP")
		)
		(pad "8" smd rect
			(at -1.500124 -2.8702 90)
			(size 0.3048 1.27)
			(layers "F.Cu" "F.Mask" "F.Paste")
			(net "Net_135")
		)
		(pad "9" smd rect
			(at -1.999996 -2.9591 90)
			(size 0.3048 1.0922)
			(layers "F.Cu" "F.Mask" "F.Paste")
			(net "Net_136")
		)
		(pad "10" smd rect
			(at -2.9591 -1.999996 90)
			(size 1.0922 0.3048)
			(layers "F.Cu" "F.Mask" "F.Paste")
			(net "P3V3_STBY")
		)
		(pad "11" smd rect
			(at -2.8702 -1.500124 90)
			(size 1.27 0.3048)
			(layers "F.Cu" "F.Mask" "F.Paste")
			(net "GND")
		)
		(pad "12" smd rect
			(at -2.8702 -0.999998 90)
			(size 1.27 0.3048)
			(layers "F.Cu" "F.Mask" "F.Paste")
			(net "USB_EN_1")
		)
		(pad "13" smd rect
			(at -2.8702 -0.500126 90)
			(size 1.27 0.3048)
			(layers "F.Cu" "F.Mask" "F.Paste")
			(net "USB_OCS_N1")
		)
		(pad "14" smd rect
			(at -2.8702 0 90)
			(size 1.27 0.3048)
			(layers "F.Cu" "F.Mask" "F.Paste")
			(net "CRFILT")
		)
		(pad "15" smd rect
			(at -2.8702 0.500126 90)
			(size 1.27 0.3048)
			(layers "F.Cu" "F.Mask" "F.Paste")
			(net "P3V3_STBY")
		)
		(pad "16" smd rect
			(at -2.8702 0.999998 90)
			(size 1.27 0.3048)
			(layers "F.Cu" "F.Mask" "F.Paste")
			(net "USB_EN_2")
		)
		(pad "17" smd rect
			(at -2.8702 1.500124 90)
			(size 1.27 0.3048)
			(layers "F.Cu" "F.Mask" "F.Paste")
			(net "USB_OCS_N2")
		)
		(pad "18" smd rect
			(at -2.9591 1.999996 90)
			(size 1.0922 0.3048)
			(layers "F.Cu" "F.Mask" "F.Paste")
			(net "USB_EN_3")
		)
		(pad "19" smd rect
			(at -1.999996 2.9591 90)
			(size 0.3048 1.0922)
			(layers "F.Cu" "F.Mask" "F.Paste")
			(net "USB_OCS_N3")
		)
		(pad "20" smd rect
			(at -1.500124 2.8702 90)
			(size 0.3048 1.27)
			(layers "F.Cu" "F.Mask" "F.Paste")
			(net "USB_EN_4")
		)
		(pad "21" smd rect
			(at -0.999998 2.8702 90)
			(size 0.3048 1.27)
			(layers "F.Cu" "F.Mask" "F.Paste")
			(net "USB_OCS_N4")
		)
		(pad "22" smd rect
			(at -0.500126 2.8702 90)
			(size 0.3048 1.27)
			(layers "F.Cu" "F.Mask" "F.Paste")
			(net "TP_USB_SDA")
		)
		(pad "23" smd rect
			(at 0 2.8702 90)
			(size 0.3048 1.27)
			(layers "F.Cu" "F.Mask" "F.Paste")
			(net "P3V3_STBY")
		)
		(pad "24" smd rect
			(at 0.500126 2.8702 90)
			(size 0.3048 1.27)
			(layers "F.Cu" "F.Mask" "F.Paste")
			(net "CFG_SEL0")
		)
		(pad "25" smd rect
			(at 0.999998 2.8702 90)
			(size 0.3048 1.27)
			(layers "F.Cu" "F.Mask" "F.Paste")
			(net "CFG_SEL1")
		)
		(pad "26" smd rect
			(at 1.500124 2.8702 90)
			(size 0.3048 1.27)
			(layers "F.Cu" "F.Mask" "F.Paste")
			(net "USB_RESET_N")
		)
		(pad "27" smd rect
			(at 1.999996 2.9591 90)
			(size 0.3048 1.0922)
			(layers "F.Cu" "F.Mask" "F.Paste")
			(net "VBUS_DET")
		)
		(pad "28" smd rect
			(at 2.9591 1.999996 90)
			(size 1.0922 0.3048)
			(layers "F.Cu" "F.Mask" "F.Paste")
			(net "USB_SUSP_IND")
		)
		(pad "29" smd rect
			(at 2.8702 1.500124 90)
			(size 1.27 0.3048)
			(layers "F.Cu" "F.Mask" "F.Paste")
			(net "P3V3_STBY")
		)
		(pad "30" smd rect
			(at 2.8702 0.999998 90)
			(size 1.27 0.3048)
			(layers "F.Cu" "F.Mask" "F.Paste")
			(net "USB_COMP_DN")
		)
		(pad "31" smd rect
			(at 2.8702 0.500126 90)
			(size 1.27 0.3048)
			(layers "F.Cu" "F.Mask" "F.Paste")
			(net "USB_COMP_DP")
		)
		(pad "32" smd rect
			(at 2.8702 0 90)
			(size 1.27 0.3048)
			(layers "F.Cu" "F.Mask" "F.Paste")
			(net "USB_HUB_XTAL_OUT")
		)
		(pad "33" smd rect
			(at 2.8702 -0.500126 90)
			(size 1.27 0.3048)
			(layers "F.Cu" "F.Mask" "F.Paste")
			(net "USB_HUB_XTAL_IN")
		)
		(pad "34" smd rect
			(at 2.8702 -0.999998 90)
			(size 1.27 0.3048)
			(layers "F.Cu" "F.Mask" "F.Paste")
			(net "PLLFILT")
		)
		(pad "35" smd rect
			(at 2.8702 -1.500124 90)
			(size 1.27 0.3048)
			(layers "F.Cu" "F.Mask" "F.Paste")
			(net "RBIAS")
		)
		(pad "36" smd rect
			(at 2.9591 -1.999996 90)
			(size 1.0922 0.3048)
			(layers "F.Cu" "F.Mask" "F.Paste")
			(net "P3V3_STBY")
		)
		(pad "37" smd rect
			(at 0 0 90)
			(size 3.8608 3.8608)
			(layers "F.Cu" "F.Mask" "F.Paste")
			(net "GND")
		)
	)
	(footprint ""
		(layer "F.Cu")
		(at 193.839338 -126.524258 180)
		(property "Reference" "C284"
			(at 0 0 180)
			(layer "F.SilkS")
			(hide yes)
			(effects
				(font
					(size 1.27 1.27)
				)
			)
		)
		(property "Value" "SCD01U25V2KX-3GP"
			(at 1.1811 -2.7051 180)
			(unlocked yes)
			(layer "F.Fab")
			(hide yes)
			(effects
				(font
					(size 1.016 1.016)
					(thickness 0.1524)
				)
			)
		)
		(property "Device Type" "C402H22"
			(at 1.1811 -4.2291 180)
			(unlocked yes)
			(layer "F.Fab")
			(hide yes)
			(effects
				(font
					(size 1.016 1.016)
					(thickness 0.1524)
				)
			)
		)
		(duplicate_pad_numbers_are_jumpers no)
		(fp_rect
			(start -0.4318 0.9525)
			(end 0.4318 -0.9525)
			(stroke
				(width 0)
				(type default)
			)
			(fill no)
			(layer "F.CrtYd")
		)
		(fp_rect
			(start -0.4318 0.9525)
			(end 0.4318 -0.9525)
			(stroke
				(width 0)
				(type default)
			)
			(fill no)
			(layer "F.Fab")
		)
		(pad "1" smd custom
			(at 0 -0.4445 180)
			(size 0.1524 0.1524)
			(layers "F.Cu" "F.Mask" "F.Paste")
			(net "VT235_VDES")
			(options
				(clearance outline)
				(anchor circle)
			)
			(primitives
				(gr_poly
					(pts
						(arc
							(start 0.3048 -0.2032)
							(mid 0.275042 -0.275042)
							(end 0.2032 -0.3048)
						)
						(arc
							(start -0.2032 -0.3048)
							(mid -0.275042 -0.275042)
							(end -0.3048 -0.2032)
						)
						(arc
							(start -0.3048 0.2032)
							(mid -0.275042 0.275042)
							(end -0.2032 0.3048)
						)
						(arc
							(start 0.2032 0.3048)
							(mid 0.275042 0.275042)
							(end 0.3048 0.2032)
						)
					)
					(width 0)
					(fill yes)
				)
			)
		)
		(pad "2" smd custom
			(at 0 0.4445 180)
			(size 0.1524 0.1524)
			(layers "F.Cu" "F.Mask" "F.Paste")
			(net "VT235_VDES_RCC")
			(options
				(clearance outline)
				(anchor circle)
			)
			(primitives
				(gr_poly
					(pts
						(arc
							(start 0.3048 -0.2032)
							(mid 0.275042 -0.275042)
							(end 0.2032 -0.3048)
						)
						(arc
							(start -0.2032 -0.3048)
							(mid -0.275042 -0.275042)
							(end -0.3048 -0.2032)
						)
						(arc
							(start -0.3048 0.2032)
							(mid -0.275042 0.275042)
							(end -0.2032 0.3048)
						)
						(arc
							(start 0.2032 0.3048)
							(mid 0.275042 0.275042)
							(end 0.3048 0.2032)
						)
					)
					(width 0)
					(fill yes)
				)
			)
		)
	)
	(footprint ""
		(layer "F.Cu")
		(at 87.501476 -68.22059 -90)
		(property "Reference" "R14"
			(at 0 0 270)
			(layer "F.SilkS")
			(hide yes)
			(effects
				(font
					(size 1.27 1.27)
				)
			)
		)
		(property "Value" "0R2J-2-GP"
			(at 0.064008 -3.993896 270)
			(unlocked yes)
			(layer "F.Fab")
			(hide yes)
			(effects
				(font
					(size 1.016 1.016)
					(thickness 0.1524)
				)
			)
		)
		(property "Device Type" "R402H16"
			(at 0.064008 -5.517896 270)
			(unlocked yes)
			(layer "F.Fab")
			(hide yes)
			(effects
				(font
					(size 1.016 1.016)
					(thickness 0.1524)
				)
			)
		)
		(duplicate_pad_numbers_are_jumpers no)
		(fp_line
			(start -0.508 -0.9398)
			(end -0.508 0.9398)
			(stroke
				(width 0.1524)
				(type default)
			)
			(layer "F.SilkS")
		)
		(fp_line
			(start 0.508 -0.9398)
			(end -0.508 -0.9398)
			(stroke
				(width 0.1524)
				(type default)
			)
			(layer "F.SilkS")
		)
		(fp_rect
			(start -0.508 0.9398)
			(end 0.508 -0.9398)
			(stroke
				(width 0)
				(type default)
			)
			(fill no)
			(layer "F.CrtYd")
		)
		(fp_rect
			(start -0.508 0.9398)
			(end 0.508 -0.9398)
			(stroke
				(width 0)
				(type default)
			)
			(fill no)
			(layer "F.Fab")
		)
		(pad "1" smd custom
			(at 0 -0.4445 270)
			(size 0.1397 0.1397)
			(layers "F.Cu" "F.Mask" "F.Paste")
			(net "NCSI_RXD0")
			(options
				(clearance outline)
				(anchor circle)
			)
			(primitives
				(gr_poly
					(pts
						(arc
							(start -0.1778 -0.2794)
							(mid -0.249642 -0.249642)
							(end -0.2794 -0.1778)
						)
						(arc
							(start -0.2794 0.1778)
							(mid -0.249642 0.249642)
							(end -0.1778 0.2794)
						)
						(arc
							(start 0.1778 0.2794)
							(mid 0.249642 0.249642)
							(end 0.2794 0.1778)
						)
						(arc
							(start 0.2794 -0.1778)
							(mid 0.249642 -0.249642)
							(end 0.1778 -0.2794)
						)
					)
					(width 0)
					(fill yes)
				)
			)
		)
		(pad "2" smd custom
			(at 0 0.4445 270)
			(size 0.1397 0.1397)
			(layers "F.Cu" "F.Mask" "F.Paste")
			(net "NCSI_RXD0_R")
			(options
				(clearance outline)
				(anchor circle)
			)
			(primitives
				(gr_poly
					(pts
						(arc
							(start -0.1778 -0.2794)
							(mid -0.249642 -0.249642)
							(end -0.2794 -0.1778)
						)
						(arc
							(start -0.2794 0.1778)
							(mid -0.249642 0.249642)
							(end -0.1778 0.2794)
						)
						(arc
							(start 0.1778 0.2794)
							(mid 0.249642 0.249642)
							(end 0.2794 0.1778)
						)
						(arc
							(start 0.2794 -0.1778)
							(mid 0.249642 -0.249642)
							(end 0.1778 -0.2794)
						)
					)
					(width 0)
					(fill yes)
				)
			)
		)
	)
	(footprint ""
		(layer "F.Cu")
		(at 86.322154 -46.029118)
		(property "Reference" "R16"
			(at 0 0 0)
			(layer "F.SilkS")
			(hide yes)
			(effects
				(font
					(size 1.27 1.27)
				)
			)
		)
		(property "Value" "10KR2F-2-GP"
			(at 0.064008 -3.993896 0)
			(unlocked yes)
			(layer "F.Fab")
			(hide yes)
			(effects
				(font
					(size 1.016 1.016)
					(thickness 0.1524)
				)
			)
		)
		(property "Device Type" "R402H16"
			(at 0.064008 -5.517896 0)
			(unlocked yes)
			(layer "F.Fab")
			(hide yes)
			(effects
				(font
					(size 1.016 1.016)
					(thickness 0.1524)
				)
			)
		)
		(duplicate_pad_numbers_are_jumpers no)
		(fp_line
			(start -0.508 -0.9398)
			(end -0.508 0.9398)
			(stroke
				(width 0.1524)
				(type default)
			)
			(layer "F.SilkS")
		)
		(fp_line
			(start 0.508 -0.9398)
			(end -0.508 -0.9398)
			(stroke
				(width 0.1524)
				(type default)
			)
			(layer "F.SilkS")
		)
		(fp_rect
			(start -0.508 0.9398)
			(end 0.508 -0.9398)
			(stroke
				(width 0)
				(type default)
			)
			(fill no)
			(layer "F.CrtYd")
		)
		(fp_rect
			(start -0.508 0.9398)
			(end 0.508 -0.9398)
			(stroke
				(width 0)
				(type default)
			)
			(fill no)
			(layer "F.Fab")
		)
		(pad "1" smd custom
			(at 0 -0.4445)
			(size 0.1397 0.1397)
			(layers "F.Cu" "F.Mask" "F.Paste")
			(net "P3V3_STBY")
			(options
				(clearance outline)
				(anchor circle)
			)
			(primitives
				(gr_poly
					(pts
						(arc
							(start -0.1778 -0.2794)
							(mid -0.249642 -0.249642)
							(end -0.2794 -0.1778)
						)
						(arc
							(start -0.2794 0.1778)
							(mid -0.249642 0.249642)
							(end -0.1778 0.2794)
						)
						(arc
							(start 0.1778 0.2794)
							(mid 0.249642 0.249642)
							(end 0.2794 0.1778)
						)
						(arc
							(start 0.2794 -0.1778)
							(mid 0.249642 -0.249642)
							(end 0.1778 -0.2794)
						)
					)
					(width 0)
					(fill yes)
				)
			)
		)
		(pad "2" smd custom
			(at 0 0.4445)
			(size 0.1397 0.1397)
			(layers "F.Cu" "F.Mask" "F.Paste")
			(net "MEZZA_PRSNT1_N")
			(options
				(clearance outline)
				(anchor circle)
			)
			(primitives
				(gr_poly
					(pts
						(arc
							(start -0.1778 -0.2794)
							(mid -0.249642 -0.249642)
							(end -0.2794 -0.1778)
						)
						(arc
							(start -0.2794 0.1778)
							(mid -0.249642 0.249642)
							(end -0.1778 0.2794)
						)
						(arc
							(start 0.1778 0.2794)
							(mid 0.249642 0.249642)
							(end 0.2794 0.1778)
						)
						(arc
							(start 0.2794 -0.1778)
							(mid 0.249642 -0.249642)
							(end 0.1778 -0.2794)
						)
					)
					(width 0)
					(fill yes)
				)
			)
		)
	)
	(footprint ""
		(layer "F.Cu")
		(at 55.6768 -163.1442 180)
		(property "Reference" "R405"
			(at 0 0 180)
			(layer "F.SilkS")
			(hide yes)
			(effects
				(font
					(size 1.27 1.27)
				)
			)
		)
		(property "Value" "1KR2F-3-GP"
			(at 0.064008 -3.993896 180)
			(unlocked yes)
			(layer "F.Fab")
			(hide yes)
			(effects
				(font
					(size 1.016 1.016)
					(thickness 0.1524)
				)
			)
		)
		(property "Device Type" "R402H16"
			(at 0.064008 -5.517896 180)
			(unlocked yes)
			(layer "F.Fab")
			(hide yes)
			(effects
				(font
					(size 1.016 1.016)
					(thickness 0.1524)
				)
			)
		)
		(duplicate_pad_numbers_are_jumpers no)
		(fp_line
			(start 0.508 -0.9398)
			(end -0.508 -0.9398)
			(stroke
				(width 0.1524)
				(type default)
			)
			(layer "F.SilkS")
		)
		(fp_line
			(start -0.508 -0.9398)
			(end -0.508 0.9398)
			(stroke
				(width 0.1524)
				(type default)
			)
			(layer "F.SilkS")
		)
		(fp_rect
			(start -0.508 0.9398)
			(end 0.508 -0.9398)
			(stroke
				(width 0)
				(type default)
			)
			(fill no)
			(layer "F.CrtYd")
		)
		(fp_rect
			(start -0.508 0.9398)
			(end 0.508 -0.9398)
			(stroke
				(width 0)
				(type default)
			)
			(fill no)
			(layer "F.Fab")
		)
		(pad "1" smd custom
			(at 0 -0.4445 180)
			(size 0.1397 0.1397)
			(layers "F.Cu" "F.Mask" "F.Paste")
			(net "ADC_P1V8_STBY")
			(options
				(clearance outline)
				(anchor circle)
			)
			(primitives
				(gr_poly
					(pts
						(arc
							(start -0.1778 -0.2794)
							(mid -0.249642 -0.249642)
							(end -0.2794 -0.1778)
						)
						(arc
							(start -0.2794 0.1778)
							(mid -0.249642 0.249642)
							(end -0.1778 0.2794)
						)
						(arc
							(start 0.1778 0.2794)
							(mid 0.249642 0.249642)
							(end 0.2794 0.1778)
						)
						(arc
							(start 0.2794 -0.1778)
							(mid 0.249642 -0.249642)
							(end 0.1778 -0.2794)
						)
					)
					(width 0)
					(fill yes)
				)
			)
		)
		(pad "2" smd custom
			(at 0 0.4445 180)
			(size 0.1397 0.1397)
			(layers "F.Cu" "F.Mask" "F.Paste")
			(net "GND")
			(options
				(clearance outline)
				(anchor circle)
			)
			(primitives
				(gr_poly
					(pts
						(arc
							(start -0.1778 -0.2794)
							(mid -0.249642 -0.249642)
							(end -0.2794 -0.1778)
						)
						(arc
							(start -0.2794 0.1778)
							(mid -0.249642 0.249642)
							(end -0.1778 0.2794)
						)
						(arc
							(start 0.1778 0.2794)
							(mid 0.249642 0.249642)
							(end 0.2794 0.1778)
						)
						(arc
							(start 0.2794 -0.1778)
							(mid 0.249642 -0.249642)
							(end 0.1778 -0.2794)
						)
					)
					(width 0)
					(fill yes)
				)
			)
		)
	)
	(footprint ""
		(layer "F.Cu")
		(at 33.1216 -131.5212)
		(property "Reference" "OSC1"
			(at 0 0 0)
			(layer "F.SilkS")
			(hide yes)
			(effects
				(font
					(size 1.27 1.27)
				)
			)
		)
		(property "Value" "OSC-24MHZ-18-GP"
			(at 0.0127 -2.7686 0)
			(unlocked yes)
			(layer "F.Fab")
			(hide yes)
			(effects
				(font
					(size 1.016 1.016)
					(thickness 0.1524)
				)
			)
		)
		(property "Device Type" "OSC-3225-4P-3H48"
			(at 0.0127 -4.2926 0)
			(unlocked yes)
			(layer "F.Fab")
			(hide yes)
			(effects
				(font
					(size 1.016 1.016)
					(thickness 0.1524)
				)
			)
		)
		(duplicate_pad_numbers_are_jumpers no)
		(fp_line
			(start -2.2352 1.6256)
			(end -2.2352 0.635)
			(stroke
				(width 0.3302)
				(type default)
			)
			(layer "F.SilkS")
		)
		(fp_line
			(start -2.1209 -1.5367)
			(end 2.1209 -1.5367)
			(stroke
				(width 0.1524)
				(type default)
			)
			(layer "F.SilkS")
		)
		(fp_line
			(start -2.1209 1.5367)
			(end -2.1209 -1.5367)
			(stroke
				(width 0.1524)
				(type default)
			)
			(layer "F.SilkS")
		)
		(fp_line
			(start -1.3208 1.6256)
			(end -2.2352 1.6256)
			(stroke
				(width 0.3302)
				(type default)
			)
			(layer "F.SilkS")
		)
		(fp_line
			(start 2.1209 -1.5367)
			(end 2.1209 1.5367)
			(stroke
				(width 0.1524)
				(type default)
			)
			(layer "F.SilkS")
		)
		(fp_line
			(start 2.1209 1.5367)
			(end -2.1209 1.5367)
			(stroke
				(width 0.1524)
				(type default)
			)
			(layer "F.SilkS")
		)
		(fp_poly
			(pts
				(xy -2.8321 1.459992) (xy -2.8321 0.189992) (xy -2.1971 0.824992)
			)
			(stroke
				(width 0)
				(type default)
			)
			(fill yes)
			(layer "F.SilkS")
		)
		(fp_rect
			(start -1.6002 1.2446)
			(end 1.6002 -1.2446)
			(stroke
				(width 0)
				(type default)
			)
			(fill no)
			(layer "F.CrtYd")
		)
		(fp_poly
			(pts
				(xy -2.3749 1.7907) (xy -2.3749 -1.7907) (xy 2.3749 -1.7907) (xy 2.3749 1.7907) (xy 1.6002 1.7907)
				(xy 1.6002 -1.2446) (xy -1.6002 -1.2446) (xy -1.6002 1.2446) (xy 1.59512 1.2446) (xy 1.59512 1.7907)
			)
			(stroke
				(width 0)
				(type default)
			)
			(fill no)
			(layer "F.CrtYd")
		)
		(fp_rect
			(start -2.3749 1.7907)
			(end 2.3749 -1.7907)
			(stroke
				(width 0)
				(type default)
			)
			(fill no)
			(layer "F.Fab")
		)
		(pad "1" smd rect
			(at -1.171448 0.824992)
			(size 1.397 0.9144)
			(layers "F.Cu" "F.Mask" "F.Paste")
			(net "OSC_OE")
		)
		(pad "2" smd rect
			(at 1.171448 0.824992)
			(size 1.397 0.9144)
			(layers "F.Cu" "F.Mask" "F.Paste")
			(net "GND")
		)
		(pad "3" smd rect
			(at 1.171448 -0.824992)
			(size 1.397 0.9144)
			(layers "F.Cu" "F.Mask" "F.Paste")
			(net "OSC_OUT")
		)
		(pad "4" smd rect
			(at -1.171448 -0.824992)
			(size 1.397 0.9144)
			(layers "F.Cu" "F.Mask" "F.Paste")
			(net "P3V3_STBY")
		)
		(zone
			(layer "F.Cu")
			(hatch none 0.5)
			(connect_pads
				(clearance 0)
			)
			(min_thickness 0.25)
			(keepout
				(tracks not_allowed)
				(vias allowed)
				(pads allowed)
				(copperpour not_allowed)
				(footprints allowed)
			)
			(placement
				(enabled no)
				(sheetname "")
			)
			(fill
				(thermal_gap 0.5)
				(thermal_bridge_width 0.5)
				(island_removal_mode 0)
			)
			(polygon
				(pts
					(xy 32.973772 -131.478528) (xy 33.269428 -131.478528) (xy 33.269428 -131.563872) (xy 32.973772 -131.563872)
				)
			)
		)
		(zone
			(layer "F.Cu")
			(hatch none 0.5)
			(connect_pads
				(clearance 0)
			)
			(min_thickness 0.25)
			(keepout
				(tracks allowed)
				(vias not_allowed)
				(pads allowed)
				(copperpour not_allowed)
				(footprints allowed)
			)
			(placement
				(enabled no)
				(sheetname "")
			)
			(fill
				(thermal_gap 0.5)
				(thermal_bridge_width 0.5)
				(island_removal_mode 0)
			)
			(polygon
				(pts
					(xy 32.648652 -130.239008) (xy 32.648652 -131.153408) (xy 31.251652 -131.153408) (xy 31.251652 -131.888992)
					(xy 32.648652 -131.888992) (xy 32.648652 -132.803392) (xy 33.594548 -132.803392) (xy 33.594548 -131.888992)
					(xy 34.991548 -131.888992) (xy 34.991548 -131.153408) (xy 33.594548 -131.153408) (xy 33.594548 -130.239008)
				)
			)
		)
	)
	(footprint ""
		(layer "F.Cu")
		(at 187.198 -48.4378 180)
		(property "Reference" "R665"
			(at 0 0 180)
			(layer "F.SilkS")
			(hide yes)
			(effects
				(font
					(size 1.27 1.27)
				)
			)
		)
		(property "Value" "10KR2F-2-GP"
			(at 0.064008 -3.993896 180)
			(unlocked yes)
			(layer "F.Fab")
			(hide yes)
			(effects
				(font
					(size 1.016 1.016)
					(thickness 0.1524)
				)
			)
		)
		(property "Device Type" "R402H16"
			(at 0.064008 -5.517896 180)
			(unlocked yes)
			(layer "F.Fab")
			(hide yes)
			(effects
				(font
					(size 1.016 1.016)
					(thickness 0.1524)
				)
			)
		)
		(duplicate_pad_numbers_are_jumpers no)
		(fp_line
			(start 0.508 -0.9398)
			(end -0.508 -0.9398)
			(stroke
				(width 0.1524)
				(type default)
			)
			(layer "F.SilkS")
		)
		(fp_line
			(start -0.508 -0.9398)
			(end -0.508 0.9398)
			(stroke
				(width 0.1524)
				(type default)
			)
			(layer "F.SilkS")
		)
		(fp_rect
			(start -0.508 0.9398)
			(end 0.508 -0.9398)
			(stroke
				(width 0)
				(type default)
			)
			(fill no)
			(layer "F.CrtYd")
		)
		(fp_rect
			(start -0.508 0.9398)
			(end 0.508 -0.9398)
			(stroke
				(width 0)
				(type default)
			)
			(fill no)
			(layer "F.Fab")
		)
		(pad "1" smd custom
			(at 0 -0.4445 180)
			(size 0.1397 0.1397)
			(layers "F.Cu" "F.Mask" "F.Paste")
			(net "P1V8")
			(options
				(clearance outline)
				(anchor circle)
			)
			(primitives
				(gr_poly
					(pts
						(arc
							(start -0.1778 -0.2794)
							(mid -0.249642 -0.249642)
							(end -0.2794 -0.1778)
						)
						(arc
							(start -0.2794 0.1778)
							(mid -0.249642 0.249642)
							(end -0.1778 0.2794)
						)
						(arc
							(start 0.1778 0.2794)
							(mid 0.249642 0.249642)
							(end 0.2794 0.1778)
						)
						(arc
							(start 0.2794 -0.1778)
							(mid 0.249642 -0.249642)
							(end 0.1778 -0.2794)
						)
					)
					(width 0)
					(fill yes)
				)
			)
		)
		(pad "2" smd custom
			(at 0 0.4445 180)
			(size 0.1397 0.1397)
			(layers "F.Cu" "F.Mask" "F.Paste")
			(net "XM_CS0_N")
			(options
				(clearance outline)
				(anchor circle)
			)
			(primitives
				(gr_poly
					(pts
						(arc
							(start -0.1778 -0.2794)
							(mid -0.249642 -0.249642)
							(end -0.2794 -0.1778)
						)
						(arc
							(start -0.2794 0.1778)
							(mid -0.249642 0.249642)
							(end -0.1778 0.2794)
						)
						(arc
							(start 0.1778 0.2794)
							(mid 0.249642 0.249642)
							(end 0.2794 0.1778)
						)
						(arc
							(start 0.2794 -0.1778)
							(mid 0.249642 -0.249642)
							(end 0.1778 -0.2794)
						)
					)
					(width 0)
					(fill yes)
				)
			)
		)
	)
	(footprint ""
		(layer "F.Cu")
		(at 93.875606 -129.506726 -90)
		(property "Reference" "U33"
			(at 0 0 270)
			(layer "F.SilkS")
			(hide yes)
			(effects
				(font
					(size 1.27 1.27)
				)
			)
		)
		(property "Value" "TS5A23157DGSR-GP"
			(at 0 -11.1252 270)
			(unlocked yes)
			(layer "F.Fab")
			(hide yes)
			(effects
				(font
					(size 1.016 1.016)
					(thickness 0.1524)
				)
			)
		)
		(property "Device Type" "MSOP10H44"
			(at 0 -12.6492 270)
			(unlocked yes)
			(layer "F.Fab")
			(hide yes)
			(effects
				(font
					(size 1.016 1.016)
					(thickness 0.1524)
				)
			)
		)
		(duplicate_pad_numbers_are_jumpers no)
		(fp_line
			(start -2.0066 1.016)
			(end -2.0066 -1.016)
			(stroke
				(width 0.1524)
				(type default)
			)
			(layer "F.SilkS")
		)
		(fp_line
			(start -1.8288 1.016)
			(end -1.8288 3.048)
			(stroke
				(width 0.508)
				(type default)
			)
			(layer "F.SilkS")
		)
		(fp_line
			(start 1.143 1.016)
			(end -2.0066 1.016)
			(stroke
				(width 0.1524)
				(type default)
			)
			(layer "F.SilkS")
		)
		(fp_line
			(start -1.5748 0)
			(end -1.9558 0.381)
			(stroke
				(width 0.1524)
				(type default)
			)
			(layer "F.SilkS")
		)
		(fp_line
			(start -1.5748 0)
			(end -1.9558 -0.381)
			(stroke
				(width 0.1524)
				(type default)
			)
			(layer "F.SilkS")
		)
		(fp_line
			(start -2.0066 -1.016)
			(end 1.143 -1.016)
			(stroke
				(width 0.1524)
				(type default)
			)
			(layer "F.SilkS")
		)
		(fp_line
			(start 1.143 -1.016)
			(end 1.143 1.016)
			(stroke
				(width 0.1524)
				(type default)
			)
			(layer "F.SilkS")
		)
		(fp_poly
			(pts
				(xy -2.0828 3.3401) (xy 2.0828 3.3401) (xy 2.0828 -3.3401) (xy -2.0828 -3.3401)
			)
			(stroke
				(width 0)
				(type default)
			)
			(fill no)
			(layer "F.CrtYd")
		)
		(fp_poly
			(pts
				(xy -2.0828 3.3401) (xy 2.0828 3.3401) (xy 2.0828 -3.3401) (xy -2.0828 -3.3401)
			)
			(stroke
				(width 0)
				(type default)
			)
			(fill no)
			(layer "F.Fab")
		)
		(pad "1" smd rect
			(at -0.99949 2.0701 270)
			(size 0.3048 1.524)
			(layers "F.Cu" "F.Mask" "F.Paste")
			(net "UART_SEL_MUX")
		)
		(pad "2" smd rect
			(at -0.50038 2.0701 270)
			(size 0.3048 1.524)
			(layers "F.Cu" "F.Mask" "F.Paste")
			(net "UART_BMC_TX")
		)
		(pad "3" smd rect
			(at 0 2.0701 270)
			(size 0.3048 1.524)
			(layers "F.Cu" "F.Mask" "F.Paste")
			(net "GND")
		)
		(pad "4" smd rect
			(at 0.50038 2.0701 270)
			(size 0.3048 1.524)
			(layers "F.Cu" "F.Mask" "F.Paste")
			(net "UART_BMC_RX")
		)
		(pad "5" smd rect
			(at 0.99949 2.0701 270)
			(size 0.3048 1.524)
			(layers "F.Cu" "F.Mask" "F.Paste")
			(net "UART_SEL_MUX")
		)
		(pad "6" smd rect
			(at 0.99949 -2.0701 270)
			(size 0.3048 1.524)
			(layers "F.Cu" "F.Mask" "F.Paste")
			(net "DEBUG_UART_IOM_RX")
		)
		(pad "7" smd rect
			(at 0.50038 -2.0701 270)
			(size 0.3048 1.524)
			(layers "F.Cu" "F.Mask" "F.Paste")
			(net "UART_COMP_IN_RX")
		)
		(pad "8" smd rect
			(at 0 -2.0701 270)
			(size 0.3048 1.524)
			(layers "F.Cu" "F.Mask" "F.Paste")
			(net "P3V3_STBY")
		)
		(pad "9" smd rect
			(at -0.50038 -2.0701 270)
			(size 0.3048 1.524)
			(layers "F.Cu" "F.Mask" "F.Paste")
			(net "UART_COMP_OUT_TX")
		)
		(pad "10" smd rect
			(at -0.99949 -2.0701 270)
			(size 0.3048 1.524)
			(layers "F.Cu" "F.Mask" "F.Paste")
			(net "DEBUG_UART_IOM_TX")
		)
	)
	(footprint ""
		(layer "F.Cu")
		(at 171.494196 -117.368066)
		(property "Reference" "C219"
			(at 0 0 0)
			(layer "F.SilkS")
			(hide yes)
			(effects
				(font
					(size 1.27 1.27)
				)
			)
		)
		(property "Value" "SCD47U25V3KX-3-GP"
			(at 0 -2.8194 0)
			(unlocked yes)
			(layer "F.Fab")
			(hide yes)
			(effects
				(font
					(size 1.016 1.016)
					(thickness 0.1524)
				)
			)
		)
		(property "Device Type" "C603H36"
			(at 0 -4.3434 0)
			(unlocked yes)
			(layer "F.Fab")
			(hide yes)
			(effects
				(font
					(size 1.016 1.016)
					(thickness 0.1524)
				)
			)
		)
		(duplicate_pad_numbers_are_jumpers no)
		(fp_line
			(start 0.508 0)
			(end -0.508 0)
			(stroke
				(width 0.2032)
				(type default)
			)
			(layer "F.SilkS")
		)
		(fp_rect
			(start -0.5842 1.3335)
			(end 0.5842 -1.3335)
			(stroke
				(width 0)
				(type default)
			)
			(fill no)
			(layer "F.CrtYd")
		)
		(fp_rect
			(start -0.5842 1.3335)
			(end 0.5842 -1.3335)
			(stroke
				(width 0)
				(type default)
			)
			(fill no)
			(layer "F.Fab")
		)
		(pad "1" smd custom
			(at 0 -0.762)
			(size 0.2159 0.2159)
			(layers "F.Cu" "F.Mask" "F.Paste")
			(net "PQ4_D")
			(options
				(clearance outline)
				(anchor circle)
			)
			(primitives
				(gr_poly
					(pts
						(arc
							(start -0.3302 -0.4318)
							(mid -0.402042 -0.402042)
							(end -0.4318 -0.3302)
						)
						(arc
							(start -0.4318 0.3302)
							(mid -0.402042 0.402042)
							(end -0.3302 0.4318)
						)
						(arc
							(start 0.3302 0.4318)
							(mid 0.402042 0.402042)
							(end 0.4318 0.3302)
						)
						(arc
							(start 0.4318 -0.3302)
							(mid 0.402042 -0.402042)
							(end 0.3302 -0.4318)
						)
					)
					(width 0)
					(fill yes)
				)
			)
		)
		(pad "2" smd custom
			(at 0 0.762)
			(size 0.2159 0.2159)
			(layers "F.Cu" "F.Mask" "F.Paste")
			(net "P1V8")
			(options
				(clearance outline)
				(anchor circle)
			)
			(primitives
				(gr_poly
					(pts
						(arc
							(start -0.3302 -0.4318)
							(mid -0.402042 -0.402042)
							(end -0.4318 -0.3302)
						)
						(arc
							(start -0.4318 0.3302)
							(mid -0.402042 0.402042)
							(end -0.3302 0.4318)
						)
						(arc
							(start 0.3302 0.4318)
							(mid 0.402042 0.402042)
							(end 0.4318 0.3302)
						)
						(arc
							(start 0.4318 -0.3302)
							(mid 0.402042 -0.402042)
							(end 0.3302 -0.4318)
						)
					)
					(width 0)
					(fill yes)
				)
			)
		)
	)
	(footprint ""
		(layer "F.Cu")
		(at 77.283818 -74.153268 90)
		(property "Reference" "VIA2"
			(at 0 0 90)
			(layer "F.SilkS")
			(hide yes)
			(effects
				(font
					(size 1.27 1.27)
				)
			)
		)
		(property "Value" "85OHM-8L-1D6MM-L16L18-GP"
			(at 4.064 0.6096 90)
			(unlocked yes)
			(layer "F.Fab")
			(hide yes)
			(effects
				(font
					(size 1.016 1.016)
					(thickness 0.1524)
				)
			)
		)
		(property "Device Type" "VIA-PCIE-4P-368076"
			(at 4.064 -0.9144 90)
			(unlocked yes)
			(layer "F.Fab")
			(hide yes)
			(effects
				(font
					(size 1.016 1.016)
					(thickness 0.1524)
				)
			)
		)
		(duplicate_pad_numbers_are_jumpers no)
		(fp_rect
			(start -1.8415 0.381)
			(end 1.8415 -0.381)
			(stroke
				(width 0)
				(type default)
			)
			(fill no)
			(layer "F.CrtYd")
		)
		(fp_rect
			(start -1.8415 0.381)
			(end 1.8415 -0.381)
			(stroke
				(width 0)
				(type default)
			)
			(fill no)
			(layer "F.Fab")
		)
		(pad "1" thru_hole circle
			(at -1.4605 0 90)
			(size 0.508 0.508)
			(drill 0.254)
			(layers "*.Cu" "*.Mask")
			(remove_unused_layers no)
			(net "GND")
			(clearance 0.127)
			(thermal_gap 0.127)
		)
		(pad "2" thru_hole circle
			(at -0.4445 0 90)
			(size 0.508 0.508)
			(drill 0.254)
			(layers "*.Cu" "*.Mask")
			(remove_unused_layers no)
			(net "PCIE_COMP_TO_IOM_17_DP")
			(clearance 0.127)
			(thermal_gap 0.127)
		)
		(pad "3" thru_hole circle
			(at 0.4445 0 90)
			(size 0.508 0.508)
			(drill 0.254)
			(layers "*.Cu" "*.Mask")
			(remove_unused_layers no)
			(net "PCIE_COMP_TO_IOM_17_DN")
			(clearance 0.127)
			(thermal_gap 0.127)
		)
		(pad "4" thru_hole circle
			(at 1.4605 0 90)
			(size 0.508 0.508)
			(drill 0.254)
			(layers "*.Cu" "*.Mask")
			(remove_unused_layers no)
			(net "GND")
			(clearance 0.127)
			(thermal_gap 0.127)
		)
	)
	(footprint ""
		(layer "F.Cu")
		(at 168.6306 -109.1946 -90)
		(property "Reference" "C466"
			(at 0 0 270)
			(layer "F.SilkS")
			(hide yes)
			(effects
				(font
					(size 1.27 1.27)
				)
			)
		)
		(property "Value" "SC1U16V2KX-7-GP"
			(at 1.7526 -1.6002 270)
			(unlocked yes)
			(layer "F.Fab")
			(hide yes)
			(effects
				(font
					(size 1.016 1.016)
					(thickness 0.1524)
				)
			)
		)
		(property "Device Type" "C402-TO0D2H24"
			(at 1.7526 -3.1242 270)
			(unlocked yes)
			(layer "F.Fab")
			(hide yes)
			(effects
				(font
					(size 1.016 1.016)
					(thickness 0.1524)
				)
			)
		)
		(duplicate_pad_numbers_are_jumpers no)
		(fp_rect
			(start -0.4826 0.889)
			(end 0.4826 -0.889)
			(stroke
				(width 0)
				(type default)
			)
			(fill no)
			(layer "F.CrtYd")
		)
		(fp_rect
			(start -0.4826 0.889)
			(end 0.4826 -0.889)
			(stroke
				(width 0)
				(type default)
			)
			(fill no)
			(layer "F.Fab")
		)
		(pad "1" smd custom
			(at 0 -0.4572 270)
			(size 0.1524 0.1524)
			(layers "F.Cu" "F.Mask" "F.Paste")
			(net "P1V8")
			(options
				(clearance outline)
				(anchor circle)
			)
			(primitives
				(gr_poly
					(pts
						(arc
							(start -0.254 0.3048)
							(mid -0.325842 0.275042)
							(end -0.3556 0.2032)
						)
						(arc
							(start -0.3556 -0.2032)
							(mid -0.325842 -0.275042)
							(end -0.254 -0.3048)
						)
						(arc
							(start 0.254 -0.3048)
							(mid 0.325842 -0.275042)
							(end 0.3556 -0.2032)
						)
						(arc
							(start 0.3556 0.2032)
							(mid 0.325842 0.275042)
							(end 0.254 0.3048)
						)
					)
					(width 0)
					(fill yes)
				)
			)
		)
		(pad "2" smd custom
			(at 0 0.4572 270)
			(size 0.1524 0.1524)
			(layers "F.Cu" "F.Mask" "F.Paste")
			(net "GND")
			(options
				(clearance outline)
				(anchor circle)
			)
			(primitives
				(gr_poly
					(pts
						(arc
							(start -0.254 0.3048)
							(mid -0.325842 0.275042)
							(end -0.3556 0.2032)
						)
						(arc
							(start -0.3556 -0.2032)
							(mid -0.325842 -0.275042)
							(end -0.254 -0.3048)
						)
						(arc
							(start 0.254 -0.3048)
							(mid 0.325842 -0.275042)
							(end 0.3556 -0.2032)
						)
						(arc
							(start 0.3556 0.2032)
							(mid 0.325842 0.275042)
							(end 0.254 0.3048)
						)
					)
					(width 0)
					(fill yes)
				)
			)
		)
	)
	(footprint ""
		(layer "F.Cu")
		(at 42.5704 -185.039 90)
		(property "Reference" "L9"
			(at 0 0 90)
			(layer "F.SilkS")
			(hide yes)
			(effects
				(font
					(size 1.27 1.27)
				)
			)
		)
		(property "Value" "COIL-3D3UH-26-GP"
			(at -4.699 -4.0132 90)
			(unlocked yes)
			(layer "F.Fab")
			(hide yes)
			(effects
				(font
					(size 1.016 1.016)
					(thickness 0.1524)
				)
			)
		)
		(property "Device Type" "L7066-1830-UH119"
			(at -4.699 -5.5372 90)
			(unlocked yes)
			(layer "F.Fab")
			(hide yes)
			(effects
				(font
					(size 1.016 1.016)
					(thickness 0.1524)
				)
			)
		)
		(duplicate_pad_numbers_are_jumpers no)
		(fp_line
			(start 3.556 -4.4958)
			(end 3.556 4.4958)
			(stroke
				(width 0.1524)
				(type default)
			)
			(layer "F.SilkS")
		)
		(fp_line
			(start -3.556 -4.4958)
			(end 3.556 -4.4958)
			(stroke
				(width 0.1524)
				(type default)
			)
			(layer "F.SilkS")
		)
		(fp_line
			(start 3.556 4.4958)
			(end -3.556 4.4958)
			(stroke
				(width 0.1524)
				(type default)
			)
			(layer "F.SilkS")
		)
		(fp_line
			(start -3.556 4.4958)
			(end -3.556 -4.4958)
			(stroke
				(width 0.1524)
				(type default)
			)
			(layer "F.SilkS")
		)
		(fp_rect
			(start -3.302 3.4798)
			(end 3.302 -3.4798)
			(stroke
				(width 0)
				(type default)
			)
			(fill no)
			(layer "F.CrtYd")
		)
		(fp_poly
			(pts
				(xy -3.81 4.572) (xy -3.81 -4.572) (xy 3.81 -4.572) (xy 3.81 -0.5588) (xy 3.302 -0.5588) (xy 3.302 -3.4798)
				(xy -3.302 -3.4798) (xy -3.302 3.4798) (xy 3.302 3.4798) (xy 3.302 -0.5461) (xy 3.81 -0.5461) (xy 3.81 4.572)
			)
			(stroke
				(width 0)
				(type default)
			)
			(fill no)
			(layer "F.CrtYd")
		)
		(fp_rect
			(start -3.81 4.572)
			(end 3.81 -4.572)
			(stroke
				(width 0)
				(type default)
			)
			(fill no)
			(layer "F.Fab")
		)
		(pad "1" smd rect
			(at 0 -2.779522 90)
			(size 3.5052 2.921)
			(layers "F.Cu" "F.Mask" "F.Paste")
			(net "P3V3_STBY_LL")
		)
		(pad "2" smd rect
			(at 0 2.779522 90)
			(size 3.5052 2.921)
			(layers "F.Cu" "F.Mask" "F.Paste")
			(net "P3V3_STBY_OUT")
		)
	)
	(footprint ""
		(layer "F.Cu")
		(at 43.2054 -179.4256)
		(property "Reference" "C181"
			(at 0 0 0)
			(layer "F.SilkS")
			(hide yes)
			(effects
				(font
					(size 1.27 1.27)
				)
			)
		)
		(property "Value" "SCD1U25V2KX-2-GP"
			(at 1.1811 -2.7051 0)
			(unlocked yes)
			(layer "F.Fab")
			(hide yes)
			(effects
				(font
					(size 1.016 1.016)
					(thickness 0.1524)
				)
			)
		)
		(property "Device Type" "C402H22"
			(at 1.1811 -4.2291 0)
			(unlocked yes)
			(layer "F.Fab")
			(hide yes)
			(effects
				(font
					(size 1.016 1.016)
					(thickness 0.1524)
				)
			)
		)
		(duplicate_pad_numbers_are_jumpers no)
		(fp_rect
			(start -0.4318 0.9525)
			(end 0.4318 -0.9525)
			(stroke
				(width 0)
				(type default)
			)
			(fill no)
			(layer "F.CrtYd")
		)
		(fp_rect
			(start -0.4318 0.9525)
			(end 0.4318 -0.9525)
			(stroke
				(width 0)
				(type default)
			)
			(fill no)
			(layer "F.Fab")
		)
		(pad "1" smd custom
			(at 0 -0.4445)
			(size 0.1524 0.1524)
			(layers "F.Cu" "F.Mask" "F.Paste")
			(net "P3V3_STBY_OUT")
			(options
				(clearance outline)
				(anchor circle)
			)
			(primitives
				(gr_poly
					(pts
						(arc
							(start 0.3048 -0.2032)
							(mid 0.275042 -0.275042)
							(end 0.2032 -0.3048)
						)
						(arc
							(start -0.2032 -0.3048)
							(mid -0.275042 -0.275042)
							(end -0.3048 -0.2032)
						)
						(arc
							(start -0.3048 0.2032)
							(mid -0.275042 0.275042)
							(end -0.2032 0.3048)
						)
						(arc
							(start 0.2032 0.3048)
							(mid 0.275042 0.275042)
							(end 0.3048 0.2032)
						)
					)
					(width 0)
					(fill yes)
				)
			)
		)
		(pad "2" smd custom
			(at 0 0.4445)
			(size 0.1524 0.1524)
			(layers "F.Cu" "F.Mask" "F.Paste")
			(net "P3V3_STBY_LL_R")
			(options
				(clearance outline)
				(anchor circle)
			)
			(primitives
				(gr_poly
					(pts
						(arc
							(start 0.3048 -0.2032)
							(mid 0.275042 -0.275042)
							(end 0.2032 -0.3048)
						)
						(arc
							(start -0.2032 -0.3048)
							(mid -0.275042 -0.275042)
							(end -0.3048 -0.2032)
						)
						(arc
							(start -0.3048 0.2032)
							(mid -0.275042 0.275042)
							(end -0.2032 0.3048)
						)
						(arc
							(start 0.2032 0.3048)
							(mid 0.275042 0.275042)
							(end 0.3048 0.2032)
						)
					)
					(width 0)
					(fill yes)
				)
			)
		)
	)
	(footprint ""
		(layer "F.Cu")
		(at 211.6328 -65.9638 -45)
		(property "Reference" "VIA47"
			(at 0 0 315)
			(layer "F.SilkS")
			(hide yes)
			(effects
				(font
					(size 1.27 1.27)
				)
			)
		)
		(property "Value" "100OHM-8L-1D6MM-L18L16-GP"
			(at -3.720879 -4.508552 315)
			(unlocked yes)
			(layer "F.Fab")
			(hide yes)
			(effects
				(font
					(size 1.016 1.016)
					(thickness 0.1524)
				)
			)
		)
		(property "Device Type" "VIA-PCIE-4P-394076"
			(at -3.721059 -6.032502 315)
			(unlocked yes)
			(layer "F.Fab")
			(hide yes)
			(effects
				(font
					(size 1.016 1.016)
					(thickness 0.1524)
				)
			)
		)
		(duplicate_pad_numbers_are_jumpers no)
		(fp_poly
			(pts
				(xy -1.968472 -0.380877) (xy 1.968528 -0.380878) (xy 1.968527 0.381122) (xy -1.968472 0.381122)
			)
			(stroke
				(width 0)
				(type default)
			)
			(fill no)
			(layer "F.CrtYd")
		)
		(fp_poly
			(pts
				(xy -1.968472 -0.380877) (xy 1.968528 -0.380878) (xy 1.968527 0.381122) (xy -1.968472 0.381122)
			)
			(stroke
				(width 0)
				(type default)
			)
			(fill no)
			(layer "F.Fab")
		)
		(pad "1" thru_hole circle
			(at -1.5875 0 315)
			(size 0.508 0.508)
			(drill 0.254)
			(layers "*.Cu" "*.Mask")
			(remove_unused_layers no)
			(net "GND")
			(clearance 0.127)
			(thermal_gap 0.127)
		)
		(pad "2" thru_hole circle
			(at -0.571501 0 315)
			(size 0.508 0.508)
			(drill 0.254)
			(layers "*.Cu" "*.Mask")
			(remove_unused_layers no)
			(net "PHY_IOC_TO_CON_B_2_DP")
			(clearance 0.127)
			(thermal_gap 0.127)
		)
		(pad "3" thru_hole circle
			(at 0.571501 0 315)
			(size 0.508 0.508)
			(drill 0.254)
			(layers "*.Cu" "*.Mask")
			(remove_unused_layers no)
			(net "PHY_IOC_TO_CON_B_2_DN")
			(clearance 0.127)
			(thermal_gap 0.127)
		)
		(pad "4" thru_hole circle
			(at 1.5875 0 315)
			(size 0.508 0.508)
			(drill 0.254)
			(layers "*.Cu" "*.Mask")
			(remove_unused_layers no)
			(net "GND")
			(clearance 0.127)
			(thermal_gap 0.127)
		)
	)
	(footprint ""
		(layer "F.Cu")
		(at 201.803 -126.8476)
		(property "Reference" "C252"
			(at 0 0 0)
			(layer "F.SilkS")
			(hide yes)
			(effects
				(font
					(size 1.27 1.27)
				)
			)
		)
		(property "Value" "SC470P50V2KX-3GP"
			(at 1.1811 -2.7051 0)
			(unlocked yes)
			(layer "F.Fab")
			(hide yes)
			(effects
				(font
					(size 1.016 1.016)
					(thickness 0.1524)
				)
			)
		)
		(property "Device Type" "C402H22"
			(at 1.1811 -4.2291 0)
			(unlocked yes)
			(layer "F.Fab")
			(hide yes)
			(effects
				(font
					(size 1.016 1.016)
					(thickness 0.1524)
				)
			)
		)
		(duplicate_pad_numbers_are_jumpers no)
		(fp_rect
			(start -0.4318 0.9525)
			(end 0.4318 -0.9525)
			(stroke
				(width 0)
				(type default)
			)
			(fill no)
			(layer "F.CrtYd")
		)
		(fp_rect
			(start -0.4318 0.9525)
			(end 0.4318 -0.9525)
			(stroke
				(width 0)
				(type default)
			)
			(fill no)
			(layer "F.Fab")
		)
		(pad "1" smd custom
			(at 0 -0.4445)
			(size 0.1524 0.1524)
			(layers "F.Cu" "F.Mask" "F.Paste")
			(net "GND")
			(options
				(clearance outline)
				(anchor circle)
			)
			(primitives
				(gr_poly
					(pts
						(arc
							(start 0.3048 -0.2032)
							(mid 0.275042 -0.275042)
							(end 0.2032 -0.3048)
						)
						(arc
							(start -0.2032 -0.3048)
							(mid -0.275042 -0.275042)
							(end -0.3048 -0.2032)
						)
						(arc
							(start -0.3048 0.2032)
							(mid -0.275042 0.275042)
							(end -0.2032 0.3048)
						)
						(arc
							(start 0.2032 0.3048)
							(mid 0.275042 0.275042)
							(end 0.3048 0.2032)
						)
					)
					(width 0)
					(fill yes)
				)
			)
		)
		(pad "2" smd custom
			(at 0 0.4445)
			(size 0.1524 0.1524)
			(layers "F.Cu" "F.Mask" "F.Paste")
			(net "TPS74801_1V5_SS")
			(options
				(clearance outline)
				(anchor circle)
			)
			(primitives
				(gr_poly
					(pts
						(arc
							(start 0.3048 -0.2032)
							(mid 0.275042 -0.275042)
							(end 0.2032 -0.3048)
						)
						(arc
							(start -0.2032 -0.3048)
							(mid -0.275042 -0.275042)
							(end -0.3048 -0.2032)
						)
						(arc
							(start -0.3048 0.2032)
							(mid -0.275042 0.275042)
							(end -0.2032 0.3048)
						)
						(arc
							(start 0.2032 0.3048)
							(mid 0.275042 0.275042)
							(end 0.3048 0.2032)
						)
					)
					(width 0)
					(fill yes)
				)
			)
		)
	)
	(footprint ""
		(layer "F.Cu")
		(at 124.862844 -9.628378 90)
		(property "Reference" "C130"
			(at 0 0 90)
			(layer "F.SilkS")
			(hide yes)
			(effects
				(font
					(size 1.27 1.27)
				)
			)
		)
		(property "Value" "SCD1U16V2KX-3GP"
			(at 1.1811 -2.7051 90)
			(unlocked yes)
			(layer "F.Fab")
			(hide yes)
			(effects
				(font
					(size 1.016 1.016)
					(thickness 0.1524)
				)
			)
		)
		(property "Device Type" "C402H22"
			(at 1.1811 -4.2291 90)
			(unlocked yes)
			(layer "F.Fab")
			(hide yes)
			(effects
				(font
					(size 1.016 1.016)
					(thickness 0.1524)
				)
			)
		)
		(duplicate_pad_numbers_are_jumpers no)
		(fp_rect
			(start -0.4318 0.9525)
			(end 0.4318 -0.9525)
			(stroke
				(width 0)
				(type default)
			)
			(fill no)
			(layer "F.CrtYd")
		)
		(fp_rect
			(start -0.4318 0.9525)
			(end 0.4318 -0.9525)
			(stroke
				(width 0)
				(type default)
			)
			(fill no)
			(layer "F.Fab")
		)
		(pad "1" smd custom
			(at 0 -0.4445 90)
			(size 0.1524 0.1524)
			(layers "F.Cu" "F.Mask" "F.Paste")
			(net "MB0_CM_VOUT_R")
			(options
				(clearance outline)
				(anchor circle)
			)
			(primitives
				(gr_poly
					(pts
						(arc
							(start 0.3048 -0.2032)
							(mid 0.275042 -0.275042)
							(end 0.2032 -0.3048)
						)
						(arc
							(start -0.2032 -0.3048)
							(mid -0.275042 -0.275042)
							(end -0.3048 -0.2032)
						)
						(arc
							(start -0.3048 0.2032)
							(mid -0.275042 0.275042)
							(end -0.2032 0.3048)
						)
						(arc
							(start 0.2032 0.3048)
							(mid 0.275042 0.275042)
							(end 0.3048 0.2032)
						)
					)
					(width 0)
					(fill yes)
				)
			)
		)
		(pad "2" smd custom
			(at 0 0.4445 90)
			(size 0.1524 0.1524)
			(layers "F.Cu" "F.Mask" "F.Paste")
			(net "AGND_CURRENT_MON")
			(options
				(clearance outline)
				(anchor circle)
			)
			(primitives
				(gr_poly
					(pts
						(arc
							(start 0.3048 -0.2032)
							(mid 0.275042 -0.275042)
							(end 0.2032 -0.3048)
						)
						(arc
							(start -0.2032 -0.3048)
							(mid -0.275042 -0.275042)
							(end -0.3048 -0.2032)
						)
						(arc
							(start -0.3048 0.2032)
							(mid -0.275042 0.275042)
							(end -0.2032 0.3048)
						)
						(arc
							(start 0.2032 0.3048)
							(mid 0.275042 0.275042)
							(end 0.3048 0.2032)
						)
					)
					(width 0)
					(fill yes)
				)
			)
		)
	)
	(footprint ""
		(layer "F.Cu")
		(at 205.867 -49.9618)
		(property "Reference" "TP136"
			(at 0 0 0)
			(layer "F.SilkS")
			(hide yes)
			(effects
				(font
					(size 1.27 1.27)
				)
			)
		)
		(property "Value" "TPAD28-2-GP"
			(at -0.0127 -1.6637 0)
			(unlocked yes)
			(layer "F.Fab")
			(hide yes)
			(effects
				(font
					(size 1.016 1.016)
					(thickness 0.1524)
				)
			)
		)
		(property "Device Type" "TPAD28"
			(at -0.0127 -3.1877 0)
			(unlocked yes)
			(layer "F.Fab")
			(hide yes)
			(effects
				(font
					(size 1.016 1.016)
					(thickness 0.1524)
				)
			)
		)
		(duplicate_pad_numbers_are_jumpers no)
		(fp_poly
			(pts
				(arc
					(start 0.3556 0)
					(mid -0.3556 0)
					(end 0.3556 0)
				)
			)
			(stroke
				(width 0)
				(type default)
			)
			(fill no)
			(layer "F.CrtYd")
		)
		(fp_poly
			(pts
				(arc
					(start 0.6096 0)
					(mid -0.6096 0)
					(end 0.6096 0)
				)
			)
			(stroke
				(width 0)
				(type default)
			)
			(fill no)
			(layer "F.Fab")
		)
		(pad "1" smd circle
			(at 0 0)
			(size 0.7112 0.7112)
			(layers "F.Cu" "F.Mask" "F.Paste")
			(net "ICE0_TMS")
		)
	)
	(footprint ""
		(layer "F.Cu")
		(at 76.385928 -146.839432 90)
		(property "Reference" "R617"
			(at 0 0 90)
			(layer "F.SilkS")
			(hide yes)
			(effects
				(font
					(size 1.27 1.27)
				)
			)
		)
		(property "Value" "0R2J-2-GP"
			(at 0.064008 -3.993896 90)
			(unlocked yes)
			(layer "F.Fab")
			(hide yes)
			(effects
				(font
					(size 1.016 1.016)
					(thickness 0.1524)
				)
			)
		)
		(property "Device Type" "R402H16"
			(at 0.064008 -5.517896 90)
			(unlocked yes)
			(layer "F.Fab")
			(hide yes)
			(effects
				(font
					(size 1.016 1.016)
					(thickness 0.1524)
				)
			)
		)
		(duplicate_pad_numbers_are_jumpers no)
		(fp_line
			(start 0.508 -0.9398)
			(end -0.508 -0.9398)
			(stroke
				(width 0.1524)
				(type default)
			)
			(layer "F.SilkS")
		)
		(fp_line
			(start -0.508 -0.9398)
			(end -0.508 0.9398)
			(stroke
				(width 0.1524)
				(type default)
			)
			(layer "F.SilkS")
		)
		(fp_rect
			(start -0.508 0.9398)
			(end 0.508 -0.9398)
			(stroke
				(width 0)
				(type default)
			)
			(fill no)
			(layer "F.CrtYd")
		)
		(fp_rect
			(start -0.508 0.9398)
			(end 0.508 -0.9398)
			(stroke
				(width 0)
				(type default)
			)
			(fill no)
			(layer "F.Fab")
		)
		(pad "1" smd custom
			(at 0 -0.4445 90)
			(size 0.1397 0.1397)
			(layers "F.Cu" "F.Mask" "F.Paste")
			(net "I2C_DPB_SDA")
			(options
				(clearance outline)
				(anchor circle)
			)
			(primitives
				(gr_poly
					(pts
						(arc
							(start -0.1778 -0.2794)
							(mid -0.249642 -0.249642)
							(end -0.2794 -0.1778)
						)
						(arc
							(start -0.2794 0.1778)
							(mid -0.249642 0.249642)
							(end -0.1778 0.2794)
						)
						(arc
							(start 0.1778 0.2794)
							(mid 0.249642 0.249642)
							(end 0.2794 0.1778)
						)
						(arc
							(start 0.2794 -0.1778)
							(mid 0.249642 -0.249642)
							(end 0.1778 -0.2794)
						)
					)
					(width 0)
					(fill yes)
				)
			)
		)
		(pad "2" smd custom
			(at 0 0.4445 90)
			(size 0.1397 0.1397)
			(layers "F.Cu" "F.Mask" "F.Paste")
			(net "I2C_DPB_SDA_R")
			(options
				(clearance outline)
				(anchor circle)
			)
			(primitives
				(gr_poly
					(pts
						(arc
							(start -0.1778 -0.2794)
							(mid -0.249642 -0.249642)
							(end -0.2794 -0.1778)
						)
						(arc
							(start -0.2794 0.1778)
							(mid -0.249642 0.249642)
							(end -0.1778 0.2794)
						)
						(arc
							(start 0.1778 0.2794)
							(mid 0.249642 0.249642)
							(end 0.2794 0.1778)
						)
						(arc
							(start 0.2794 -0.1778)
							(mid 0.249642 -0.249642)
							(end 0.1778 -0.2794)
						)
					)
					(width 0)
					(fill yes)
				)
			)
		)
	)
	(footprint ""
		(layer "F.Cu")
		(at 192.772538 -49.977294)
		(property "Reference" "TP154"
			(at 0 0 0)
			(layer "F.SilkS")
			(hide yes)
			(effects
				(font
					(size 1.27 1.27)
				)
			)
		)
		(property "Value" "TPAD28-2-GP"
			(at -0.0127 -1.6637 0)
			(unlocked yes)
			(layer "F.Fab")
			(hide yes)
			(effects
				(font
					(size 1.016 1.016)
					(thickness 0.1524)
				)
			)
		)
		(property "Device Type" "TPAD28"
			(at -0.0127 -3.1877 0)
			(unlocked yes)
			(layer "F.Fab")
			(hide yes)
			(effects
				(font
					(size 1.016 1.016)
					(thickness 0.1524)
				)
			)
		)
		(duplicate_pad_numbers_are_jumpers no)
		(fp_poly
			(pts
				(arc
					(start 0.3556 0)
					(mid -0.3556 0)
					(end 0.3556 0)
				)
			)
			(stroke
				(width 0)
				(type default)
			)
			(fill no)
			(layer "F.CrtYd")
		)
		(fp_poly
			(pts
				(arc
					(start 0.6096 0)
					(mid -0.6096 0)
					(end 0.6096 0)
				)
			)
			(stroke
				(width 0)
				(type default)
			)
			(fill no)
			(layer "F.Fab")
		)
		(pad "1" smd circle
			(at 0 0)
			(size 0.7112 0.7112)
			(layers "F.Cu" "F.Mask" "F.Paste")
			(net "IOC_TRST_N")
		)
	)
	(footprint ""
		(layer "F.Cu")
		(at 51.5112 -129.5146)
		(property "Reference" "TP9"
			(at 0 0 0)
			(layer "F.SilkS")
			(hide yes)
			(effects
				(font
					(size 1.27 1.27)
				)
			)
		)
		(property "Value" "TPAD28-2-GP"
			(at -0.0127 -1.6637 0)
			(unlocked yes)
			(layer "F.Fab")
			(hide yes)
			(effects
				(font
					(size 1.016 1.016)
					(thickness 0.1524)
				)
			)
		)
		(property "Device Type" "TPAD28"
			(at -0.0127 -3.1877 0)
			(unlocked yes)
			(layer "F.Fab")
			(hide yes)
			(effects
				(font
					(size 1.016 1.016)
					(thickness 0.1524)
				)
			)
		)
		(duplicate_pad_numbers_are_jumpers no)
		(fp_poly
			(pts
				(arc
					(start 0.3556 0)
					(mid -0.3556 0)
					(end 0.3556 0)
				)
			)
			(stroke
				(width 0)
				(type default)
			)
			(fill no)
			(layer "F.CrtYd")
		)
		(fp_poly
			(pts
				(arc
					(start 0.6096 0)
					(mid -0.6096 0)
					(end 0.6096 0)
				)
			)
			(stroke
				(width 0)
				(type default)
			)
			(fill no)
			(layer "F.Fab")
		)
		(pad "1" smd circle
			(at 0 0)
			(size 0.7112 0.7112)
			(layers "F.Cu" "F.Mask" "F.Paste")
			(net "TP_BMC0_LPC_LAD0")
		)
	)
	(footprint ""
		(layer "F.Cu")
		(at 170.9039 -119.553736 90)
		(property "Reference" "R525"
			(at 0 0 90)
			(layer "F.SilkS")
			(hide yes)
			(effects
				(font
					(size 1.27 1.27)
				)
			)
		)
		(property "Value" "10KR2F-2-GP"
			(at 0.064008 -3.993896 90)
			(unlocked yes)
			(layer "F.Fab")
			(hide yes)
			(effects
				(font
					(size 1.016 1.016)
					(thickness 0.1524)
				)
			)
		)
		(property "Device Type" "R402H16"
			(at 0.064008 -5.517896 90)
			(unlocked yes)
			(layer "F.Fab")
			(hide yes)
			(effects
				(font
					(size 1.016 1.016)
					(thickness 0.1524)
				)
			)
		)
		(duplicate_pad_numbers_are_jumpers no)
		(fp_line
			(start 0.508 -0.9398)
			(end -0.508 -0.9398)
			(stroke
				(width 0.1524)
				(type default)
			)
			(layer "F.SilkS")
		)
		(fp_line
			(start -0.508 -0.9398)
			(end -0.508 0.9398)
			(stroke
				(width 0.1524)
				(type default)
			)
			(layer "F.SilkS")
		)
		(fp_rect
			(start -0.508 0.9398)
			(end 0.508 -0.9398)
			(stroke
				(width 0)
				(type default)
			)
			(fill no)
			(layer "F.CrtYd")
		)
		(fp_rect
			(start -0.508 0.9398)
			(end 0.508 -0.9398)
			(stroke
				(width 0)
				(type default)
			)
			(fill no)
			(layer "F.Fab")
		)
		(pad "1" smd custom
			(at 0 -0.4445 90)
			(size 0.1397 0.1397)
			(layers "F.Cu" "F.Mask" "F.Paste")
			(net "P12V_STBY")
			(options
				(clearance outline)
				(anchor circle)
			)
			(primitives
				(gr_poly
					(pts
						(arc
							(start -0.1778 -0.2794)
							(mid -0.249642 -0.249642)
							(end -0.2794 -0.1778)
						)
						(arc
							(start -0.2794 0.1778)
							(mid -0.249642 0.249642)
							(end -0.1778 0.2794)
						)
						(arc
							(start 0.1778 0.2794)
							(mid 0.249642 0.249642)
							(end 0.2794 0.1778)
						)
						(arc
							(start 0.2794 -0.1778)
							(mid 0.249642 -0.249642)
							(end 0.1778 -0.2794)
						)
					)
					(width 0)
					(fill yes)
				)
			)
		)
		(pad "2" smd custom
			(at 0 0.4445 90)
			(size 0.1397 0.1397)
			(layers "F.Cu" "F.Mask" "F.Paste")
			(net "PQ4_D")
			(options
				(clearance outline)
				(anchor circle)
			)
			(primitives
				(gr_poly
					(pts
						(arc
							(start -0.1778 -0.2794)
							(mid -0.249642 -0.249642)
							(end -0.2794 -0.1778)
						)
						(arc
							(start -0.2794 0.1778)
							(mid -0.249642 0.249642)
							(end -0.1778 0.2794)
						)
						(arc
							(start 0.1778 0.2794)
							(mid 0.249642 0.249642)
							(end 0.2794 0.1778)
						)
						(arc
							(start 0.2794 -0.1778)
							(mid 0.249642 -0.249642)
							(end 0.1778 -0.2794)
						)
					)
					(width 0)
					(fill yes)
				)
			)
		)
	)
	(footprint ""
		(layer "F.Cu")
		(at 12.94384 -13.41882 180)
		(property "Reference" "C529"
			(at 0 0 180)
			(layer "F.SilkS")
			(hide yes)
			(effects
				(font
					(size 1.27 1.27)
				)
			)
		)
		(property "Value" "SC1000P2KV6KX-GP-U"
			(at 0.0508 -3.5052 180)
			(unlocked yes)
			(layer "F.Fab")
			(hide yes)
			(effects
				(font
					(size 1.016 1.016)
					(thickness 0.1524)
				)
			)
		)
		(property "Device Type" "C1206H58"
			(at 0.0508 -5.0292 180)
			(unlocked yes)
			(layer "F.Fab")
			(hide yes)
			(effects
				(font
					(size 1.016 1.016)
					(thickness 0.1524)
				)
			)
		)
		(duplicate_pad_numbers_are_jumpers no)
		(fp_line
			(start 1.016 2.2352)
			(end -1.016 2.2352)
			(stroke
				(width 0.1524)
				(type default)
			)
			(layer "F.SilkS")
		)
		(fp_line
			(start 1.016 0.8382)
			(end 1.016 2.2352)
			(stroke
				(width 0.1524)
				(type default)
			)
			(layer "F.SilkS")
		)
		(fp_line
			(start 1.016 -2.2352)
			(end 1.016 -0.8382)
			(stroke
				(width 0.1524)
				(type default)
			)
			(layer "F.SilkS")
		)
		(fp_line
			(start 1.016 -2.2352)
			(end -1.016 -2.2352)
			(stroke
				(width 0.1524)
				(type default)
			)
			(layer "F.SilkS")
		)
		(fp_line
			(start -1.016 2.2352)
			(end -1.016 0.8128)
			(stroke
				(width 0.1524)
				(type default)
			)
			(layer "F.SilkS")
		)
		(fp_line
			(start -1.016 -2.2352)
			(end -1.016 -0.8382)
			(stroke
				(width 0.1524)
				(type default)
			)
			(layer "F.SilkS")
		)
		(fp_rect
			(start -1.0922 2.3114)
			(end 1.0922 -2.3114)
			(stroke
				(width 0)
				(type default)
			)
			(fill no)
			(layer "F.CrtYd")
		)
		(fp_poly
			(pts
				(xy -1.0922 -2.3114) (xy 1.0922 -2.3114) (xy 1.0922 2.3114) (xy -1.0922 2.3114)
			)
			(stroke
				(width 0)
				(type default)
			)
			(fill no)
			(layer "F.Fab")
		)
		(pad "1" smd rect
			(at 0 -1.397 180)
			(size 1.651 1.27)
			(layers "F.Cu" "F.Mask" "F.Paste")
			(net "RST_BTN_GND")
		)
		(pad "2" smd rect
			(at 0 1.397 180)
			(size 1.651 1.27)
			(layers "F.Cu" "F.Mask" "F.Paste")
			(net "GND")
		)
	)
	(footprint ""
		(layer "F.Cu")
		(at 179.999894 -14.699996)
		(property "Reference" "EXT1"
			(at 0 0 0)
			(layer "F.SilkS")
			(hide yes)
			(effects
				(font
					(size 1.27 1.27)
				)
			)
		)
		(property "Value" "MINI-SAS-36P-7-GP"
			(at -9.3345 2.159 0)
			(unlocked yes)
			(layer "F.Fab")
			(hide yes)
			(effects
				(font
					(size 1.016 1.016)
					(thickness 0.1524)
				)
			)
		)
		(property "Device Type" "PREFIT-42P-131384H522"
			(at -9.3345 0.635 0)
			(unlocked yes)
			(layer "F.Fab")
			(hide yes)
			(effects
				(font
					(size 1.016 1.016)
					(thickness 0.1524)
				)
			)
		)
		(duplicate_pad_numbers_are_jumpers no)
		(fp_line
			(start -6.8072 9.3726)
			(end -6.2103 9.3726)
			(stroke
				(width 0.1524)
				(type default)
			)
			(layer "F.SilkS")
		)
		(fp_line
			(start -6.8072 20.6248)
			(end -6.8072 9.3726)
			(stroke
				(width 0.1524)
				(type default)
			)
			(layer "F.SilkS")
		)
		(fp_line
			(start -6.2103 -18.288)
			(end 6.2103 -18.288)
			(stroke
				(width 0.1524)
				(type default)
			)
			(layer "F.SilkS")
		)
		(fp_line
			(start -6.2103 9.3726)
			(end -6.2103 -18.288)
			(stroke
				(width 0.1524)
				(type default)
			)
			(layer "F.SilkS")
		)
		(fp_line
			(start 6.2103 -18.288)
			(end 6.2103 9.3726)
			(stroke
				(width 0.1524)
				(type default)
			)
			(layer "F.SilkS")
		)
		(fp_line
			(start 6.2103 9.3726)
			(end 6.8072 9.3726)
			(stroke
				(width 0.1524)
				(type default)
			)
			(layer "F.SilkS")
		)
		(fp_line
			(start 6.8072 9.3726)
			(end 6.8072 20.6248)
			(stroke
				(width 0.1524)
				(type default)
			)
			(layer "F.SilkS")
		)
		(fp_line
			(start 6.8072 20.6248)
			(end -6.8072 20.6248)
			(stroke
				(width 0.1524)
				(type default)
			)
			(layer "F.SilkS")
		)
		(fp_poly
			(pts
				(xy -6.8072 20.6248) (xy -6.8072 10.5156) (xy 6.8072 10.5156) (xy 6.8072 20.6248)
			)
			(stroke
				(width 0)
				(type default)
			)
			(fill yes)
			(layer "F.SilkS")
		)
		(fp_poly
			(pts
				(arc
					(start -3.7211 9.970008)
					(mid -4.0767 10.325608)
					(end -4.4323 9.970008)
				)
				(arc
					(start -4.4323 9.284208)
					(mid -4.0767 8.928608)
					(end -3.7211 9.284208)
				)
			)
			(stroke
				(width 0)
				(type default)
			)
			(fill yes)
			(layer "F.SilkS")
		)
		(fp_poly
			(pts
				(arc
					(start 4.4069 9.970008)
					(mid 4.0513 10.325608)
					(end 3.6957 9.970008)
				)
				(arc
					(start 3.6957 9.284208)
					(mid 4.0513 8.928608)
					(end 4.4069 9.284208)
				)
			)
			(stroke
				(width 0)
				(type default)
			)
			(fill yes)
			(layer "F.SilkS")
		)
		(fp_poly
			(pts
				(arc
					(start -3.9116 -2.8829)
					(mid -4.2926 -2.5019)
					(end -4.6736 -2.8829)
				)
				(arc
					(start -4.6736 -4.4069)
					(mid -4.2926 -4.7879)
					(end -3.9116 -4.4069)
				)
			)
			(stroke
				(width 0)
				(type default)
			)
			(fill yes)
			(layer "F.SilkS")
		)
		(fp_poly
			(pts
				(arc
					(start -0.0381 -17.145)
					(mid -0.4191 -17.526)
					(end -0.0381 -17.907)
				)
				(arc
					(start 1.4859 -17.907)
					(mid 1.8669 -17.526)
					(end 1.4859 -17.145)
				)
			)
			(stroke
				(width 0)
				(type default)
			)
			(fill yes)
			(layer "F.SilkS")
		)
		(fp_poly
			(pts
				(arc
					(start 4.7244 -2.8829)
					(mid 4.3434 -2.5019)
					(end 3.9624 -2.8829)
				)
				(arc
					(start 3.9624 -4.4069)
					(mid 4.3434 -4.7879)
					(end 4.7244 -4.4069)
				)
			)
			(stroke
				(width 0)
				(type default)
			)
			(fill yes)
			(layer "F.SilkS")
		)
		(fp_poly
			(pts
				(arc
					(start -4.6101 -14.2875)
					(mid -5.1181 -13.7795)
					(end -5.6261 -14.2875)
				)
				(arc
					(start -5.6261 -15.8115)
					(mid -5.1181 -16.3195)
					(end -4.6101 -15.8115)
				)
			)
			(stroke
				(width 0)
				(type default)
			)
			(fill yes)
			(layer "F.SilkS")
		)
		(fp_poly
			(pts
				(arc
					(start -4.6101 -10.414)
					(mid -5.1181 -9.906)
					(end -5.6261 -10.414)
				)
				(arc
					(start -5.6261 -11.938)
					(mid -5.1181 -12.446)
					(end -4.6101 -11.938)
				)
			)
			(stroke
				(width 0)
				(type default)
			)
			(fill yes)
			(layer "F.SilkS")
		)
		(fp_poly
			(pts
				(arc
					(start -4.5847 -6.5024)
					(mid -5.0927 -5.9944)
					(end -5.6007 -6.5024)
				)
				(arc
					(start -5.6007 -8.0264)
					(mid -5.0927 -8.5344)
					(end -4.5847 -8.0264)
				)
			)
			(stroke
				(width 0)
				(type default)
			)
			(fill yes)
			(layer "F.SilkS")
		)
		(fp_rect
			(start -10.9601 15.0622)
			(end 10.9601 -22.9743)
			(stroke
				(width 0)
				(type default)
			)
			(fill no)
			(layer "B.CrtYd")
		)
		(fp_poly
			(pts
				(xy -6.5532 20.3708) (xy -6.5532 9.6266) (xy -5.9563 9.6266) (xy -5.9563 -18.034) (xy 5.9563 -18.034)
				(xy 5.9563 9.6266) (xy 6.5532 9.6266) (xy 6.5532 20.3708)
			)
			(stroke
				(width 0)
				(type default)
			)
			(fill no)
			(layer "F.CrtYd")
		)
		(fp_poly
			(pts
				(xy -11.557 25.3746) (xy -11.557 4.6228) (xy -10.9601 4.6228) (xy -10.9601 -23.0378) (xy 10.9601 -23.0378)
				(xy 10.9601 2.1717) (xy 6.464554 2.1717) (xy 6.464554 -18.542254) (xy -6.464554 -18.542254) (xy -6.464554 9.118346)
				(xy -7.061454 9.118346) (xy -7.061454 20.879054) (xy 7.061454 20.879054) (xy 7.061454 9.118346)
				(xy 6.464554 9.118346) (xy 6.464554 2.1844) (xy 10.9601 2.1844) (xy 10.9601 4.6228) (xy 11.557 4.6228)
				(xy 11.557 25.3746)
			)
			(stroke
				(width 0)
				(type default)
			)
			(fill no)
			(layer "F.CrtYd")
		)
		(fp_poly
			(pts
				(xy -7.0612 20.8788) (xy -7.0612 9.1186) (xy -6.4643 9.1186) (xy -6.4643 -18.542) (xy 6.4643 -18.542)
				(xy 6.4643 -0.00635) (xy 5.9563 -0.00635) (xy 5.9563 -18.034) (xy -5.9563 -18.034) (xy -5.9563 9.6266)
				(xy -6.5532 9.6266) (xy -6.5532 20.3708) (xy 6.5532 20.3708) (xy 6.5532 9.6266) (xy 5.9563 9.6266)
				(xy 5.9563 0.00635) (xy 6.4643 0.00635) (xy 6.4643 9.1186) (xy 7.0612 9.1186) (xy 7.0612 20.8788)
			)
			(stroke
				(width 0)
				(type default)
			)
			(fill no)
			(layer "F.CrtYd")
		)
		(fp_rect
			(start -15.9639 20.066)
			(end 15.9639 -27.9781)
			(stroke
				(width 0)
				(type default)
			)
			(fill no)
			(layer "B.Fab")
		)
		(fp_rect
			(start -10.9601 15.0622)
			(end 10.9601 -22.9743)
			(stroke
				(width 0)
				(type default)
			)
			(fill no)
			(layer "B.Fab")
		)
		(fp_poly
			(pts
				(xy -16.5608 30.3784) (xy -16.5608 -0.381) (xy -15.9639 -0.381) (xy -15.9639 -28.0416) (xy 15.9639 -28.0416)
				(xy 15.9639 -0.381) (xy 16.5608 -0.381) (xy 16.5608 30.3784)
			)
			(stroke
				(width 0)
				(type default)
			)
			(fill no)
			(layer "F.Fab")
		)
		(fp_poly
			(pts
				(xy -11.557 25.3746) (xy -11.557 4.6228) (xy -10.9601 4.6228) (xy -10.9601 -23.0378) (xy 10.9601 -23.0378)
				(xy 10.9601 4.6228) (xy 11.557 4.6228) (xy 11.557 25.3746)
			)
			(stroke
				(width 0)
				(type default)
			)
			(fill no)
			(layer "F.Fab")
		)
		(fp_poly
			(pts
				(xy -7.0612 20.8788) (xy -7.0612 9.1186) (xy -6.4643 9.1186) (xy -6.4643 -18.542) (xy 6.4643 -18.542)
				(xy 6.4643 9.1186) (xy 7.0612 9.1186) (xy 7.0612 20.8788)
			)
			(stroke
				(width 0)
				(type default)
			)
			(fill no)
			(layer "F.Fab")
		)
		(fp_text user "Press Fit"
			(at -5.055108 12.29614 0)
			(unlocked yes)
			(layer "F.SilkS")
			(effects
				(font
					(size 1.016 1.016)
					(thickness 0.1524)
				)
				(justify left)
			)
		)
		(fp_text user "Can not place BGA,CSP,Wave Solder Component"
			(at -24.838914 17.72412 0)
			(unlocked yes)
			(layer "B.Fab")
			(effects
				(font
					(size 1.016 1.016)
					(thickness 0.1524)
				)
				(justify left)
			)
		)
		(fp_text user "Can not place BGA,CSP,Wave Solder Component"
			(at -25.305766 27.745182 0)
			(unlocked yes)
			(layer "F.Fab")
			(effects
				(font
					(size 1.016 1.016)
					(thickness 0.1524)
				)
				(justify left)
			)
		)
		(fp_text user "High Limit 2mm"
			(at -7.86384 23.09876 0)
			(unlocked yes)
			(layer "F.Fab")
			(effects
				(font
					(size 1.016 1.016)
					(thickness 0.1524)
				)
				(justify left)
			)
		)
		(pad "A1" thru_hole circle
			(at -2.999994 -4.400042)
			(size 0.7366 0.7366)
			(drill 0.369824)
			(layers "*.Cu" "*.Mask")
			(remove_unused_layers no)
			(net "ZDEF_EXTA_TP_A1")
			(clearance 0.1778)
			(thermal_gap 0.1778)
		)
		(pad "A2" thru_hole circle
			(at -2.249932 -2.999994)
			(size 0.7366 0.7366)
			(drill 0.369824)
			(layers "*.Cu" "*.Mask")
			(remove_unused_layers no)
			(net "ZDEF_EXTA_TP_A2")
			(clearance 0.1778)
			(thermal_gap 0.1778)
		)
		(pad "A3" thru_hole circle
			(at -1.500124 -3.700018)
			(size 0.7366 0.7366)
			(drill 0.369824)
			(layers "*.Cu" "*.Mask")
			(remove_unused_layers no)
			(net "GND")
			(clearance 0.1778)
			(thermal_gap 0.1778)
		)
		(pad "A4" thru_hole circle
			(at -0.749808 -4.400042)
			(size 0.7366 0.7366)
			(drill 0.369824)
			(layers "*.Cu" "*.Mask")
			(remove_unused_layers no)
			(net "PHY_CON_A_TO_IOC_1_DP_C")
			(clearance 0.1778)
			(thermal_gap 0.1778)
		)
		(pad "A5" thru_hole circle
			(at 0 -2.999994)
			(size 0.7366 0.7366)
			(drill 0.369824)
			(layers "*.Cu" "*.Mask")
			(remove_unused_layers no)
			(net "PHY_CON_A_TO_IOC_1_DN_C")
			(clearance 0.1778)
			(thermal_gap 0.1778)
		)
		(pad "A6" thru_hole circle
			(at 0.749808 -3.700018)
			(size 0.7366 0.7366)
			(drill 0.369824)
			(layers "*.Cu" "*.Mask")
			(remove_unused_layers no)
			(net "GND")
			(clearance 0.1778)
			(thermal_gap 0.1778)
		)
		(pad "A7" thru_hole circle
			(at 1.500124 -4.400042)
			(size 0.7366 0.7366)
			(drill 0.369824)
			(layers "*.Cu" "*.Mask")
			(remove_unused_layers no)
			(net "PHY_CON_A_TO_IOC_0_DP_C")
			(clearance 0.1778)
			(thermal_gap 0.1778)
		)
		(pad "A8" thru_hole circle
			(at 2.250186 -2.999994)
			(size 0.7366 0.7366)
			(drill 0.369824)
			(layers "*.Cu" "*.Mask")
			(remove_unused_layers no)
			(net "PHY_CON_A_TO_IOC_0_DN_C")
			(clearance 0.1778)
			(thermal_gap 0.1778)
		)
		(pad "A9" thru_hole circle
			(at 2.999994 -3.700018)
			(size 0.7366 0.7366)
			(drill 0.369824)
			(layers "*.Cu" "*.Mask")
			(remove_unused_layers no)
			(net "GND")
			(clearance 0.1778)
			(thermal_gap 0.1778)
		)
		(pad "B1" thru_hole circle
			(at -2.999994 -8.199882)
			(size 0.7366 0.7366)
			(drill 0.369824)
			(layers "*.Cu" "*.Mask")
			(remove_unused_layers no)
			(net "ZDEF_EXTA_TP_B1")
			(clearance 0.1778)
			(thermal_gap 0.1778)
		)
		(pad "B2" thru_hole circle
			(at -2.249932 -6.800088)
			(size 0.7366 0.7366)
			(drill 0.369824)
			(layers "*.Cu" "*.Mask")
			(remove_unused_layers no)
			(net "ZDEF_EXTA_TP_B2")
			(clearance 0.1778)
			(thermal_gap 0.1778)
		)
		(pad "B3" thru_hole circle
			(at -1.500124 -7.500112)
			(size 0.7366 0.7366)
			(drill 0.369824)
			(layers "*.Cu" "*.Mask")
			(remove_unused_layers no)
			(net "GND")
			(clearance 0.1778)
			(thermal_gap 0.1778)
		)
		(pad "B4" thru_hole circle
			(at -0.749808 -8.199882)
			(size 0.7366 0.7366)
			(drill 0.369824)
			(layers "*.Cu" "*.Mask")
			(remove_unused_layers no)
			(net "PHY_CON_A_TO_IOC_3_DP_C")
			(clearance 0.1778)
			(thermal_gap 0.1778)
		)
		(pad "B5" thru_hole circle
			(at 0 -6.800088)
			(size 0.7366 0.7366)
			(drill 0.369824)
			(layers "*.Cu" "*.Mask")
			(remove_unused_layers no)
			(net "PHY_CON_A_TO_IOC_3_DN_C")
			(clearance 0.1778)
			(thermal_gap 0.1778)
		)
		(pad "B6" thru_hole circle
			(at 0.749808 -7.500112)
			(size 0.7366 0.7366)
			(drill 0.369824)
			(layers "*.Cu" "*.Mask")
			(remove_unused_layers no)
			(net "GND")
			(clearance 0.1778)
			(thermal_gap 0.1778)
		)
		(pad "B7" thru_hole circle
			(at 1.500124 -8.199882)
			(size 0.7366 0.7366)
			(drill 0.369824)
			(layers "*.Cu" "*.Mask")
			(remove_unused_layers no)
			(net "PHY_CON_A_TO_IOC_2_DP_C")
			(clearance 0.1778)
			(thermal_gap 0.1778)
		)
		(pad "B8" thru_hole circle
			(at 2.250186 -6.800088)
			(size 0.7366 0.7366)
			(drill 0.369824)
			(layers "*.Cu" "*.Mask")
			(remove_unused_layers no)
			(net "PHY_CON_A_TO_IOC_2_DN_C")
			(clearance 0.1778)
			(thermal_gap 0.1778)
		)
		(pad "B9" thru_hole circle
			(at 2.999994 -7.500112)
			(size 0.7366 0.7366)
			(drill 0.369824)
			(layers "*.Cu" "*.Mask")
			(remove_unused_layers no)
			(net "GND")
			(clearance 0.1778)
			(thermal_gap 0.1778)
		)
		(pad "C1" thru_hole circle
			(at -2.999994 -11.999976)
			(size 0.7366 0.7366)
			(drill 0.369824)
			(layers "*.Cu" "*.Mask")
			(remove_unused_layers no)
			(net "ZDEF_EXTA_TP_C1")
			(clearance 0.1778)
			(thermal_gap 0.1778)
		)
		(pad "C2" thru_hole circle
			(at -2.249932 -10.599928)
			(size 0.7366 0.7366)
			(drill 0.369824)
			(layers "*.Cu" "*.Mask")
			(remove_unused_layers no)
			(net "ZDEF_EXTA_TP_C2")
			(clearance 0.1778)
			(thermal_gap 0.1778)
		)
		(pad "C3" thru_hole circle
			(at -1.500124 -11.299952)
			(size 0.7366 0.7366)
			(drill 0.369824)
			(layers "*.Cu" "*.Mask")
			(remove_unused_layers no)
			(net "GND")
			(clearance 0.1778)
			(thermal_gap 0.1778)
		)
		(pad "C4" thru_hole circle
			(at -0.749808 -11.999976)
			(size 0.7366 0.7366)
			(drill 0.369824)
			(layers "*.Cu" "*.Mask")
			(remove_unused_layers no)
			(net "PHY_IOC_TO_CON_A_1_DP")
			(clearance 0.1778)
			(thermal_gap 0.1778)
		)
		(pad "C5" thru_hole circle
			(at 0 -10.599928)
			(size 0.7366 0.7366)
			(drill 0.369824)
			(layers "*.Cu" "*.Mask")
			(remove_unused_layers no)
			(net "PHY_IOC_TO_CON_A_1_DN")
			(clearance 0.1778)
			(thermal_gap 0.1778)
		)
		(pad "C6" thru_hole circle
			(at 0.749808 -11.299952)
			(size 0.7366 0.7366)
			(drill 0.369824)
			(layers "*.Cu" "*.Mask")
			(remove_unused_layers no)
			(net "GND")
			(clearance 0.1778)
			(thermal_gap 0.1778)
		)
		(pad "C7" thru_hole circle
			(at 1.500124 -11.999976)
			(size 0.7366 0.7366)
			(drill 0.369824)
			(layers "*.Cu" "*.Mask")
			(remove_unused_layers no)
			(net "PHY_IOC_TO_CON_A_0_DP")
			(clearance 0.1778)
			(thermal_gap 0.1778)
		)
		(pad "C8" thru_hole circle
			(at 2.250186 -10.599928)
			(size 0.7366 0.7366)
			(drill 0.369824)
			(layers "*.Cu" "*.Mask")
			(remove_unused_layers no)
			(net "PHY_IOC_TO_CON_A_0_DN")
			(clearance 0.1778)
			(thermal_gap 0.1778)
		)
		(pad "C9" thru_hole circle
			(at 2.999994 -11.299952)
			(size 0.7366 0.7366)
			(drill 0.369824)
			(layers "*.Cu" "*.Mask")
			(remove_unused_layers no)
			(net "GND")
			(clearance 0.1778)
			(thermal_gap 0.1778)
		)
		(pad "D1" thru_hole circle
			(at -2.999994 -15.80007)
			(size 0.7366 0.7366)
			(drill 0.369824)
			(layers "*.Cu" "*.Mask")
			(remove_unused_layers no)
			(net "ZDEF_EXTA_TP_D1")
			(clearance 0.1778)
			(thermal_gap 0.1778)
		)
		(pad "D2" thru_hole circle
			(at -2.249932 -14.400022)
			(size 0.7366 0.7366)
			(drill 0.369824)
			(layers "*.Cu" "*.Mask")
			(remove_unused_layers no)
			(net "ZDEF_EXTA_TP_D2")
			(clearance 0.1778)
			(thermal_gap 0.1778)
		)
		(pad "D3" thru_hole circle
			(at -1.500124 -15.100046)
			(size 0.7366 0.7366)
			(drill 0.369824)
			(layers "*.Cu" "*.Mask")
			(remove_unused_layers no)
			(net "GND")
			(clearance 0.1778)
			(thermal_gap 0.1778)
		)
		(pad "D4" thru_hole circle
			(at -0.749808 -15.80007)
			(size 0.7366 0.7366)
			(drill 0.369824)
			(layers "*.Cu" "*.Mask")
			(remove_unused_layers no)
			(net "PHY_IOC_TO_CON_A_3_DP")
			(clearance 0.1778)
			(thermal_gap 0.1778)
		)
		(pad "D5" thru_hole circle
			(at 0 -14.400022)
			(size 0.7366 0.7366)
			(drill 0.369824)
			(layers "*.Cu" "*.Mask")
			(remove_unused_layers no)
			(net "PHY_IOC_TO_CON_A_3_DN")
			(clearance 0.1778)
			(thermal_gap 0.1778)
		)
		(pad "D6" thru_hole circle
			(at 0.749808 -15.100046)
			(size 0.7366 0.7366)
			(drill 0.369824)
			(layers "*.Cu" "*.Mask")
			(remove_unused_layers no)
			(net "GND")
			(clearance 0.1778)
			(thermal_gap 0.1778)
		)
		(pad "D7" thru_hole circle
			(at 1.500124 -15.80007)
			(size 0.7366 0.7366)
			(drill 0.369824)
			(layers "*.Cu" "*.Mask")
			(remove_unused_layers no)
			(net "PHY_IOC_TO_CON_A_2_DP")
			(clearance 0.1778)
			(thermal_gap 0.1778)
		)
		(pad "D8" thru_hole circle
			(at 2.250186 -14.400022)
			(size 0.7366 0.7366)
			(drill 0.369824)
			(layers "*.Cu" "*.Mask")
			(remove_unused_layers no)
			(net "PHY_IOC_TO_CON_A_2_DN")
			(clearance 0.1778)
			(thermal_gap 0.1778)
		)
		(pad "D9" thru_hole circle
			(at 2.999994 -15.100046)
			(size 0.7366 0.7366)
			(drill 0.369824)
			(layers "*.Cu" "*.Mask")
			(remove_unused_layers no)
			(net "GND")
			(clearance 0.1778)
			(thermal_gap 0.1778)
		)
		(pad "G1" thru_hole circle
			(at -5.500116 9.61009)
			(size 0.9144 0.9144)
			(drill 0.569976)
			(layers "*.Cu" "*.Mask")
			(remove_unused_layers no)
			(net "EXT1_CONN_GND")
			(clearance 0.1905)
			(thermal_gap 0.1905)
		)
		(pad "G2" thru_hole circle
			(at 5.500116 9.61009)
			(size 0.9144 0.9144)
			(drill 0.569976)
			(layers "*.Cu" "*.Mask")
			(remove_unused_layers no)
			(net "EXT1_CONN_GND")
			(clearance 0.1905)
			(thermal_gap 0.1905)
		)
		(pad "G3" thru_hole circle
			(at -5.500116 -3.700018)
			(size 0.9144 0.9144)
			(drill 0.569976)
			(layers "*.Cu" "*.Mask")
			(remove_unused_layers no)
			(net "EXT1_CONN_GND")
			(clearance 0.1905)
			(thermal_gap 0.1905)
		)
		(pad "G4" thru_hole circle
			(at 5.500116 -3.700018)
			(size 0.9144 0.9144)
			(drill 0.569976)
			(layers "*.Cu" "*.Mask")
			(remove_unused_layers no)
			(net "EXT1_CONN_GND")
			(clearance 0.1905)
			(thermal_gap 0.1905)
		)
		(pad "G5" thru_hole circle
			(at -1.500124 -17.509998)
			(size 0.9144 0.9144)
			(drill 0.569976)
			(layers "*.Cu" "*.Mask")
			(remove_unused_layers no)
			(net "EXT1_CONN_GND")
			(clearance 0.1905)
			(thermal_gap 0.1905)
		)
		(pad "G6" thru_hole circle
			(at 2.999994 -17.509998)
			(size 0.9144 0.9144)
			(drill 0.569976)
			(layers "*.Cu" "*.Mask")
			(remove_unused_layers no)
			(net "EXT1_CONN_GND")
			(clearance 0.1905)
			(thermal_gap 0.1905)
		)
		(pad "G7" thru_hole circle
			(at 0 0)
			(size 3.81 3.81)
			(drill 2.2098)
			(layers "*.Cu" "*.Mask")
			(remove_unused_layers no)
			(net "EXT1_CONN_GND")
			(clearance -0.2921)
			(thermal_gap 0.3048)
			(padstack
				(mode front_inner_back)
				(layer "Inner"
					(shape circle)
					(size 2.6162 2.6162)
					(clearance 0.3048)
				)
				(layer "B.Cu"
					(shape circle)
					(size 3.81 3.81)
					(clearance -0.2921)
				)
			)
		)
		(zone
			(layer "F.Cu")
			(hatch none 0.5)
			(connect_pads
				(clearance 0)
			)
			(min_thickness 0.25)
			(keepout
				(tracks not_allowed)
				(vias allowed)
				(pads allowed)
				(copperpour not_allowed)
				(footprints allowed)
			)
			(placement
				(enabled no)
				(sheetname "")
			)
			(fill
				(thermal_gap 0.5)
				(thermal_bridge_width 0.5)
				(island_removal_mode 0)
			)
			(polygon
				(pts
					(xy 174.199804 -7.260082) (xy 174.199804 -5.96011) (xy 174.800006 -5.96011) (xy 174.800006 -7.260082)
				)
			)
		)
		(zone
			(layer "F.Cu")
			(hatch none 0.5)
			(connect_pads
				(clearance 0)
			)
			(min_thickness 0.25)
			(keepout
				(tracks allowed)
				(vias not_allowed)
				(pads allowed)
				(copperpour not_allowed)
				(footprints allowed)
			)
			(placement
				(enabled no)
				(sheetname "")
			)
			(fill
				(thermal_gap 0.5)
				(thermal_bridge_width 0.5)
				(island_removal_mode 0)
			)
			(polygon
				(pts
					(xy 174.199804 -5.96011) (xy 174.800006 -5.96011) (xy 174.800006 -7.260082) (xy 174.199804 -7.260082)
				)
			)
		)
		(zone
			(layer "F.Cu")
			(hatch none 0.5)
			(connect_pads
				(clearance 0)
			)
			(min_thickness 0.25)
			(keepout
				(tracks not_allowed)
				(vias allowed)
				(pads allowed)
				(copperpour not_allowed)
				(footprints allowed)
			)
			(placement
				(enabled no)
				(sheetname "")
			)
			(fill
				(thermal_gap 0.5)
				(thermal_bridge_width 0.5)
				(island_removal_mode 0)
			)
			(polygon
				(pts
					(xy 185.199782 -7.260082) (xy 185.199782 -5.96011) (xy 185.799984 -5.96011) (xy 185.799984 -7.260082)
				)
			)
		)
		(zone
			(layer "F.Cu")
			(hatch none 0.5)
			(connect_pads
				(clearance 0)
			)
			(min_thickness 0.25)
			(keepout
				(tracks allowed)
				(vias not_allowed)
				(pads allowed)
				(copperpour not_allowed)
				(footprints allowed)
			)
			(placement
				(enabled no)
				(sheetname "")
			)
			(fill
				(thermal_gap 0.5)
				(thermal_bridge_width 0.5)
				(island_removal_mode 0)
			)
			(polygon
				(pts
					(xy 185.199782 -5.96011) (xy 185.799984 -5.96011) (xy 185.799984 -7.260082) (xy 185.199782 -7.260082)
				)
			)
		)
	)
	(footprint ""
		(layer "F.Cu")
		(at 85.344 -150.368 90)
		(property "Reference" "C44"
			(at 0 0 90)
			(layer "F.SilkS")
			(hide yes)
			(effects
				(font
					(size 1.27 1.27)
				)
			)
		)
		(property "Value" "SCD1U16V2KX-3GP"
			(at 1.1811 -2.7051 90)
			(unlocked yes)
			(layer "F.Fab")
			(hide yes)
			(effects
				(font
					(size 1.016 1.016)
					(thickness 0.1524)
				)
			)
		)
		(property "Device Type" "C402H22"
			(at 1.1811 -4.2291 90)
			(unlocked yes)
			(layer "F.Fab")
			(hide yes)
			(effects
				(font
					(size 1.016 1.016)
					(thickness 0.1524)
				)
			)
		)
		(duplicate_pad_numbers_are_jumpers no)
		(fp_rect
			(start -0.4318 0.9525)
			(end 0.4318 -0.9525)
			(stroke
				(width 0)
				(type default)
			)
			(fill no)
			(layer "F.CrtYd")
		)
		(fp_rect
			(start -0.4318 0.9525)
			(end 0.4318 -0.9525)
			(stroke
				(width 0)
				(type default)
			)
			(fill no)
			(layer "F.Fab")
		)
		(pad "1" smd custom
			(at 0 -0.4445 90)
			(size 0.1524 0.1524)
			(layers "F.Cu" "F.Mask" "F.Paste")
			(net "P3V3_STBY")
			(options
				(clearance outline)
				(anchor circle)
			)
			(primitives
				(gr_poly
					(pts
						(arc
							(start 0.3048 -0.2032)
							(mid 0.275042 -0.275042)
							(end 0.2032 -0.3048)
						)
						(arc
							(start -0.2032 -0.3048)
							(mid -0.275042 -0.275042)
							(end -0.3048 -0.2032)
						)
						(arc
							(start -0.3048 0.2032)
							(mid -0.275042 0.275042)
							(end -0.2032 0.3048)
						)
						(arc
							(start 0.2032 0.3048)
							(mid 0.275042 0.275042)
							(end 0.3048 0.2032)
						)
					)
					(width 0)
					(fill yes)
				)
			)
		)
		(pad "2" smd custom
			(at 0 0.4445 90)
			(size 0.1524 0.1524)
			(layers "F.Cu" "F.Mask" "F.Paste")
			(net "GND")
			(options
				(clearance outline)
				(anchor circle)
			)
			(primitives
				(gr_poly
					(pts
						(arc
							(start 0.3048 -0.2032)
							(mid 0.275042 -0.275042)
							(end 0.2032 -0.3048)
						)
						(arc
							(start -0.2032 -0.3048)
							(mid -0.275042 -0.275042)
							(end -0.3048 -0.2032)
						)
						(arc
							(start -0.3048 0.2032)
							(mid -0.275042 0.275042)
							(end -0.2032 0.3048)
						)
						(arc
							(start 0.2032 0.3048)
							(mid 0.275042 0.275042)
							(end 0.3048 0.2032)
						)
					)
					(width 0)
					(fill yes)
				)
			)
		)
	)
	(footprint ""
		(layer "F.Cu")
		(at 155.758642 -95.053658)
		(property "Reference" "R692"
			(at 0 0 0)
			(layer "F.SilkS")
			(hide yes)
			(effects
				(font
					(size 1.27 1.27)
				)
			)
		)
		(property "Value" "0R2J-2-GP"
			(at 0.064008 -3.993896 0)
			(unlocked yes)
			(layer "F.Fab")
			(hide yes)
			(effects
				(font
					(size 1.016 1.016)
					(thickness 0.1524)
				)
			)
		)
		(property "Device Type" "R402H16"
			(at 0.064008 -5.517896 0)
			(unlocked yes)
			(layer "F.Fab")
			(hide yes)
			(effects
				(font
					(size 1.016 1.016)
					(thickness 0.1524)
				)
			)
		)
		(duplicate_pad_numbers_are_jumpers no)
		(fp_line
			(start -0.508 -0.9398)
			(end -0.508 0.9398)
			(stroke
				(width 0.1524)
				(type default)
			)
			(layer "F.SilkS")
		)
		(fp_line
			(start 0.508 -0.9398)
			(end -0.508 -0.9398)
			(stroke
				(width 0.1524)
				(type default)
			)
			(layer "F.SilkS")
		)
		(fp_rect
			(start -0.508 0.9398)
			(end 0.508 -0.9398)
			(stroke
				(width 0)
				(type default)
			)
			(fill no)
			(layer "F.CrtYd")
		)
		(fp_rect
			(start -0.508 0.9398)
			(end 0.508 -0.9398)
			(stroke
				(width 0)
				(type default)
			)
			(fill no)
			(layer "F.Fab")
		)
		(pad "1" smd custom
			(at 0 -0.4445)
			(size 0.1397 0.1397)
			(layers "F.Cu" "F.Mask" "F.Paste")
			(net "IOM_IOC_UART_TX")
			(options
				(clearance outline)
				(anchor circle)
			)
			(primitives
				(gr_poly
					(pts
						(arc
							(start -0.1778 -0.2794)
							(mid -0.249642 -0.249642)
							(end -0.2794 -0.1778)
						)
						(arc
							(start -0.2794 0.1778)
							(mid -0.249642 0.249642)
							(end -0.1778 0.2794)
						)
						(arc
							(start 0.1778 0.2794)
							(mid 0.249642 0.249642)
							(end 0.2794 0.1778)
						)
						(arc
							(start 0.2794 -0.1778)
							(mid 0.249642 -0.249642)
							(end 0.1778 -0.2794)
						)
					)
					(width 0)
					(fill yes)
				)
			)
		)
		(pad "2" smd custom
			(at 0 0.4445)
			(size 0.1397 0.1397)
			(layers "F.Cu" "F.Mask" "F.Paste")
			(net "IOC_UART_R_TX")
			(options
				(clearance outline)
				(anchor circle)
			)
			(primitives
				(gr_poly
					(pts
						(arc
							(start -0.1778 -0.2794)
							(mid -0.249642 -0.249642)
							(end -0.2794 -0.1778)
						)
						(arc
							(start -0.2794 0.1778)
							(mid -0.249642 0.249642)
							(end -0.1778 0.2794)
						)
						(arc
							(start 0.1778 0.2794)
							(mid 0.249642 0.249642)
							(end 0.2794 0.1778)
						)
						(arc
							(start 0.2794 -0.1778)
							(mid 0.249642 -0.249642)
							(end 0.1778 -0.2794)
						)
					)
					(width 0)
					(fill yes)
				)
			)
		)
	)
	(footprint ""
		(layer "F.Cu")
		(at 200.1266 -49.9618 -90)
		(property "Reference" "TP137"
			(at 0 0 270)
			(layer "F.SilkS")
			(hide yes)
			(effects
				(font
					(size 1.27 1.27)
				)
			)
		)
		(property "Value" "TPAD28-2-GP"
			(at -0.0127 -1.6637 270)
			(unlocked yes)
			(layer "F.Fab")
			(hide yes)
			(effects
				(font
					(size 1.016 1.016)
					(thickness 0.1524)
				)
			)
		)
		(property "Device Type" "TPAD28"
			(at -0.0127 -3.1877 270)
			(unlocked yes)
			(layer "F.Fab")
			(hide yes)
			(effects
				(font
					(size 1.016 1.016)
					(thickness 0.1524)
				)
			)
		)
		(duplicate_pad_numbers_are_jumpers no)
		(fp_poly
			(pts
				(arc
					(start 0 -0.3556)
					(mid 0 0.3556)
					(end 0 -0.3556)
				)
			)
			(stroke
				(width 0)
				(type default)
			)
			(fill no)
			(layer "F.CrtYd")
		)
		(fp_poly
			(pts
				(arc
					(start 0 -0.6096)
					(mid 0 0.6096)
					(end 0 -0.6096)
				)
			)
			(stroke
				(width 0)
				(type default)
			)
			(fill no)
			(layer "F.Fab")
		)
		(pad "1" smd circle
			(at 0 0 270)
			(size 0.7112 0.7112)
			(layers "F.Cu" "F.Mask" "F.Paste")
			(net "ICE0_TDI")
		)
	)
	(footprint ""
		(layer "F.Cu")
		(at 112.87379 -7.736078 -90)
		(property "Reference" "R459"
			(at 0 0 270)
			(layer "F.SilkS")
			(hide yes)
			(effects
				(font
					(size 1.27 1.27)
				)
			)
		)
		(property "Value" "0R2J-2-GP"
			(at 0.064008 -3.993896 270)
			(unlocked yes)
			(layer "F.Fab")
			(hide yes)
			(effects
				(font
					(size 1.016 1.016)
					(thickness 0.1524)
				)
			)
		)
		(property "Device Type" "R402H16"
			(at 0.064008 -5.517896 270)
			(unlocked yes)
			(layer "F.Fab")
			(hide yes)
			(effects
				(font
					(size 1.016 1.016)
					(thickness 0.1524)
				)
			)
		)
		(duplicate_pad_numbers_are_jumpers no)
		(fp_line
			(start -0.508 -0.9398)
			(end -0.508 0.9398)
			(stroke
				(width 0.1524)
				(type default)
			)
			(layer "F.SilkS")
		)
		(fp_line
			(start 0.508 -0.9398)
			(end -0.508 -0.9398)
			(stroke
				(width 0.1524)
				(type default)
			)
			(layer "F.SilkS")
		)
		(fp_rect
			(start -0.508 0.9398)
			(end 0.508 -0.9398)
			(stroke
				(width 0)
				(type default)
			)
			(fill no)
			(layer "F.CrtYd")
		)
		(fp_rect
			(start -0.508 0.9398)
			(end 0.508 -0.9398)
			(stroke
				(width 0)
				(type default)
			)
			(fill no)
			(layer "F.Fab")
		)
		(pad "1" smd custom
			(at 0 -0.4445 270)
			(size 0.1397 0.1397)
			(layers "F.Cu" "F.Mask" "F.Paste")
			(net "MB0_CM_ADR1_R")
			(options
				(clearance outline)
				(anchor circle)
			)
			(primitives
				(gr_poly
					(pts
						(arc
							(start -0.1778 -0.2794)
							(mid -0.249642 -0.249642)
							(end -0.2794 -0.1778)
						)
						(arc
							(start -0.2794 0.1778)
							(mid -0.249642 0.249642)
							(end -0.1778 0.2794)
						)
						(arc
							(start 0.1778 0.2794)
							(mid 0.249642 0.249642)
							(end 0.2794 0.1778)
						)
						(arc
							(start 0.2794 -0.1778)
							(mid 0.249642 -0.249642)
							(end 0.1778 -0.2794)
						)
					)
					(width 0)
					(fill yes)
				)
			)
		)
		(pad "2" smd custom
			(at 0 0.4445 270)
			(size 0.1397 0.1397)
			(layers "F.Cu" "F.Mask" "F.Paste")
			(net "AGND_CURRENT_MON")
			(options
				(clearance outline)
				(anchor circle)
			)
			(primitives
				(gr_poly
					(pts
						(arc
							(start -0.1778 -0.2794)
							(mid -0.249642 -0.249642)
							(end -0.2794 -0.1778)
						)
						(arc
							(start -0.2794 0.1778)
							(mid -0.249642 0.249642)
							(end -0.1778 0.2794)
						)
						(arc
							(start 0.1778 0.2794)
							(mid 0.249642 0.249642)
							(end 0.2794 0.1778)
						)
						(arc
							(start 0.2794 -0.1778)
							(mid 0.249642 -0.249642)
							(end 0.1778 -0.2794)
						)
					)
					(width 0)
					(fill yes)
				)
			)
		)
	)
	(footprint ""
		(layer "F.Cu")
		(at 155.42514 -132.471922 -90)
		(property "Reference" "C210"
			(at 0 0 270)
			(layer "F.SilkS")
			(hide yes)
			(effects
				(font
					(size 1.27 1.27)
				)
			)
		)
		(property "Value" "SC2200P50V2KX-2GP"
			(at 1.1811 -2.7051 270)
			(unlocked yes)
			(layer "F.Fab")
			(hide yes)
			(effects
				(font
					(size 1.016 1.016)
					(thickness 0.1524)
				)
			)
		)
		(property "Device Type" "C402H22"
			(at 1.1811 -4.2291 270)
			(unlocked yes)
			(layer "F.Fab")
			(hide yes)
			(effects
				(font
					(size 1.016 1.016)
					(thickness 0.1524)
				)
			)
		)
		(duplicate_pad_numbers_are_jumpers no)
		(fp_rect
			(start -0.4318 0.9525)
			(end 0.4318 -0.9525)
			(stroke
				(width 0)
				(type default)
			)
			(fill no)
			(layer "F.CrtYd")
		)
		(fp_rect
			(start -0.4318 0.9525)
			(end 0.4318 -0.9525)
			(stroke
				(width 0)
				(type default)
			)
			(fill no)
			(layer "F.Fab")
		)
		(pad "1" smd custom
			(at 0 -0.4445 270)
			(size 0.1524 0.1524)
			(layers "F.Cu" "F.Mask" "F.Paste")
			(net "P1V8_STBY_SW")
			(options
				(clearance outline)
				(anchor circle)
			)
			(primitives
				(gr_poly
					(pts
						(arc
							(start 0.3048 -0.2032)
							(mid 0.275042 -0.275042)
							(end 0.2032 -0.3048)
						)
						(arc
							(start -0.2032 -0.3048)
							(mid -0.275042 -0.275042)
							(end -0.3048 -0.2032)
						)
						(arc
							(start -0.3048 0.2032)
							(mid -0.275042 0.275042)
							(end -0.2032 0.3048)
						)
						(arc
							(start 0.2032 0.3048)
							(mid 0.275042 0.275042)
							(end 0.3048 0.2032)
						)
					)
					(width 0)
					(fill yes)
				)
			)
		)
		(pad "2" smd custom
			(at 0 0.4445 270)
			(size 0.1524 0.1524)
			(layers "F.Cu" "F.Mask" "F.Paste")
			(net "P1V8_STBY_SNB")
			(options
				(clearance outline)
				(anchor circle)
			)
			(primitives
				(gr_poly
					(pts
						(arc
							(start 0.3048 -0.2032)
							(mid 0.275042 -0.275042)
							(end 0.2032 -0.3048)
						)
						(arc
							(start -0.2032 -0.3048)
							(mid -0.275042 -0.275042)
							(end -0.3048 -0.2032)
						)
						(arc
							(start -0.3048 0.2032)
							(mid -0.275042 0.275042)
							(end -0.2032 0.3048)
						)
						(arc
							(start 0.2032 0.3048)
							(mid 0.275042 0.275042)
							(end 0.3048 0.2032)
						)
					)
					(width 0)
					(fill yes)
				)
			)
		)
	)
	(footprint ""
		(layer "F.Cu")
		(at 8.88111 -135.290052 -90)
		(property "Reference" "R239"
			(at 0 0 270)
			(layer "F.SilkS")
			(hide yes)
			(effects
				(font
					(size 1.27 1.27)
				)
			)
		)
		(property "Value" "0R2J-2-GP"
			(at 0.064008 -3.993896 270)
			(unlocked yes)
			(layer "F.Fab")
			(hide yes)
			(effects
				(font
					(size 1.016 1.016)
					(thickness 0.1524)
				)
			)
		)
		(property "Device Type" "R402H16"
			(at 0.064008 -5.517896 270)
			(unlocked yes)
			(layer "F.Fab")
			(hide yes)
			(effects
				(font
					(size 1.016 1.016)
					(thickness 0.1524)
				)
			)
		)
		(duplicate_pad_numbers_are_jumpers no)
		(fp_line
			(start -0.508 -0.9398)
			(end -0.508 0.9398)
			(stroke
				(width 0.1524)
				(type default)
			)
			(layer "F.SilkS")
		)
		(fp_line
			(start 0.508 -0.9398)
			(end -0.508 -0.9398)
			(stroke
				(width 0.1524)
				(type default)
			)
			(layer "F.SilkS")
		)
		(fp_rect
			(start -0.508 0.9398)
			(end 0.508 -0.9398)
			(stroke
				(width 0)
				(type default)
			)
			(fill no)
			(layer "F.CrtYd")
		)
		(fp_rect
			(start -0.508 0.9398)
			(end 0.508 -0.9398)
			(stroke
				(width 0)
				(type default)
			)
			(fill no)
			(layer "F.Fab")
		)
		(pad "1" smd custom
			(at 0 -0.4445 270)
			(size 0.1397 0.1397)
			(layers "F.Cu" "F.Mask" "F.Paste")
			(net "MEM_PAR")
			(options
				(clearance outline)
				(anchor circle)
			)
			(primitives
				(gr_poly
					(pts
						(arc
							(start -0.1778 -0.2794)
							(mid -0.249642 -0.249642)
							(end -0.2794 -0.1778)
						)
						(arc
							(start -0.2794 0.1778)
							(mid -0.249642 0.249642)
							(end -0.1778 0.2794)
						)
						(arc
							(start 0.1778 0.2794)
							(mid 0.249642 0.249642)
							(end 0.2794 0.1778)
						)
						(arc
							(start 0.2794 -0.1778)
							(mid 0.249642 -0.249642)
							(end 0.1778 -0.2794)
						)
					)
					(width 0)
					(fill yes)
				)
			)
		)
		(pad "2" smd custom
			(at 0 0.4445 270)
			(size 0.1397 0.1397)
			(layers "F.Cu" "F.Mask" "F.Paste")
			(net "GND")
			(options
				(clearance outline)
				(anchor circle)
			)
			(primitives
				(gr_poly
					(pts
						(arc
							(start -0.1778 -0.2794)
							(mid -0.249642 -0.249642)
							(end -0.2794 -0.1778)
						)
						(arc
							(start -0.2794 0.1778)
							(mid -0.249642 0.249642)
							(end -0.1778 0.2794)
						)
						(arc
							(start 0.1778 0.2794)
							(mid 0.249642 0.249642)
							(end 0.2794 0.1778)
						)
						(arc
							(start 0.2794 -0.1778)
							(mid 0.249642 -0.249642)
							(end 0.1778 -0.2794)
						)
					)
					(width 0)
					(fill yes)
				)
			)
		)
	)
	(footprint ""
		(layer "F.Cu")
		(at 164.6936 -138.4554 90)
		(property "Reference" "R511"
			(at 0 0 90)
			(layer "F.SilkS")
			(hide yes)
			(effects
				(font
					(size 1.27 1.27)
				)
			)
		)
		(property "Value" "2D2R3-1-U-GP"
			(at -0.0254 -2.5146 90)
			(unlocked yes)
			(layer "F.Fab")
			(hide yes)
			(effects
				(font
					(size 1.016 1.016)
					(thickness 0.1524)
				)
			)
		)
		(property "Device Type" "R603H22"
			(at -0.0254 -4.0386 90)
			(unlocked yes)
			(layer "F.Fab")
			(hide yes)
			(effects
				(font
					(size 1.016 1.016)
					(thickness 0.1524)
				)
			)
		)
		(duplicate_pad_numbers_are_jumpers no)
		(fp_line
			(start 0.2032 0)
			(end 0.4826 0)
			(stroke
				(width 0.2032)
				(type default)
			)
			(layer "F.SilkS")
		)
		(fp_line
			(start -0.4826 0)
			(end -0.2032 0)
			(stroke
				(width 0.2032)
				(type default)
			)
			(layer "F.SilkS")
		)
		(fp_rect
			(start -0.5842 1.3335)
			(end 0.5842 -1.3335)
			(stroke
				(width 0)
				(type default)
			)
			(fill no)
			(layer "F.CrtYd")
		)
		(fp_rect
			(start -0.5842 1.3335)
			(end 0.5842 -1.3335)
			(stroke
				(width 0)
				(type default)
			)
			(fill no)
			(layer "F.Fab")
		)
		(pad "1" smd custom
			(at 0 -0.762 90)
			(size 0.2159 0.2159)
			(layers "F.Cu" "F.Mask" "F.Paste")
			(net "P12V_STBY_VCC_PU4")
			(options
				(clearance outline)
				(anchor circle)
			)
			(primitives
				(gr_poly
					(pts
						(arc
							(start -0.3302 -0.4318)
							(mid -0.402042 -0.402042)
							(end -0.4318 -0.3302)
						)
						(arc
							(start -0.4318 0.3302)
							(mid -0.402042 0.402042)
							(end -0.3302 0.4318)
						)
						(arc
							(start 0.3302 0.4318)
							(mid 0.402042 0.402042)
							(end 0.4318 0.3302)
						)
						(arc
							(start 0.4318 -0.3302)
							(mid 0.402042 -0.402042)
							(end 0.3302 -0.4318)
						)
					)
					(width 0)
					(fill yes)
				)
			)
		)
		(pad "2" smd custom
			(at 0 0.762 90)
			(size 0.2159 0.2159)
			(layers "F.Cu" "F.Mask" "F.Paste")
			(net "P12V_STBY")
			(options
				(clearance outline)
				(anchor circle)
			)
			(primitives
				(gr_poly
					(pts
						(arc
							(start -0.3302 -0.4318)
							(mid -0.402042 -0.402042)
							(end -0.4318 -0.3302)
						)
						(arc
							(start -0.4318 0.3302)
							(mid -0.402042 0.402042)
							(end -0.3302 0.4318)
						)
						(arc
							(start 0.3302 0.4318)
							(mid 0.402042 0.402042)
							(end 0.4318 0.3302)
						)
						(arc
							(start 0.4318 -0.3302)
							(mid 0.402042 -0.402042)
							(end 0.3302 -0.4318)
						)
					)
					(width 0)
					(fill yes)
				)
			)
		)
	)
	(footprint ""
		(layer "F.Cu")
		(at 52.832 -132.207)
		(property "Reference" "TP10"
			(at 0 0 0)
			(layer "F.SilkS")
			(hide yes)
			(effects
				(font
					(size 1.27 1.27)
				)
			)
		)
		(property "Value" "TPAD28-2-GP"
			(at -0.0127 -1.6637 0)
			(unlocked yes)
			(layer "F.Fab")
			(hide yes)
			(effects
				(font
					(size 1.016 1.016)
					(thickness 0.1524)
				)
			)
		)
		(property "Device Type" "TPAD28"
			(at -0.0127 -3.1877 0)
			(unlocked yes)
			(layer "F.Fab")
			(hide yes)
			(effects
				(font
					(size 1.016 1.016)
					(thickness 0.1524)
				)
			)
		)
		(duplicate_pad_numbers_are_jumpers no)
		(fp_poly
			(pts
				(arc
					(start 0.3556 0)
					(mid -0.3556 0)
					(end 0.3556 0)
				)
			)
			(stroke
				(width 0)
				(type default)
			)
			(fill no)
			(layer "F.CrtYd")
		)
		(fp_poly
			(pts
				(arc
					(start 0.6096 0)
					(mid -0.6096 0)
					(end 0.6096 0)
				)
			)
			(stroke
				(width 0)
				(type default)
			)
			(fill no)
			(layer "F.Fab")
		)
		(pad "1" smd circle
			(at 0 0)
			(size 0.7112 0.7112)
			(layers "F.Cu" "F.Mask" "F.Paste")
			(net "TP_BMC0_LPC_LAD1")
		)
	)
	(footprint ""
		(layer "F.Cu")
		(at 58.3946 -159.1818)
		(property "Reference" "R391"
			(at 0 0 0)
			(layer "F.SilkS")
			(hide yes)
			(effects
				(font
					(size 1.27 1.27)
				)
			)
		)
		(property "Value" "4K7R2F-GP"
			(at 0.064008 -3.993896 0)
			(unlocked yes)
			(layer "F.Fab")
			(hide yes)
			(effects
				(font
					(size 1.016 1.016)
					(thickness 0.1524)
				)
			)
		)
		(property "Device Type" "R402H16"
			(at 0.064008 -5.517896 0)
			(unlocked yes)
			(layer "F.Fab")
			(hide yes)
			(effects
				(font
					(size 1.016 1.016)
					(thickness 0.1524)
				)
			)
		)
		(duplicate_pad_numbers_are_jumpers no)
		(fp_line
			(start -0.508 -0.9398)
			(end -0.508 0.9398)
			(stroke
				(width 0.1524)
				(type default)
			)
			(layer "F.SilkS")
		)
		(fp_line
			(start 0.508 -0.9398)
			(end -0.508 -0.9398)
			(stroke
				(width 0.1524)
				(type default)
			)
			(layer "F.SilkS")
		)
		(fp_rect
			(start -0.508 0.9398)
			(end 0.508 -0.9398)
			(stroke
				(width 0)
				(type default)
			)
			(fill no)
			(layer "F.CrtYd")
		)
		(fp_rect
			(start -0.508 0.9398)
			(end 0.508 -0.9398)
			(stroke
				(width 0)
				(type default)
			)
			(fill no)
			(layer "F.Fab")
		)
		(pad "1" smd custom
			(at 0 -0.4445)
			(size 0.1397 0.1397)
			(layers "F.Cu" "F.Mask" "F.Paste")
			(net "P3V3_STBY")
			(options
				(clearance outline)
				(anchor circle)
			)
			(primitives
				(gr_poly
					(pts
						(arc
							(start -0.1778 -0.2794)
							(mid -0.249642 -0.249642)
							(end -0.2794 -0.1778)
						)
						(arc
							(start -0.2794 0.1778)
							(mid -0.249642 0.249642)
							(end -0.1778 0.2794)
						)
						(arc
							(start 0.1778 0.2794)
							(mid 0.249642 0.249642)
							(end 0.2794 0.1778)
						)
						(arc
							(start 0.2794 -0.1778)
							(mid 0.249642 -0.249642)
							(end 0.1778 -0.2794)
						)
					)
					(width 0)
					(fill yes)
				)
			)
		)
		(pad "2" smd custom
			(at 0 0.4445)
			(size 0.1397 0.1397)
			(layers "F.Cu" "F.Mask" "F.Paste")
			(net "MAC2_TXD0")
			(options
				(clearance outline)
				(anchor circle)
			)
			(primitives
				(gr_poly
					(pts
						(arc
							(start -0.1778 -0.2794)
							(mid -0.249642 -0.249642)
							(end -0.2794 -0.1778)
						)
						(arc
							(start -0.2794 0.1778)
							(mid -0.249642 0.249642)
							(end -0.1778 0.2794)
						)
						(arc
							(start 0.1778 0.2794)
							(mid 0.249642 0.249642)
							(end 0.2794 0.1778)
						)
						(arc
							(start 0.2794 -0.1778)
							(mid 0.249642 -0.249642)
							(end 0.1778 -0.2794)
						)
					)
					(width 0)
					(fill yes)
				)
			)
		)
	)
	(footprint ""
		(layer "F.Cu")
		(at 111.0742 -12.079478 -90)
		(property "Reference" "C147"
			(at 0 0 270)
			(layer "F.SilkS")
			(hide yes)
			(effects
				(font
					(size 1.27 1.27)
				)
			)
		)
		(property "Value" "SC1U16V3KX-5GP"
			(at 0 -2.8194 270)
			(unlocked yes)
			(layer "F.Fab")
			(hide yes)
			(effects
				(font
					(size 1.016 1.016)
					(thickness 0.1524)
				)
			)
		)
		(property "Device Type" "C603H36"
			(at 0 -4.3434 270)
			(unlocked yes)
			(layer "F.Fab")
			(hide yes)
			(effects
				(font
					(size 1.016 1.016)
					(thickness 0.1524)
				)
			)
		)
		(duplicate_pad_numbers_are_jumpers no)
		(fp_line
			(start 0.508 0)
			(end -0.508 0)
			(stroke
				(width 0.2032)
				(type default)
			)
			(layer "F.SilkS")
		)
		(fp_rect
			(start -0.5842 1.3335)
			(end 0.5842 -1.3335)
			(stroke
				(width 0)
				(type default)
			)
			(fill no)
			(layer "F.CrtYd")
		)
		(fp_rect
			(start -0.5842 1.3335)
			(end 0.5842 -1.3335)
			(stroke
				(width 0)
				(type default)
			)
			(fill no)
			(layer "F.Fab")
		)
		(pad "1" smd custom
			(at 0 -0.762 270)
			(size 0.2159 0.2159)
			(layers "F.Cu" "F.Mask" "F.Paste")
			(net "MB0_VCAP_R")
			(options
				(clearance outline)
				(anchor circle)
			)
			(primitives
				(gr_poly
					(pts
						(arc
							(start -0.3302 -0.4318)
							(mid -0.402042 -0.402042)
							(end -0.4318 -0.3302)
						)
						(arc
							(start -0.4318 0.3302)
							(mid -0.402042 0.402042)
							(end -0.3302 0.4318)
						)
						(arc
							(start 0.3302 0.4318)
							(mid 0.402042 0.402042)
							(end 0.4318 0.3302)
						)
						(arc
							(start 0.4318 -0.3302)
							(mid 0.402042 -0.402042)
							(end 0.3302 -0.4318)
						)
					)
					(width 0)
					(fill yes)
				)
			)
		)
		(pad "2" smd custom
			(at 0 0.762 270)
			(size 0.2159 0.2159)
			(layers "F.Cu" "F.Mask" "F.Paste")
			(net "AGND_CURRENT_MON")
			(options
				(clearance outline)
				(anchor circle)
			)
			(primitives
				(gr_poly
					(pts
						(arc
							(start -0.3302 -0.4318)
							(mid -0.402042 -0.402042)
							(end -0.4318 -0.3302)
						)
						(arc
							(start -0.4318 0.3302)
							(mid -0.402042 0.402042)
							(end -0.3302 0.4318)
						)
						(arc
							(start 0.3302 0.4318)
							(mid 0.402042 0.402042)
							(end 0.4318 0.3302)
						)
						(arc
							(start 0.4318 -0.3302)
							(mid 0.402042 -0.402042)
							(end 0.3302 -0.4318)
						)
					)
					(width 0)
					(fill yes)
				)
			)
		)
	)
	(footprint ""
		(layer "F.Cu")
		(at 66.802 -172.085)
		(property "Reference" "C34"
			(at 0 0 0)
			(layer "F.SilkS")
			(hide yes)
			(effects
				(font
					(size 1.27 1.27)
				)
			)
		)
		(property "Value" "SCD1U16V2KX-3GP"
			(at 1.1811 -2.7051 0)
			(unlocked yes)
			(layer "F.Fab")
			(hide yes)
			(effects
				(font
					(size 1.016 1.016)
					(thickness 0.1524)
				)
			)
		)
		(property "Device Type" "C402H22"
			(at 1.1811 -4.2291 0)
			(unlocked yes)
			(layer "F.Fab")
			(hide yes)
			(effects
				(font
					(size 1.016 1.016)
					(thickness 0.1524)
				)
			)
		)
		(duplicate_pad_numbers_are_jumpers no)
		(fp_rect
			(start -0.4318 0.9525)
			(end 0.4318 -0.9525)
			(stroke
				(width 0)
				(type default)
			)
			(fill no)
			(layer "F.CrtYd")
		)
		(fp_rect
			(start -0.4318 0.9525)
			(end 0.4318 -0.9525)
			(stroke
				(width 0)
				(type default)
			)
			(fill no)
			(layer "F.Fab")
		)
		(pad "1" smd custom
			(at 0 -0.4445)
			(size 0.1524 0.1524)
			(layers "F.Cu" "F.Mask" "F.Paste")
			(net "P5V_STBY")
			(options
				(clearance outline)
				(anchor circle)
			)
			(primitives
				(gr_poly
					(pts
						(arc
							(start 0.3048 -0.2032)
							(mid 0.275042 -0.275042)
							(end 0.2032 -0.3048)
						)
						(arc
							(start -0.2032 -0.3048)
							(mid -0.275042 -0.275042)
							(end -0.3048 -0.2032)
						)
						(arc
							(start -0.3048 0.2032)
							(mid -0.275042 0.275042)
							(end -0.2032 0.3048)
						)
						(arc
							(start 0.2032 0.3048)
							(mid 0.275042 0.275042)
							(end 0.3048 0.2032)
						)
					)
					(width 0)
					(fill yes)
				)
			)
		)
		(pad "2" smd custom
			(at 0 0.4445)
			(size 0.1524 0.1524)
			(layers "F.Cu" "F.Mask" "F.Paste")
			(net "GND")
			(options
				(clearance outline)
				(anchor circle)
			)
			(primitives
				(gr_poly
					(pts
						(arc
							(start 0.3048 -0.2032)
							(mid 0.275042 -0.275042)
							(end 0.2032 -0.3048)
						)
						(arc
							(start -0.2032 -0.3048)
							(mid -0.275042 -0.275042)
							(end -0.3048 -0.2032)
						)
						(arc
							(start -0.3048 0.2032)
							(mid -0.275042 0.275042)
							(end -0.2032 0.3048)
						)
						(arc
							(start 0.2032 0.3048)
							(mid 0.275042 0.275042)
							(end 0.3048 0.2032)
						)
					)
					(width 0)
					(fill yes)
				)
			)
		)
	)
	(footprint ""
		(layer "F.Cu")
		(at 131.230878 -6.462776 -90)
		(property "Reference" "R450"
			(at 0 0 270)
			(layer "F.SilkS")
			(hide yes)
			(effects
				(font
					(size 1.27 1.27)
				)
			)
		)
		(property "Value" "10R5F-1-GP"
			(at 0 -8.9535 270)
			(unlocked yes)
			(layer "F.Fab")
			(hide yes)
			(effects
				(font
					(size 1.27 1.016)
					(thickness 0.1524)
				)
			)
		)
		(property "Device Type" "R805H24"
			(at 0 -10.6299 270)
			(unlocked yes)
			(layer "F.Fab")
			(hide yes)
			(effects
				(font
					(size 1.27 1.016)
					(thickness 0.1524)
				)
			)
		)
		(duplicate_pad_numbers_are_jumpers no)
		(fp_line
			(start -0.889 1.7018)
			(end 0.889 1.7018)
			(stroke
				(width 0.1524)
				(type default)
			)
			(layer "F.SilkS")
		)
		(fp_line
			(start 0.889 1.7018)
			(end 0.889 -0.508)
			(stroke
				(width 0.1524)
				(type default)
			)
			(layer "F.SilkS")
		)
		(fp_line
			(start -0.889 0.0762)
			(end -0.889 1.7018)
			(stroke
				(width 0.1524)
				(type default)
			)
			(layer "F.SilkS")
		)
		(fp_line
			(start -0.889 -1.7018)
			(end -0.889 0.2794)
			(stroke
				(width 0.1524)
				(type default)
			)
			(layer "F.SilkS")
		)
		(fp_line
			(start 0.889 -1.7018)
			(end 0.889 -0.381)
			(stroke
				(width 0.1524)
				(type default)
			)
			(layer "F.SilkS")
		)
		(fp_line
			(start 0.889 -1.7018)
			(end -0.889 -1.7018)
			(stroke
				(width 0.1524)
				(type default)
			)
			(layer "F.SilkS")
		)
		(fp_poly
			(pts
				(xy 0.9652 -1.778) (xy 0.9652 1.778) (xy -0.9652 1.778) (xy -0.9652 -1.778)
			)
			(stroke
				(width 0)
				(type default)
			)
			(fill no)
			(layer "F.CrtYd")
		)
		(fp_rect
			(start -0.9652 1.778)
			(end 0.9652 -1.778)
			(stroke
				(width 0)
				(type default)
			)
			(fill no)
			(layer "F.Fab")
		)
		(pad "1" smd rect
			(at 0 -0.9652 270)
			(size 1.397 1.143)
			(layers "F.Cu" "F.Mask" "F.Paste")
			(net "MB0_12V_CTRL_GATE1")
		)
		(pad "2" smd rect
			(at 0 0.9652 270)
			(size 1.397 1.143)
			(layers "F.Cu" "F.Mask" "F.Paste")
			(net "MB0_CM_GATE_R")
		)
	)
	(footprint ""
		(layer "F.Cu")
		(at 74.46137 -138.914124 -90)
		(property "Reference" "R51"
			(at 0 0 270)
			(layer "F.SilkS")
			(hide yes)
			(effects
				(font
					(size 1.27 1.27)
				)
			)
		)
		(property "Value" "33R2F-3-GP"
			(at 0.064008 -3.993896 270)
			(unlocked yes)
			(layer "F.Fab")
			(hide yes)
			(effects
				(font
					(size 1.016 1.016)
					(thickness 0.1524)
				)
			)
		)
		(property "Device Type" "R402H16"
			(at 0.064008 -5.517896 270)
			(unlocked yes)
			(layer "F.Fab")
			(hide yes)
			(effects
				(font
					(size 1.016 1.016)
					(thickness 0.1524)
				)
			)
		)
		(duplicate_pad_numbers_are_jumpers no)
		(fp_line
			(start -0.508 -0.9398)
			(end -0.508 0.9398)
			(stroke
				(width 0.1524)
				(type default)
			)
			(layer "F.SilkS")
		)
		(fp_line
			(start 0.508 -0.9398)
			(end -0.508 -0.9398)
			(stroke
				(width 0.1524)
				(type default)
			)
			(layer "F.SilkS")
		)
		(fp_rect
			(start -0.508 0.9398)
			(end 0.508 -0.9398)
			(stroke
				(width 0)
				(type default)
			)
			(fill no)
			(layer "F.CrtYd")
		)
		(fp_rect
			(start -0.508 0.9398)
			(end 0.508 -0.9398)
			(stroke
				(width 0)
				(type default)
			)
			(fill no)
			(layer "F.Fab")
		)
		(pad "1" smd custom
			(at 0 -0.4445 270)
			(size 0.1397 0.1397)
			(layers "F.Cu" "F.Mask" "F.Paste")
			(net "FP_PWR_BTN_N")
			(options
				(clearance outline)
				(anchor circle)
			)
			(primitives
				(gr_poly
					(pts
						(arc
							(start -0.1778 -0.2794)
							(mid -0.249642 -0.249642)
							(end -0.2794 -0.1778)
						)
						(arc
							(start -0.2794 0.1778)
							(mid -0.249642 0.249642)
							(end -0.1778 0.2794)
						)
						(arc
							(start 0.1778 0.2794)
							(mid 0.249642 0.249642)
							(end 0.2794 0.1778)
						)
						(arc
							(start 0.2794 -0.1778)
							(mid 0.249642 -0.249642)
							(end 0.1778 -0.2794)
						)
					)
					(width 0)
					(fill yes)
				)
			)
		)
		(pad "2" smd custom
			(at 0 0.4445 270)
			(size 0.1397 0.1397)
			(layers "F.Cu" "F.Mask" "F.Paste")
			(net "FP_PWR_BTN_N_R")
			(options
				(clearance outline)
				(anchor circle)
			)
			(primitives
				(gr_poly
					(pts
						(arc
							(start -0.1778 -0.2794)
							(mid -0.249642 -0.249642)
							(end -0.2794 -0.1778)
						)
						(arc
							(start -0.2794 0.1778)
							(mid -0.249642 0.249642)
							(end -0.1778 0.2794)
						)
						(arc
							(start 0.1778 0.2794)
							(mid 0.249642 0.249642)
							(end 0.2794 0.1778)
						)
						(arc
							(start 0.2794 -0.1778)
							(mid 0.249642 -0.249642)
							(end 0.1778 -0.2794)
						)
					)
					(width 0)
					(fill yes)
				)
			)
		)
	)
	(footprint ""
		(layer "F.Cu")
		(at 23.756874 -125.638814 180)
		(property "Reference" "R346"
			(at 0 0 180)
			(layer "F.SilkS")
			(hide yes)
			(effects
				(font
					(size 1.27 1.27)
				)
			)
		)
		(property "Value" "150R2F-1-GP"
			(at 0.064008 -3.993896 180)
			(unlocked yes)
			(layer "F.Fab")
			(hide yes)
			(effects
				(font
					(size 1.016 1.016)
					(thickness 0.1524)
				)
			)
		)
		(property "Device Type" "R402H16"
			(at 0.064008 -5.517896 180)
			(unlocked yes)
			(layer "F.Fab")
			(hide yes)
			(effects
				(font
					(size 1.016 1.016)
					(thickness 0.1524)
				)
			)
		)
		(duplicate_pad_numbers_are_jumpers no)
		(fp_line
			(start 0.508 -0.9398)
			(end -0.508 -0.9398)
			(stroke
				(width 0.1524)
				(type default)
			)
			(layer "F.SilkS")
		)
		(fp_line
			(start -0.508 -0.9398)
			(end -0.508 0.9398)
			(stroke
				(width 0.1524)
				(type default)
			)
			(layer "F.SilkS")
		)
		(fp_rect
			(start -0.508 0.9398)
			(end 0.508 -0.9398)
			(stroke
				(width 0)
				(type default)
			)
			(fill no)
			(layer "F.CrtYd")
		)
		(fp_rect
			(start -0.508 0.9398)
			(end 0.508 -0.9398)
			(stroke
				(width 0)
				(type default)
			)
			(fill no)
			(layer "F.Fab")
		)
		(pad "1" smd custom
			(at 0 -0.4445 180)
			(size 0.1397 0.1397)
			(layers "F.Cu" "F.Mask" "F.Paste")
			(net "P3V3_STBY")
			(options
				(clearance outline)
				(anchor circle)
			)
			(primitives
				(gr_poly
					(pts
						(arc
							(start -0.1778 -0.2794)
							(mid -0.249642 -0.249642)
							(end -0.2794 -0.1778)
						)
						(arc
							(start -0.2794 0.1778)
							(mid -0.249642 0.249642)
							(end -0.1778 0.2794)
						)
						(arc
							(start 0.1778 0.2794)
							(mid 0.249642 0.249642)
							(end 0.2794 0.1778)
						)
						(arc
							(start 0.2794 -0.1778)
							(mid 0.249642 -0.249642)
							(end 0.1778 -0.2794)
						)
					)
					(width 0)
					(fill yes)
				)
			)
		)
		(pad "2" smd custom
			(at 0 0.4445 180)
			(size 0.1397 0.1397)
			(layers "F.Cu" "F.Mask" "F.Paste")
			(net "BMC_HBLED_R")
			(options
				(clearance outline)
				(anchor circle)
			)
			(primitives
				(gr_poly
					(pts
						(arc
							(start -0.1778 -0.2794)
							(mid -0.249642 -0.249642)
							(end -0.2794 -0.1778)
						)
						(arc
							(start -0.2794 0.1778)
							(mid -0.249642 0.249642)
							(end -0.1778 0.2794)
						)
						(arc
							(start 0.1778 0.2794)
							(mid 0.249642 0.249642)
							(end 0.2794 0.1778)
						)
						(arc
							(start 0.2794 -0.1778)
							(mid 0.249642 -0.249642)
							(end 0.1778 -0.2794)
						)
					)
					(width 0)
					(fill yes)
				)
			)
		)
	)
	(footprint ""
		(layer "F.Cu")
		(at 61.543184 -143.458692 90)
		(property "Reference" "R157"
			(at 0 0 90)
			(layer "F.SilkS")
			(hide yes)
			(effects
				(font
					(size 1.27 1.27)
				)
			)
		)
		(property "Value" "0R2J-2-GP"
			(at 0.064008 -3.993896 90)
			(unlocked yes)
			(layer "F.Fab")
			(hide yes)
			(effects
				(font
					(size 1.016 1.016)
					(thickness 0.1524)
				)
			)
		)
		(property "Device Type" "R402H16"
			(at 0.064008 -5.517896 90)
			(unlocked yes)
			(layer "F.Fab")
			(hide yes)
			(effects
				(font
					(size 1.016 1.016)
					(thickness 0.1524)
				)
			)
		)
		(duplicate_pad_numbers_are_jumpers no)
		(fp_line
			(start 0.508 -0.9398)
			(end -0.508 -0.9398)
			(stroke
				(width 0.1524)
				(type default)
			)
			(layer "F.SilkS")
		)
		(fp_line
			(start -0.508 -0.9398)
			(end -0.508 0.9398)
			(stroke
				(width 0.1524)
				(type default)
			)
			(layer "F.SilkS")
		)
		(fp_rect
			(start -0.508 0.9398)
			(end 0.508 -0.9398)
			(stroke
				(width 0)
				(type default)
			)
			(fill no)
			(layer "F.CrtYd")
		)
		(fp_rect
			(start -0.508 0.9398)
			(end 0.508 -0.9398)
			(stroke
				(width 0)
				(type default)
			)
			(fill no)
			(layer "F.Fab")
		)
		(pad "1" smd custom
			(at 0 -0.4445 90)
			(size 0.1397 0.1397)
			(layers "F.Cu" "F.Mask" "F.Paste")
			(net "BMC_SMB11_DAT")
			(options
				(clearance outline)
				(anchor circle)
			)
			(primitives
				(gr_poly
					(pts
						(arc
							(start -0.1778 -0.2794)
							(mid -0.249642 -0.249642)
							(end -0.2794 -0.1778)
						)
						(arc
							(start -0.2794 0.1778)
							(mid -0.249642 0.249642)
							(end -0.1778 0.2794)
						)
						(arc
							(start 0.1778 0.2794)
							(mid 0.249642 0.249642)
							(end 0.2794 0.1778)
						)
						(arc
							(start 0.2794 -0.1778)
							(mid 0.249642 -0.249642)
							(end 0.1778 -0.2794)
						)
					)
					(width 0)
					(fill yes)
				)
			)
		)
		(pad "2" smd custom
			(at 0 0.4445 90)
			(size 0.1397 0.1397)
			(layers "F.Cu" "F.Mask" "F.Paste")
			(net "I2C_EXP_RMT_SDA_OUT")
			(options
				(clearance outline)
				(anchor circle)
			)
			(primitives
				(gr_poly
					(pts
						(arc
							(start -0.1778 -0.2794)
							(mid -0.249642 -0.249642)
							(end -0.2794 -0.1778)
						)
						(arc
							(start -0.2794 0.1778)
							(mid -0.249642 0.249642)
							(end -0.1778 0.2794)
						)
						(arc
							(start 0.1778 0.2794)
							(mid 0.249642 0.249642)
							(end 0.2794 0.1778)
						)
						(arc
							(start 0.2794 -0.1778)
							(mid 0.249642 -0.249642)
							(end 0.1778 -0.2794)
						)
					)
					(width 0)
					(fill yes)
				)
			)
		)
	)
	(footprint ""
		(layer "F.Cu")
		(at 200.7362 -113.5126 180)
		(property "Reference" "C259"
			(at 0 0 180)
			(layer "F.SilkS")
			(hide yes)
			(effects
				(font
					(size 1.27 1.27)
				)
			)
		)
		(property "Value" "SC22U6D3V6KX-2-GP"
			(at -0.0762 -5.1308 180)
			(unlocked yes)
			(layer "F.Fab")
			(hide yes)
			(effects
				(font
					(size 1.016 1.016)
					(thickness 0.1524)
				)
			)
		)
		(property "Device Type" "C1206H71"
			(at -0.127 -6.6548 180)
			(unlocked yes)
			(layer "F.Fab")
			(hide yes)
			(effects
				(font
					(size 1.016 1.016)
					(thickness 0.1524)
				)
			)
		)
		(duplicate_pad_numbers_are_jumpers no)
		(fp_line
			(start 1.016 2.2352)
			(end -1.016 2.2352)
			(stroke
				(width 0.1524)
				(type default)
			)
			(layer "F.SilkS")
		)
		(fp_line
			(start 1.016 0.8382)
			(end 1.016 2.2352)
			(stroke
				(width 0.1524)
				(type default)
			)
			(layer "F.SilkS")
		)
		(fp_line
			(start 1.016 -2.2352)
			(end 1.016 -0.8382)
			(stroke
				(width 0.1524)
				(type default)
			)
			(layer "F.SilkS")
		)
		(fp_line
			(start -1.016 2.2352)
			(end -1.016 0.8382)
			(stroke
				(width 0.1524)
				(type default)
			)
			(layer "F.SilkS")
		)
		(fp_line
			(start -1.016 -0.8382)
			(end -1.016 -2.2352)
			(stroke
				(width 0.1524)
				(type default)
			)
			(layer "F.SilkS")
		)
		(fp_line
			(start -1.016 -2.2352)
			(end 1.016 -2.2352)
			(stroke
				(width 0.1524)
				(type default)
			)
			(layer "F.SilkS")
		)
		(fp_rect
			(start -1.0922 2.3114)
			(end 1.0922 -2.3114)
			(stroke
				(width 0)
				(type default)
			)
			(fill no)
			(layer "F.CrtYd")
		)
		(fp_poly
			(pts
				(xy 1.0922 -2.3114) (xy 1.0922 2.3114) (xy -1.0922 2.3114) (xy -1.0922 -2.3114)
			)
			(stroke
				(width 0)
				(type default)
			)
			(fill no)
			(layer "F.Fab")
		)
		(pad "1" smd rect
			(at 0 -1.397 180)
			(size 1.651 1.27)
			(layers "F.Cu" "F.Mask" "F.Paste")
			(net "P0V975")
		)
		(pad "2" smd rect
			(at 0 1.397 180)
			(size 1.651 1.27)
			(layers "F.Cu" "F.Mask" "F.Paste")
			(net "GND")
		)
	)
	(footprint ""
		(layer "F.Cu")
		(at 124.841 -8.636 90)
		(property "Reference" "R435"
			(at 0 0 90)
			(layer "F.SilkS")
			(hide yes)
			(effects
				(font
					(size 1.27 1.27)
				)
			)
		)
		(property "Value" "3K83R2F-GP"
			(at 0.064008 -3.993896 90)
			(unlocked yes)
			(layer "F.Fab")
			(hide yes)
			(effects
				(font
					(size 1.016 1.016)
					(thickness 0.1524)
				)
			)
		)
		(property "Device Type" "R402H16"
			(at 0.064008 -5.517896 90)
			(unlocked yes)
			(layer "F.Fab")
			(hide yes)
			(effects
				(font
					(size 1.016 1.016)
					(thickness 0.1524)
				)
			)
		)
		(duplicate_pad_numbers_are_jumpers no)
		(fp_line
			(start 0.508 -0.9398)
			(end -0.508 -0.9398)
			(stroke
				(width 0.1524)
				(type default)
			)
			(layer "F.SilkS")
		)
		(fp_line
			(start -0.508 -0.9398)
			(end -0.508 0.9398)
			(stroke
				(width 0.1524)
				(type default)
			)
			(layer "F.SilkS")
		)
		(fp_rect
			(start -0.508 0.9398)
			(end 0.508 -0.9398)
			(stroke
				(width 0)
				(type default)
			)
			(fill no)
			(layer "F.CrtYd")
		)
		(fp_rect
			(start -0.508 0.9398)
			(end 0.508 -0.9398)
			(stroke
				(width 0)
				(type default)
			)
			(fill no)
			(layer "F.Fab")
		)
		(pad "1" smd custom
			(at 0 -0.4445 90)
			(size 0.1397 0.1397)
			(layers "F.Cu" "F.Mask" "F.Paste")
			(net "P12V_IOM_PGOOD")
			(options
				(clearance outline)
				(anchor circle)
			)
			(primitives
				(gr_poly
					(pts
						(arc
							(start -0.1778 -0.2794)
							(mid -0.249642 -0.249642)
							(end -0.2794 -0.1778)
						)
						(arc
							(start -0.2794 0.1778)
							(mid -0.249642 0.249642)
							(end -0.1778 0.2794)
						)
						(arc
							(start 0.1778 0.2794)
							(mid 0.249642 0.249642)
							(end 0.2794 0.1778)
						)
						(arc
							(start 0.2794 -0.1778)
							(mid 0.249642 -0.249642)
							(end 0.1778 -0.2794)
						)
					)
					(width 0)
					(fill yes)
				)
			)
		)
		(pad "2" smd custom
			(at 0 0.4445 90)
			(size 0.1397 0.1397)
			(layers "F.Cu" "F.Mask" "F.Paste")
			(net "GND")
			(options
				(clearance outline)
				(anchor circle)
			)
			(primitives
				(gr_poly
					(pts
						(arc
							(start -0.1778 -0.2794)
							(mid -0.249642 -0.249642)
							(end -0.2794 -0.1778)
						)
						(arc
							(start -0.2794 0.1778)
							(mid -0.249642 0.249642)
							(end -0.1778 0.2794)
						)
						(arc
							(start 0.1778 0.2794)
							(mid 0.249642 0.249642)
							(end 0.2794 0.1778)
						)
						(arc
							(start 0.2794 -0.1778)
							(mid 0.249642 -0.249642)
							(end 0.1778 -0.2794)
						)
					)
					(width 0)
					(fill yes)
				)
			)
		)
	)
	(footprint ""
		(layer "F.Cu")
		(at 88.245188 -62.817756 -90)
		(property "Reference" "R7"
			(at 0 0 270)
			(layer "F.SilkS")
			(hide yes)
			(effects
				(font
					(size 1.27 1.27)
				)
			)
		)
		(property "Value" "0R2J-2-GP"
			(at 0.064008 -3.993896 270)
			(unlocked yes)
			(layer "F.Fab")
			(hide yes)
			(effects
				(font
					(size 1.016 1.016)
					(thickness 0.1524)
				)
			)
		)
		(property "Device Type" "R402H16"
			(at 0.064008 -5.517896 270)
			(unlocked yes)
			(layer "F.Fab")
			(hide yes)
			(effects
				(font
					(size 1.016 1.016)
					(thickness 0.1524)
				)
			)
		)
		(duplicate_pad_numbers_are_jumpers no)
		(fp_line
			(start -0.508 -0.9398)
			(end -0.508 0.9398)
			(stroke
				(width 0.1524)
				(type default)
			)
			(layer "F.SilkS")
		)
		(fp_line
			(start 0.508 -0.9398)
			(end -0.508 -0.9398)
			(stroke
				(width 0.1524)
				(type default)
			)
			(layer "F.SilkS")
		)
		(fp_rect
			(start -0.508 0.9398)
			(end 0.508 -0.9398)
			(stroke
				(width 0)
				(type default)
			)
			(fill no)
			(layer "F.CrtYd")
		)
		(fp_rect
			(start -0.508 0.9398)
			(end 0.508 -0.9398)
			(stroke
				(width 0)
				(type default)
			)
			(fill no)
			(layer "F.Fab")
		)
		(pad "1" smd custom
			(at 0 -0.4445 270)
			(size 0.1397 0.1397)
			(layers "F.Cu" "F.Mask" "F.Paste")
			(net "NCSI_TXEN")
			(options
				(clearance outline)
				(anchor circle)
			)
			(primitives
				(gr_poly
					(pts
						(arc
							(start -0.1778 -0.2794)
							(mid -0.249642 -0.249642)
							(end -0.2794 -0.1778)
						)
						(arc
							(start -0.2794 0.1778)
							(mid -0.249642 0.249642)
							(end -0.1778 0.2794)
						)
						(arc
							(start 0.1778 0.2794)
							(mid 0.249642 0.249642)
							(end 0.2794 0.1778)
						)
						(arc
							(start 0.2794 -0.1778)
							(mid 0.249642 -0.249642)
							(end 0.1778 -0.2794)
						)
					)
					(width 0)
					(fill yes)
				)
			)
		)
		(pad "2" smd custom
			(at 0 0.4445 270)
			(size 0.1397 0.1397)
			(layers "F.Cu" "F.Mask" "F.Paste")
			(net "NCSI_TXEN_R")
			(options
				(clearance outline)
				(anchor circle)
			)
			(primitives
				(gr_poly
					(pts
						(arc
							(start -0.1778 -0.2794)
							(mid -0.249642 -0.249642)
							(end -0.2794 -0.1778)
						)
						(arc
							(start -0.2794 0.1778)
							(mid -0.249642 0.249642)
							(end -0.1778 0.2794)
						)
						(arc
							(start 0.1778 0.2794)
							(mid 0.249642 0.249642)
							(end 0.2794 0.1778)
						)
						(arc
							(start 0.2794 -0.1778)
							(mid 0.249642 -0.249642)
							(end 0.1778 -0.2794)
						)
					)
					(width 0)
					(fill yes)
				)
			)
		)
	)
	(footprint ""
		(layer "F.Cu")
		(at 183.515 -88.392)
		(property "Reference" "R627"
			(at 0 0 0)
			(layer "F.SilkS")
			(hide yes)
			(effects
				(font
					(size 1.27 1.27)
				)
			)
		)
		(property "Value" "4K7R2F-GP"
			(at 0.064008 -3.993896 0)
			(unlocked yes)
			(layer "F.Fab")
			(hide yes)
			(effects
				(font
					(size 1.016 1.016)
					(thickness 0.1524)
				)
			)
		)
		(property "Device Type" "R402H16"
			(at 0.064008 -5.517896 0)
			(unlocked yes)
			(layer "F.Fab")
			(hide yes)
			(effects
				(font
					(size 1.016 1.016)
					(thickness 0.1524)
				)
			)
		)
		(duplicate_pad_numbers_are_jumpers no)
		(fp_line
			(start -0.508 -0.9398)
			(end -0.508 0.9398)
			(stroke
				(width 0.1524)
				(type default)
			)
			(layer "F.SilkS")
		)
		(fp_line
			(start 0.508 -0.9398)
			(end -0.508 -0.9398)
			(stroke
				(width 0.1524)
				(type default)
			)
			(layer "F.SilkS")
		)
		(fp_rect
			(start -0.508 0.9398)
			(end 0.508 -0.9398)
			(stroke
				(width 0)
				(type default)
			)
			(fill no)
			(layer "F.CrtYd")
		)
		(fp_rect
			(start -0.508 0.9398)
			(end 0.508 -0.9398)
			(stroke
				(width 0)
				(type default)
			)
			(fill no)
			(layer "F.Fab")
		)
		(pad "1" smd custom
			(at 0 -0.4445)
			(size 0.1397 0.1397)
			(layers "F.Cu" "F.Mask" "F.Paste")
			(net "P1V8")
			(options
				(clearance outline)
				(anchor circle)
			)
			(primitives
				(gr_poly
					(pts
						(arc
							(start -0.1778 -0.2794)
							(mid -0.249642 -0.249642)
							(end -0.2794 -0.1778)
						)
						(arc
							(start -0.2794 0.1778)
							(mid -0.249642 0.249642)
							(end -0.1778 0.2794)
						)
						(arc
							(start 0.1778 0.2794)
							(mid 0.249642 0.249642)
							(end 0.2794 0.1778)
						)
						(arc
							(start 0.2794 -0.1778)
							(mid 0.249642 -0.249642)
							(end 0.1778 -0.2794)
						)
					)
					(width 0)
					(fill yes)
				)
			)
		)
		(pad "2" smd custom
			(at 0 0.4445)
			(size 0.1397 0.1397)
			(layers "F.Cu" "F.Mask" "F.Paste")
			(net "SYS_HALT0#")
			(options
				(clearance outline)
				(anchor circle)
			)
			(primitives
				(gr_poly
					(pts
						(arc
							(start -0.1778 -0.2794)
							(mid -0.249642 -0.249642)
							(end -0.2794 -0.1778)
						)
						(arc
							(start -0.2794 0.1778)
							(mid -0.249642 0.249642)
							(end -0.1778 0.2794)
						)
						(arc
							(start 0.1778 0.2794)
							(mid 0.249642 0.249642)
							(end 0.2794 0.1778)
						)
						(arc
							(start 0.2794 -0.1778)
							(mid 0.249642 -0.249642)
							(end 0.1778 -0.2794)
						)
					)
					(width 0)
					(fill yes)
				)
			)
		)
	)
	(footprint ""
		(layer "F.Cu")
		(at 153.383742 -97.335594 180)
		(property "Reference" "Q16"
			(at 0 0 180)
			(layer "F.SilkS")
			(hide yes)
			(effects
				(font
					(size 1.27 1.27)
				)
			)
		)
		(property "Value" "2N7002K-1-GP"
			(at 0.127 -8.9662 180)
			(unlocked yes)
			(layer "F.Fab")
			(hide yes)
			(effects
				(font
					(size 1.016 1.016)
					(thickness 0.1524)
				)
			)
		)
		(property "Device Type" "SOT23DGS2D4H44"
			(at 0.127 -10.4902 180)
			(unlocked yes)
			(layer "F.Fab")
			(hide yes)
			(effects
				(font
					(size 1.016 1.016)
					(thickness 0.1524)
				)
			)
		)
		(duplicate_pad_numbers_are_jumpers no)
		(fp_line
			(start 1.651 1.778)
			(end 1.651 -1.778)
			(stroke
				(width 0.1524)
				(type default)
			)
			(layer "F.SilkS")
		)
		(fp_line
			(start 1.651 -1.778)
			(end -1.651 -1.778)
			(stroke
				(width 0.1524)
				(type default)
			)
			(layer "F.SilkS")
		)
		(fp_line
			(start -1.651 1.778)
			(end 1.651 1.778)
			(stroke
				(width 0.1524)
				(type default)
			)
			(layer "F.SilkS")
		)
		(fp_line
			(start -1.651 -1.778)
			(end -1.651 1.778)
			(stroke
				(width 0.1524)
				(type default)
			)
			(layer "F.SilkS")
		)
		(fp_poly
			(pts
				(xy -1.778 1.8796) (xy -1.778 -1.8796) (xy 1.778 -1.8796) (xy 1.778 1.8796)
			)
			(stroke
				(width 0)
				(type default)
			)
			(fill no)
			(layer "F.CrtYd")
		)
		(fp_poly
			(pts
				(xy -1.778 1.8796) (xy -1.778 -1.8796) (xy 1.778 -1.8796) (xy 1.778 1.8796)
			)
			(stroke
				(width 0)
				(type default)
			)
			(fill no)
			(layer "F.Fab")
		)
		(pad "D" smd custom
			(at 0 -0.9525 180)
			(size 0.1905 0.1905)
			(layers "F.Cu" "F.Mask" "F.Paste")
			(net "SYS_RST_N_0")
			(options
				(clearance outline)
				(anchor circle)
			)
			(primitives
				(gr_poly
					(pts
						(arc
							(start -0.1778 0.5715)
							(mid -0.321484 0.511984)
							(end -0.381 0.3683)
						)
						(arc
							(start -0.381 -0.3683)
							(mid -0.321484 -0.511984)
							(end -0.1778 -0.5715)
						)
						(arc
							(start 0.1778 -0.5715)
							(mid 0.321484 -0.511984)
							(end 0.381 -0.3683)
						)
						(arc
							(start 0.381 0.3683)
							(mid 0.321484 0.511984)
							(end 0.1778 0.5715)
						)
					)
					(width 0)
					(fill yes)
				)
			)
		)
		(pad "G" smd custom
			(at -0.98425 0.9525 180)
			(size 0.1905 0.1905)
			(layers "F.Cu" "F.Mask" "F.Paste")
			(net "P3V3_STBY_G")
			(options
				(clearance outline)
				(anchor circle)
			)
			(primitives
				(gr_poly
					(pts
						(arc
							(start -0.1778 0.5715)
							(mid -0.321484 0.511984)
							(end -0.381 0.3683)
						)
						(arc
							(start -0.381 -0.3683)
							(mid -0.321484 -0.511984)
							(end -0.1778 -0.5715)
						)
						(arc
							(start 0.1778 -0.5715)
							(mid 0.321484 -0.511984)
							(end 0.381 -0.3683)
						)
						(arc
							(start 0.381 0.3683)
							(mid 0.321484 0.511984)
							(end 0.1778 0.5715)
						)
					)
					(width 0)
					(fill yes)
				)
			)
		)
		(pad "S" smd custom
			(at 0.98425 0.9525 180)
			(size 0.1905 0.1905)
			(layers "F.Cu" "F.Mask" "F.Paste")
			(net "GND")
			(options
				(clearance outline)
				(anchor circle)
			)
			(primitives
				(gr_poly
					(pts
						(arc
							(start -0.1778 0.5715)
							(mid -0.321484 0.511984)
							(end -0.381 0.3683)
						)
						(arc
							(start -0.381 -0.3683)
							(mid -0.321484 -0.511984)
							(end -0.1778 -0.5715)
						)
						(arc
							(start 0.1778 -0.5715)
							(mid 0.321484 -0.511984)
							(end 0.381 -0.3683)
						)
						(arc
							(start 0.381 0.3683)
							(mid 0.321484 0.511984)
							(end 0.1778 0.5715)
						)
					)
					(width 0)
					(fill yes)
				)
			)
		)
	)
	(footprint ""
		(layer "F.Cu")
		(at 29.755846 -186.56681 180)
		(property "Reference" "C177"
			(at 0 0 180)
			(layer "F.SilkS")
			(hide yes)
			(effects
				(font
					(size 1.27 1.27)
				)
			)
		)
		(property "Value" "SC10U16V5KX-7-GP-U"
			(at -0.0762 -6.1214 180)
			(unlocked yes)
			(layer "F.Fab")
			(hide yes)
			(effects
				(font
					(size 1.016 1.016)
					(thickness 0.1524)
				)
			)
		)
		(property "Device Type" "C805H58"
			(at -0.0762 -8.1534 180)
			(unlocked yes)
			(layer "F.Fab")
			(hide yes)
			(effects
				(font
					(size 1.016 1.016)
					(thickness 0.1524)
				)
			)
		)
		(duplicate_pad_numbers_are_jumpers no)
		(fp_line
			(start 0.635 0)
			(end -0.635 0)
			(stroke
				(width 0.508)
				(type default)
			)
			(layer "F.SilkS")
		)
		(fp_rect
			(start -0.9652 1.778)
			(end 0.9652 -1.778)
			(stroke
				(width 0)
				(type default)
			)
			(fill no)
			(layer "F.CrtYd")
		)
		(fp_poly
			(pts
				(xy -0.9652 -1.778) (xy 0.9652 -1.778) (xy 0.9652 1.778) (xy -0.9652 1.778)
			)
			(stroke
				(width 0)
				(type default)
			)
			(fill no)
			(layer "F.Fab")
		)
		(pad "1" smd rect
			(at 0 -0.9652 180)
			(size 1.397 1.143)
			(layers "F.Cu" "F.Mask" "F.Paste")
			(net "P12V_STBY_VIN_PU2")
		)
		(pad "2" smd rect
			(at 0 0.9652 180)
			(size 1.397 1.143)
			(layers "F.Cu" "F.Mask" "F.Paste")
			(net "GND")
		)
	)
	(footprint ""
		(layer "F.Cu")
		(at 154.559 -85.7758 180)
		(property "Reference" "R694"
			(at 0 0 180)
			(layer "F.SilkS")
			(hide yes)
			(effects
				(font
					(size 1.27 1.27)
				)
			)
		)
		(property "Value" "0R2J-2-GP"
			(at 0.064008 -3.993896 180)
			(unlocked yes)
			(layer "F.Fab")
			(hide yes)
			(effects
				(font
					(size 1.016 1.016)
					(thickness 0.1524)
				)
			)
		)
		(property "Device Type" "R402H16"
			(at 0.064008 -5.517896 180)
			(unlocked yes)
			(layer "F.Fab")
			(hide yes)
			(effects
				(font
					(size 1.016 1.016)
					(thickness 0.1524)
				)
			)
		)
		(duplicate_pad_numbers_are_jumpers no)
		(fp_line
			(start 0.508 -0.9398)
			(end -0.508 -0.9398)
			(stroke
				(width 0.1524)
				(type default)
			)
			(layer "F.SilkS")
		)
		(fp_line
			(start -0.508 -0.9398)
			(end -0.508 0.9398)
			(stroke
				(width 0.1524)
				(type default)
			)
			(layer "F.SilkS")
		)
		(fp_rect
			(start -0.508 0.9398)
			(end 0.508 -0.9398)
			(stroke
				(width 0)
				(type default)
			)
			(fill no)
			(layer "F.CrtYd")
		)
		(fp_rect
			(start -0.508 0.9398)
			(end 0.508 -0.9398)
			(stroke
				(width 0)
				(type default)
			)
			(fill no)
			(layer "F.Fab")
		)
		(pad "1" smd custom
			(at 0 -0.4445 180)
			(size 0.1397 0.1397)
			(layers "F.Cu" "F.Mask" "F.Paste")
			(net "IOM_IOC_UART_RX")
			(options
				(clearance outline)
				(anchor circle)
			)
			(primitives
				(gr_poly
					(pts
						(arc
							(start -0.1778 -0.2794)
							(mid -0.249642 -0.249642)
							(end -0.2794 -0.1778)
						)
						(arc
							(start -0.2794 0.1778)
							(mid -0.249642 0.249642)
							(end -0.1778 0.2794)
						)
						(arc
							(start 0.1778 0.2794)
							(mid 0.249642 0.249642)
							(end 0.2794 0.1778)
						)
						(arc
							(start 0.2794 -0.1778)
							(mid 0.249642 -0.249642)
							(end 0.1778 -0.2794)
						)
					)
					(width 0)
					(fill yes)
				)
			)
		)
		(pad "2" smd custom
			(at 0 0.4445 180)
			(size 0.1397 0.1397)
			(layers "F.Cu" "F.Mask" "F.Paste")
			(net "IOC_UART_R_RX")
			(options
				(clearance outline)
				(anchor circle)
			)
			(primitives
				(gr_poly
					(pts
						(arc
							(start -0.1778 -0.2794)
							(mid -0.249642 -0.249642)
							(end -0.2794 -0.1778)
						)
						(arc
							(start -0.2794 0.1778)
							(mid -0.249642 0.249642)
							(end -0.1778 0.2794)
						)
						(arc
							(start 0.1778 0.2794)
							(mid 0.249642 0.249642)
							(end 0.2794 0.1778)
						)
						(arc
							(start 0.2794 -0.1778)
							(mid 0.249642 -0.249642)
							(end 0.1778 -0.2794)
						)
					)
					(width 0)
					(fill yes)
				)
			)
		)
	)
	(footprint ""
		(layer "F.Cu")
		(at 76.4286 -143.3068 90)
		(property "Reference" "R130"
			(at 0 0 90)
			(layer "F.SilkS")
			(hide yes)
			(effects
				(font
					(size 1.27 1.27)
				)
			)
		)
		(property "Value" "0R2J-2-GP"
			(at 0.064008 -3.993896 90)
			(unlocked yes)
			(layer "F.Fab")
			(hide yes)
			(effects
				(font
					(size 1.016 1.016)
					(thickness 0.1524)
				)
			)
		)
		(property "Device Type" "R402H16"
			(at 0.064008 -5.517896 90)
			(unlocked yes)
			(layer "F.Fab")
			(hide yes)
			(effects
				(font
					(size 1.016 1.016)
					(thickness 0.1524)
				)
			)
		)
		(duplicate_pad_numbers_are_jumpers no)
		(fp_line
			(start 0.508 -0.9398)
			(end -0.508 -0.9398)
			(stroke
				(width 0.1524)
				(type default)
			)
			(layer "F.SilkS")
		)
		(fp_line
			(start -0.508 -0.9398)
			(end -0.508 0.9398)
			(stroke
				(width 0.1524)
				(type default)
			)
			(layer "F.SilkS")
		)
		(fp_rect
			(start -0.508 0.9398)
			(end 0.508 -0.9398)
			(stroke
				(width 0)
				(type default)
			)
			(fill no)
			(layer "F.CrtYd")
		)
		(fp_rect
			(start -0.508 0.9398)
			(end 0.508 -0.9398)
			(stroke
				(width 0)
				(type default)
			)
			(fill no)
			(layer "F.Fab")
		)
		(pad "1" smd custom
			(at 0 -0.4445 90)
			(size 0.1397 0.1397)
			(layers "F.Cu" "F.Mask" "F.Paste")
			(net "I2C_EXP_RMT_SDA")
			(options
				(clearance outline)
				(anchor circle)
			)
			(primitives
				(gr_poly
					(pts
						(arc
							(start -0.1778 -0.2794)
							(mid -0.249642 -0.249642)
							(end -0.2794 -0.1778)
						)
						(arc
							(start -0.2794 0.1778)
							(mid -0.249642 0.249642)
							(end -0.1778 0.2794)
						)
						(arc
							(start 0.1778 0.2794)
							(mid 0.249642 0.249642)
							(end 0.2794 0.1778)
						)
						(arc
							(start 0.2794 -0.1778)
							(mid 0.249642 -0.249642)
							(end 0.1778 -0.2794)
						)
					)
					(width 0)
					(fill yes)
				)
			)
		)
		(pad "2" smd custom
			(at 0 0.4445 90)
			(size 0.1397 0.1397)
			(layers "F.Cu" "F.Mask" "F.Paste")
			(net "I2C_EXP_RMT_SDA_R")
			(options
				(clearance outline)
				(anchor circle)
			)
			(primitives
				(gr_poly
					(pts
						(arc
							(start -0.1778 -0.2794)
							(mid -0.249642 -0.249642)
							(end -0.2794 -0.1778)
						)
						(arc
							(start -0.2794 0.1778)
							(mid -0.249642 0.249642)
							(end -0.1778 0.2794)
						)
						(arc
							(start 0.1778 0.2794)
							(mid 0.249642 0.249642)
							(end 0.2794 0.1778)
						)
						(arc
							(start 0.2794 -0.1778)
							(mid 0.249642 -0.249642)
							(end 0.1778 -0.2794)
						)
					)
					(width 0)
					(fill yes)
				)
			)
		)
	)
	(footprint ""
		(layer "F.Cu")
		(at 194.880738 -126.905258 180)
		(property "Reference" "C285"
			(at 0 0 180)
			(layer "F.SilkS")
			(hide yes)
			(effects
				(font
					(size 1.27 1.27)
				)
			)
		)
		(property "Value" "SCD1U50V3KX-GP"
			(at 0 -2.8194 180)
			(unlocked yes)
			(layer "F.Fab")
			(hide yes)
			(effects
				(font
					(size 1.016 1.016)
					(thickness 0.1524)
				)
			)
		)
		(property "Device Type" "C603H36"
			(at 0 -4.3434 180)
			(unlocked yes)
			(layer "F.Fab")
			(hide yes)
			(effects
				(font
					(size 1.016 1.016)
					(thickness 0.1524)
				)
			)
		)
		(duplicate_pad_numbers_are_jumpers no)
		(fp_line
			(start 0.508 0)
			(end -0.508 0)
			(stroke
				(width 0.2032)
				(type default)
			)
			(layer "F.SilkS")
		)
		(fp_rect
			(start -0.5842 1.3335)
			(end 0.5842 -1.3335)
			(stroke
				(width 0)
				(type default)
			)
			(fill no)
			(layer "F.CrtYd")
		)
		(fp_rect
			(start -0.5842 1.3335)
			(end 0.5842 -1.3335)
			(stroke
				(width 0)
				(type default)
			)
			(fill no)
			(layer "F.Fab")
		)
		(pad "1" smd custom
			(at 0 -0.762 180)
			(size 0.2159 0.2159)
			(layers "F.Cu" "F.Mask" "F.Paste")
			(net "VT235_VDES_RC")
			(options
				(clearance outline)
				(anchor circle)
			)
			(primitives
				(gr_poly
					(pts
						(arc
							(start -0.3302 -0.4318)
							(mid -0.402042 -0.402042)
							(end -0.4318 -0.3302)
						)
						(arc
							(start -0.4318 0.3302)
							(mid -0.402042 0.402042)
							(end -0.3302 0.4318)
						)
						(arc
							(start 0.3302 0.4318)
							(mid 0.402042 0.402042)
							(end 0.4318 0.3302)
						)
						(arc
							(start 0.4318 -0.3302)
							(mid 0.402042 -0.402042)
							(end 0.3302 -0.4318)
						)
					)
					(width 0)
					(fill yes)
				)
			)
		)
		(pad "2" smd custom
			(at 0 0.762 180)
			(size 0.2159 0.2159)
			(layers "F.Cu" "F.Mask" "F.Paste")
			(net "VT235_VDES_RCC")
			(options
				(clearance outline)
				(anchor circle)
			)
			(primitives
				(gr_poly
					(pts
						(arc
							(start -0.3302 -0.4318)
							(mid -0.402042 -0.402042)
							(end -0.4318 -0.3302)
						)
						(arc
							(start -0.4318 0.3302)
							(mid -0.402042 0.402042)
							(end -0.3302 0.4318)
						)
						(arc
							(start 0.3302 0.4318)
							(mid 0.402042 0.402042)
							(end 0.4318 0.3302)
						)
						(arc
							(start 0.4318 -0.3302)
							(mid 0.402042 -0.402042)
							(end 0.3302 -0.4318)
						)
					)
					(width 0)
					(fill yes)
				)
			)
		)
	)
	(footprint ""
		(layer "F.Cu")
		(at 39.0398 -158.623 180)
		(property "Reference" "R328"
			(at 0 0 180)
			(layer "F.SilkS")
			(hide yes)
			(effects
				(font
					(size 1.27 1.27)
				)
			)
		)
		(property "Value" "0R2J-2-GP"
			(at 0.064008 -3.993896 180)
			(unlocked yes)
			(layer "F.Fab")
			(hide yes)
			(effects
				(font
					(size 1.016 1.016)
					(thickness 0.1524)
				)
			)
		)
		(property "Device Type" "R402H16"
			(at 0.064008 -5.517896 180)
			(unlocked yes)
			(layer "F.Fab")
			(hide yes)
			(effects
				(font
					(size 1.016 1.016)
					(thickness 0.1524)
				)
			)
		)
		(duplicate_pad_numbers_are_jumpers no)
		(fp_line
			(start 0.508 -0.9398)
			(end -0.508 -0.9398)
			(stroke
				(width 0.1524)
				(type default)
			)
			(layer "F.SilkS")
		)
		(fp_line
			(start -0.508 -0.9398)
			(end -0.508 0.9398)
			(stroke
				(width 0.1524)
				(type default)
			)
			(layer "F.SilkS")
		)
		(fp_rect
			(start -0.508 0.9398)
			(end 0.508 -0.9398)
			(stroke
				(width 0)
				(type default)
			)
			(fill no)
			(layer "F.CrtYd")
		)
		(fp_rect
			(start -0.508 0.9398)
			(end 0.508 -0.9398)
			(stroke
				(width 0)
				(type default)
			)
			(fill no)
			(layer "F.Fab")
		)
		(pad "1" smd custom
			(at 0 -0.4445 180)
			(size 0.1397 0.1397)
			(layers "F.Cu" "F.Mask" "F.Paste")
			(net "UART_COMP_OUT_TX_R")
			(options
				(clearance outline)
				(anchor circle)
			)
			(primitives
				(gr_poly
					(pts
						(arc
							(start -0.1778 -0.2794)
							(mid -0.249642 -0.249642)
							(end -0.2794 -0.1778)
						)
						(arc
							(start -0.2794 0.1778)
							(mid -0.249642 0.249642)
							(end -0.1778 0.2794)
						)
						(arc
							(start 0.1778 0.2794)
							(mid 0.249642 0.249642)
							(end 0.2794 0.1778)
						)
						(arc
							(start 0.2794 -0.1778)
							(mid 0.249642 -0.249642)
							(end 0.1778 -0.2794)
						)
					)
					(width 0)
					(fill yes)
				)
			)
		)
		(pad "2" smd custom
			(at 0 0.4445 180)
			(size 0.1397 0.1397)
			(layers "F.Cu" "F.Mask" "F.Paste")
			(net "UART_COMP_OUT_TX")
			(options
				(clearance outline)
				(anchor circle)
			)
			(primitives
				(gr_poly
					(pts
						(arc
							(start -0.1778 -0.2794)
							(mid -0.249642 -0.249642)
							(end -0.2794 -0.1778)
						)
						(arc
							(start -0.2794 0.1778)
							(mid -0.249642 0.249642)
							(end -0.1778 0.2794)
						)
						(arc
							(start 0.1778 0.2794)
							(mid 0.249642 0.249642)
							(end 0.2794 0.1778)
						)
						(arc
							(start 0.2794 -0.1778)
							(mid 0.249642 -0.249642)
							(end 0.1778 -0.2794)
						)
					)
					(width 0)
					(fill yes)
				)
			)
		)
	)
	(footprint ""
		(layer "F.Cu")
		(at 213.2076 -120.777 90)
		(property "Reference" "C251"
			(at 0 0 90)
			(layer "F.SilkS")
			(hide yes)
			(effects
				(font
					(size 1.27 1.27)
				)
			)
		)
		(property "Value" "SCD1U16V2KX-3GP"
			(at 1.1811 -2.7051 90)
			(unlocked yes)
			(layer "F.Fab")
			(hide yes)
			(effects
				(font
					(size 1.016 1.016)
					(thickness 0.1524)
				)
			)
		)
		(property "Device Type" "C402H22"
			(at 1.1811 -4.2291 90)
			(unlocked yes)
			(layer "F.Fab")
			(hide yes)
			(effects
				(font
					(size 1.016 1.016)
					(thickness 0.1524)
				)
			)
		)
		(duplicate_pad_numbers_are_jumpers no)
		(fp_rect
			(start -0.4318 0.9525)
			(end 0.4318 -0.9525)
			(stroke
				(width 0)
				(type default)
			)
			(fill no)
			(layer "F.CrtYd")
		)
		(fp_rect
			(start -0.4318 0.9525)
			(end 0.4318 -0.9525)
			(stroke
				(width 0)
				(type default)
			)
			(fill no)
			(layer "F.Fab")
		)
		(pad "1" smd custom
			(at 0 -0.4445 90)
			(size 0.1524 0.1524)
			(layers "F.Cu" "F.Mask" "F.Paste")
			(net "P1V5_OUT")
			(options
				(clearance outline)
				(anchor circle)
			)
			(primitives
				(gr_poly
					(pts
						(arc
							(start 0.3048 -0.2032)
							(mid 0.275042 -0.275042)
							(end 0.2032 -0.3048)
						)
						(arc
							(start -0.2032 -0.3048)
							(mid -0.275042 -0.275042)
							(end -0.3048 -0.2032)
						)
						(arc
							(start -0.3048 0.2032)
							(mid -0.275042 0.275042)
							(end -0.2032 0.3048)
						)
						(arc
							(start 0.2032 0.3048)
							(mid 0.275042 0.275042)
							(end 0.3048 0.2032)
						)
					)
					(width 0)
					(fill yes)
				)
			)
		)
		(pad "2" smd custom
			(at 0 0.4445 90)
			(size 0.1524 0.1524)
			(layers "F.Cu" "F.Mask" "F.Paste")
			(net "GND")
			(options
				(clearance outline)
				(anchor circle)
			)
			(primitives
				(gr_poly
					(pts
						(arc
							(start 0.3048 -0.2032)
							(mid 0.275042 -0.275042)
							(end 0.2032 -0.3048)
						)
						(arc
							(start -0.2032 -0.3048)
							(mid -0.275042 -0.275042)
							(end -0.3048 -0.2032)
						)
						(arc
							(start -0.3048 0.2032)
							(mid -0.275042 0.275042)
							(end -0.2032 0.3048)
						)
						(arc
							(start 0.2032 0.3048)
							(mid 0.275042 0.275042)
							(end 0.3048 0.2032)
						)
					)
					(width 0)
					(fill yes)
				)
			)
		)
	)
	(footprint ""
		(layer "F.Cu")
		(at 43.3578 -131.7498 180)
		(property "Reference" "R262"
			(at 0 0 180)
			(layer "F.SilkS")
			(hide yes)
			(effects
				(font
					(size 1.27 1.27)
				)
			)
		)
		(property "Value" "4K7R2F-GP"
			(at 0.064008 -3.993896 180)
			(unlocked yes)
			(layer "F.Fab")
			(hide yes)
			(effects
				(font
					(size 1.016 1.016)
					(thickness 0.1524)
				)
			)
		)
		(property "Device Type" "R402H16"
			(at 0.064008 -5.517896 180)
			(unlocked yes)
			(layer "F.Fab")
			(hide yes)
			(effects
				(font
					(size 1.016 1.016)
					(thickness 0.1524)
				)
			)
		)
		(duplicate_pad_numbers_are_jumpers no)
		(fp_line
			(start 0.508 -0.9398)
			(end -0.508 -0.9398)
			(stroke
				(width 0.1524)
				(type default)
			)
			(layer "F.SilkS")
		)
		(fp_line
			(start -0.508 -0.9398)
			(end -0.508 0.9398)
			(stroke
				(width 0.1524)
				(type default)
			)
			(layer "F.SilkS")
		)
		(fp_rect
			(start -0.508 0.9398)
			(end 0.508 -0.9398)
			(stroke
				(width 0)
				(type default)
			)
			(fill no)
			(layer "F.CrtYd")
		)
		(fp_rect
			(start -0.508 0.9398)
			(end 0.508 -0.9398)
			(stroke
				(width 0)
				(type default)
			)
			(fill no)
			(layer "F.Fab")
		)
		(pad "1" smd custom
			(at 0 -0.4445 180)
			(size 0.1397 0.1397)
			(layers "F.Cu" "F.Mask" "F.Paste")
			(net "P3V3_STBY")
			(options
				(clearance outline)
				(anchor circle)
			)
			(primitives
				(gr_poly
					(pts
						(arc
							(start -0.1778 -0.2794)
							(mid -0.249642 -0.249642)
							(end -0.2794 -0.1778)
						)
						(arc
							(start -0.2794 0.1778)
							(mid -0.249642 0.249642)
							(end -0.1778 0.2794)
						)
						(arc
							(start 0.1778 0.2794)
							(mid 0.249642 0.249642)
							(end 0.2794 0.1778)
						)
						(arc
							(start 0.2794 -0.1778)
							(mid 0.249642 -0.249642)
							(end 0.1778 -0.2794)
						)
					)
					(width 0)
					(fill yes)
				)
			)
		)
		(pad "2" smd custom
			(at 0 0.4445 180)
			(size 0.1397 0.1397)
			(layers "F.Cu" "F.Mask" "F.Paste")
			(net "BMC_GPIOY0")
			(options
				(clearance outline)
				(anchor circle)
			)
			(primitives
				(gr_poly
					(pts
						(arc
							(start -0.1778 -0.2794)
							(mid -0.249642 -0.249642)
							(end -0.2794 -0.1778)
						)
						(arc
							(start -0.2794 0.1778)
							(mid -0.249642 0.249642)
							(end -0.1778 0.2794)
						)
						(arc
							(start 0.1778 0.2794)
							(mid 0.249642 0.249642)
							(end 0.2794 0.1778)
						)
						(arc
							(start 0.2794 -0.1778)
							(mid 0.249642 -0.249642)
							(end 0.1778 -0.2794)
						)
					)
					(width 0)
					(fill yes)
				)
			)
		)
	)
	(footprint ""
		(layer "F.Cu")
		(at 36.0934 -132.4864)
		(property "Reference" "R312"
			(at 0 0 0)
			(layer "F.SilkS")
			(hide yes)
			(effects
				(font
					(size 1.27 1.27)
				)
			)
		)
		(property "Value" "0R2J-2-GP"
			(at 0.064008 -3.993896 0)
			(unlocked yes)
			(layer "F.Fab")
			(hide yes)
			(effects
				(font
					(size 1.016 1.016)
					(thickness 0.1524)
				)
			)
		)
		(property "Device Type" "R402H16"
			(at 0.064008 -5.517896 0)
			(unlocked yes)
			(layer "F.Fab")
			(hide yes)
			(effects
				(font
					(size 1.016 1.016)
					(thickness 0.1524)
				)
			)
		)
		(duplicate_pad_numbers_are_jumpers no)
		(fp_line
			(start -0.508 -0.9398)
			(end -0.508 0.9398)
			(stroke
				(width 0.1524)
				(type default)
			)
			(layer "F.SilkS")
		)
		(fp_line
			(start 0.508 -0.9398)
			(end -0.508 -0.9398)
			(stroke
				(width 0.1524)
				(type default)
			)
			(layer "F.SilkS")
		)
		(fp_rect
			(start -0.508 0.9398)
			(end 0.508 -0.9398)
			(stroke
				(width 0)
				(type default)
			)
			(fill no)
			(layer "F.CrtYd")
		)
		(fp_rect
			(start -0.508 0.9398)
			(end 0.508 -0.9398)
			(stroke
				(width 0)
				(type default)
			)
			(fill no)
			(layer "F.Fab")
		)
		(pad "1" smd custom
			(at 0 -0.4445)
			(size 0.1397 0.1397)
			(layers "F.Cu" "F.Mask" "F.Paste")
			(net "CLKIN_24M_BMC")
			(options
				(clearance outline)
				(anchor circle)
			)
			(primitives
				(gr_poly
					(pts
						(arc
							(start -0.1778 -0.2794)
							(mid -0.249642 -0.249642)
							(end -0.2794 -0.1778)
						)
						(arc
							(start -0.2794 0.1778)
							(mid -0.249642 0.249642)
							(end -0.1778 0.2794)
						)
						(arc
							(start 0.1778 0.2794)
							(mid 0.249642 0.249642)
							(end 0.2794 0.1778)
						)
						(arc
							(start 0.2794 -0.1778)
							(mid 0.249642 -0.249642)
							(end 0.1778 -0.2794)
						)
					)
					(width 0)
					(fill yes)
				)
			)
		)
		(pad "2" smd custom
			(at 0 0.4445)
			(size 0.1397 0.1397)
			(layers "F.Cu" "F.Mask" "F.Paste")
			(net "OSC_OUT")
			(options
				(clearance outline)
				(anchor circle)
			)
			(primitives
				(gr_poly
					(pts
						(arc
							(start -0.1778 -0.2794)
							(mid -0.249642 -0.249642)
							(end -0.2794 -0.1778)
						)
						(arc
							(start -0.2794 0.1778)
							(mid -0.249642 0.249642)
							(end -0.1778 0.2794)
						)
						(arc
							(start 0.1778 0.2794)
							(mid 0.249642 0.249642)
							(end 0.2794 0.1778)
						)
						(arc
							(start 0.2794 -0.1778)
							(mid 0.249642 -0.249642)
							(end 0.1778 -0.2794)
						)
					)
					(width 0)
					(fill yes)
				)
			)
		)
	)
	(footprint ""
		(layer "F.Cu")
		(at 77.2922 -150.3426 180)
		(property "Reference" "R717"
			(at 0 0 180)
			(layer "F.SilkS")
			(hide yes)
			(effects
				(font
					(size 1.27 1.27)
				)
			)
		)
		(property "Value" "0R2J-2-GP"
			(at 0.064008 -3.993896 180)
			(unlocked yes)
			(layer "F.Fab")
			(hide yes)
			(effects
				(font
					(size 1.016 1.016)
					(thickness 0.1524)
				)
			)
		)
		(property "Device Type" "R402H16"
			(at 0.064008 -5.517896 180)
			(unlocked yes)
			(layer "F.Fab")
			(hide yes)
			(effects
				(font
					(size 1.016 1.016)
					(thickness 0.1524)
				)
			)
		)
		(duplicate_pad_numbers_are_jumpers no)
		(fp_line
			(start 0.508 -0.9398)
			(end -0.508 -0.9398)
			(stroke
				(width 0.1524)
				(type default)
			)
			(layer "F.SilkS")
		)
		(fp_line
			(start -0.508 -0.9398)
			(end -0.508 0.9398)
			(stroke
				(width 0.1524)
				(type default)
			)
			(layer "F.SilkS")
		)
		(fp_rect
			(start -0.508 0.9398)
			(end 0.508 -0.9398)
			(stroke
				(width 0)
				(type default)
			)
			(fill no)
			(layer "F.CrtYd")
		)
		(fp_rect
			(start -0.508 0.9398)
			(end 0.508 -0.9398)
			(stroke
				(width 0)
				(type default)
			)
			(fill no)
			(layer "F.Fab")
		)
		(pad "1" smd custom
			(at 0 -0.4445 180)
			(size 0.1397 0.1397)
			(layers "F.Cu" "F.Mask" "F.Paste")
			(net "COMP_TO_BMC_RESET_R")
			(options
				(clearance outline)
				(anchor circle)
			)
			(primitives
				(gr_poly
					(pts
						(arc
							(start -0.1778 -0.2794)
							(mid -0.249642 -0.249642)
							(end -0.2794 -0.1778)
						)
						(arc
							(start -0.2794 0.1778)
							(mid -0.249642 0.249642)
							(end -0.1778 0.2794)
						)
						(arc
							(start 0.1778 0.2794)
							(mid 0.249642 0.249642)
							(end 0.2794 0.1778)
						)
						(arc
							(start 0.2794 -0.1778)
							(mid 0.249642 -0.249642)
							(end 0.1778 -0.2794)
						)
					)
					(width 0)
					(fill yes)
				)
			)
		)
		(pad "2" smd custom
			(at 0 0.4445 180)
			(size 0.1397 0.1397)
			(layers "F.Cu" "F.Mask" "F.Paste")
			(net "COMP_TO_BMC_RESET")
			(options
				(clearance outline)
				(anchor circle)
			)
			(primitives
				(gr_poly
					(pts
						(arc
							(start -0.1778 -0.2794)
							(mid -0.249642 -0.249642)
							(end -0.2794 -0.1778)
						)
						(arc
							(start -0.2794 0.1778)
							(mid -0.249642 0.249642)
							(end -0.1778 0.2794)
						)
						(arc
							(start 0.1778 0.2794)
							(mid 0.249642 0.249642)
							(end 0.2794 0.1778)
						)
						(arc
							(start 0.2794 -0.1778)
							(mid 0.249642 -0.249642)
							(end 0.1778 -0.2794)
						)
					)
					(width 0)
					(fill yes)
				)
			)
		)
	)
	(footprint ""
		(layer "F.Cu")
		(at 180.6321 -48.1457)
		(property "Reference" "R672"
			(at 0 0 0)
			(layer "F.SilkS")
			(hide yes)
			(effects
				(font
					(size 1.27 1.27)
				)
			)
		)
		(property "Value" "10KR2F-2-GP"
			(at 0.064008 -3.993896 0)
			(unlocked yes)
			(layer "F.Fab")
			(hide yes)
			(effects
				(font
					(size 1.016 1.016)
					(thickness 0.1524)
				)
			)
		)
		(property "Device Type" "R402H16"
			(at 0.064008 -5.517896 0)
			(unlocked yes)
			(layer "F.Fab")
			(hide yes)
			(effects
				(font
					(size 1.016 1.016)
					(thickness 0.1524)
				)
			)
		)
		(duplicate_pad_numbers_are_jumpers no)
		(fp_line
			(start -0.508 -0.9398)
			(end -0.508 0.9398)
			(stroke
				(width 0.1524)
				(type default)
			)
			(layer "F.SilkS")
		)
		(fp_line
			(start 0.508 -0.9398)
			(end -0.508 -0.9398)
			(stroke
				(width 0.1524)
				(type default)
			)
			(layer "F.SilkS")
		)
		(fp_rect
			(start -0.508 0.9398)
			(end 0.508 -0.9398)
			(stroke
				(width 0)
				(type default)
			)
			(fill no)
			(layer "F.CrtYd")
		)
		(fp_rect
			(start -0.508 0.9398)
			(end 0.508 -0.9398)
			(stroke
				(width 0)
				(type default)
			)
			(fill no)
			(layer "F.Fab")
		)
		(pad "1" smd custom
			(at 0 -0.4445)
			(size 0.1397 0.1397)
			(layers "F.Cu" "F.Mask" "F.Paste")
			(net "XM_ADDR_6")
			(options
				(clearance outline)
				(anchor circle)
			)
			(primitives
				(gr_poly
					(pts
						(arc
							(start -0.1778 -0.2794)
							(mid -0.249642 -0.249642)
							(end -0.2794 -0.1778)
						)
						(arc
							(start -0.2794 0.1778)
							(mid -0.249642 0.249642)
							(end -0.1778 0.2794)
						)
						(arc
							(start 0.1778 0.2794)
							(mid 0.249642 0.249642)
							(end 0.2794 0.1778)
						)
						(arc
							(start 0.2794 -0.1778)
							(mid 0.249642 -0.249642)
							(end 0.1778 -0.2794)
						)
					)
					(width 0)
					(fill yes)
				)
			)
		)
		(pad "2" smd custom
			(at 0 0.4445)
			(size 0.1397 0.1397)
			(layers "F.Cu" "F.Mask" "F.Paste")
			(net "GND")
			(options
				(clearance outline)
				(anchor circle)
			)
			(primitives
				(gr_poly
					(pts
						(arc
							(start -0.1778 -0.2794)
							(mid -0.249642 -0.249642)
							(end -0.2794 -0.1778)
						)
						(arc
							(start -0.2794 0.1778)
							(mid -0.249642 0.249642)
							(end -0.1778 0.2794)
						)
						(arc
							(start 0.1778 0.2794)
							(mid 0.249642 0.249642)
							(end 0.2794 0.1778)
						)
						(arc
							(start 0.2794 -0.1778)
							(mid 0.249642 -0.249642)
							(end 0.1778 -0.2794)
						)
					)
					(width 0)
					(fill yes)
				)
			)
		)
	)
	(footprint ""
		(layer "F.Cu")
		(at 50.17897 -161.279078)
		(property "Reference" "R400"
			(at 0 0 0)
			(layer "F.SilkS")
			(hide yes)
			(effects
				(font
					(size 1.27 1.27)
				)
			)
		)
		(property "Value" "4K7R2F-GP"
			(at 0.064008 -3.993896 0)
			(unlocked yes)
			(layer "F.Fab")
			(hide yes)
			(effects
				(font
					(size 1.016 1.016)
					(thickness 0.1524)
				)
			)
		)
		(property "Device Type" "R402H16"
			(at 0.064008 -5.517896 0)
			(unlocked yes)
			(layer "F.Fab")
			(hide yes)
			(effects
				(font
					(size 1.016 1.016)
					(thickness 0.1524)
				)
			)
		)
		(duplicate_pad_numbers_are_jumpers no)
		(fp_line
			(start -0.508 -0.9398)
			(end -0.508 0.9398)
			(stroke
				(width 0.1524)
				(type default)
			)
			(layer "F.SilkS")
		)
		(fp_line
			(start 0.508 -0.9398)
			(end -0.508 -0.9398)
			(stroke
				(width 0.1524)
				(type default)
			)
			(layer "F.SilkS")
		)
		(fp_rect
			(start -0.508 0.9398)
			(end 0.508 -0.9398)
			(stroke
				(width 0)
				(type default)
			)
			(fill no)
			(layer "F.CrtYd")
		)
		(fp_rect
			(start -0.508 0.9398)
			(end 0.508 -0.9398)
			(stroke
				(width 0)
				(type default)
			)
			(fill no)
			(layer "F.Fab")
		)
		(pad "1" smd custom
			(at 0 -0.4445)
			(size 0.1397 0.1397)
			(layers "F.Cu" "F.Mask" "F.Paste")
			(net "GND")
			(options
				(clearance outline)
				(anchor circle)
			)
			(primitives
				(gr_poly
					(pts
						(arc
							(start -0.1778 -0.2794)
							(mid -0.249642 -0.249642)
							(end -0.2794 -0.1778)
						)
						(arc
							(start -0.2794 0.1778)
							(mid -0.249642 0.249642)
							(end -0.1778 0.2794)
						)
						(arc
							(start 0.1778 0.2794)
							(mid 0.249642 0.249642)
							(end 0.2794 0.1778)
						)
						(arc
							(start 0.2794 -0.1778)
							(mid 0.249642 -0.249642)
							(end 0.1778 -0.2794)
						)
					)
					(width 0)
					(fill yes)
				)
			)
		)
		(pad "2" smd custom
			(at 0 0.4445)
			(size 0.1397 0.1397)
			(layers "F.Cu" "F.Mask" "F.Paste")
			(net "UART_BMC_TX")
			(options
				(clearance outline)
				(anchor circle)
			)
			(primitives
				(gr_poly
					(pts
						(arc
							(start -0.1778 -0.2794)
							(mid -0.249642 -0.249642)
							(end -0.2794 -0.1778)
						)
						(arc
							(start -0.2794 0.1778)
							(mid -0.249642 0.249642)
							(end -0.1778 0.2794)
						)
						(arc
							(start 0.1778 0.2794)
							(mid 0.249642 0.249642)
							(end 0.2794 0.1778)
						)
						(arc
							(start 0.2794 -0.1778)
							(mid 0.249642 -0.249642)
							(end 0.1778 -0.2794)
						)
					)
					(width 0)
					(fill yes)
				)
			)
		)
	)
	(footprint ""
		(layer "F.Cu")
		(at 208.5467 -132.957316 180)
		(property "Reference" "C255"
			(at 0 0 180)
			(layer "F.SilkS")
			(hide yes)
			(effects
				(font
					(size 1.27 1.27)
				)
			)
		)
		(property "Value" "SC10U6D3V5KX-4GP"
			(at -0.0762 -6.1214 180)
			(unlocked yes)
			(layer "F.Fab")
			(hide yes)
			(effects
				(font
					(size 1.016 1.016)
					(thickness 0.1524)
				)
			)
		)
		(property "Device Type" "C805H58"
			(at -0.0762 -8.1534 180)
			(unlocked yes)
			(layer "F.Fab")
			(hide yes)
			(effects
				(font
					(size 1.016 1.016)
					(thickness 0.1524)
				)
			)
		)
		(duplicate_pad_numbers_are_jumpers no)
		(fp_line
			(start 0.635 0)
			(end -0.635 0)
			(stroke
				(width 0.508)
				(type default)
			)
			(layer "F.SilkS")
		)
		(fp_rect
			(start -0.9652 1.778)
			(end 0.9652 -1.778)
			(stroke
				(width 0)
				(type default)
			)
			(fill no)
			(layer "F.CrtYd")
		)
		(fp_poly
			(pts
				(xy -0.9652 -1.778) (xy 0.9652 -1.778) (xy 0.9652 1.778) (xy -0.9652 1.778)
			)
			(stroke
				(width 0)
				(type default)
			)
			(fill no)
			(layer "F.Fab")
		)
		(pad "1" smd rect
			(at 0 -0.9652 180)
			(size 1.397 1.143)
			(layers "F.Cu" "F.Mask" "F.Paste")
			(net "P1V8_STBY")
		)
		(pad "2" smd rect
			(at 0 0.9652 180)
			(size 1.397 1.143)
			(layers "F.Cu" "F.Mask" "F.Paste")
			(net "GND")
		)
	)
	(footprint ""
		(layer "F.Cu")
		(at 202.698096 -10.668 -90)
		(property "Reference" "R817"
			(at 0 0 270)
			(layer "F.SilkS")
			(hide yes)
			(effects
				(font
					(size 1.27 1.27)
				)
			)
		)
		(property "Value" "130R3F-GP"
			(at -0.0254 -2.5146 270)
			(unlocked yes)
			(layer "F.Fab")
			(hide yes)
			(effects
				(font
					(size 1.016 1.016)
					(thickness 0.1524)
				)
			)
		)
		(property "Device Type" "R603H22"
			(at -0.0254 -4.0386 270)
			(unlocked yes)
			(layer "F.Fab")
			(hide yes)
			(effects
				(font
					(size 1.016 1.016)
					(thickness 0.1524)
				)
			)
		)
		(duplicate_pad_numbers_are_jumpers no)
		(fp_line
			(start -0.4826 0)
			(end -0.2032 0)
			(stroke
				(width 0.2032)
				(type default)
			)
			(layer "F.SilkS")
		)
		(fp_line
			(start 0.2032 0)
			(end 0.4826 0)
			(stroke
				(width 0.2032)
				(type default)
			)
			(layer "F.SilkS")
		)
		(fp_rect
			(start -0.5842 1.3335)
			(end 0.5842 -1.3335)
			(stroke
				(width 0)
				(type default)
			)
			(fill no)
			(layer "F.CrtYd")
		)
		(fp_rect
			(start -0.5842 1.3335)
			(end 0.5842 -1.3335)
			(stroke
				(width 0)
				(type default)
			)
			(fill no)
			(layer "F.Fab")
		)
		(pad "1" smd custom
			(at 0 -0.762 270)
			(size 0.2159 0.2159)
			(layers "F.Cu" "F.Mask" "F.Paste")
			(net "ML_PWR_BLUE_LED_R")
			(options
				(clearance outline)
				(anchor circle)
			)
			(primitives
				(gr_poly
					(pts
						(arc
							(start -0.3302 -0.4318)
							(mid -0.402042 -0.402042)
							(end -0.4318 -0.3302)
						)
						(arc
							(start -0.4318 0.3302)
							(mid -0.402042 0.402042)
							(end -0.3302 0.4318)
						)
						(arc
							(start 0.3302 0.4318)
							(mid 0.402042 0.402042)
							(end 0.4318 0.3302)
						)
						(arc
							(start 0.4318 -0.3302)
							(mid 0.402042 -0.402042)
							(end 0.3302 -0.4318)
						)
					)
					(width 0)
					(fill yes)
				)
			)
		)
		(pad "2" smd custom
			(at 0 0.762 270)
			(size 0.2159 0.2159)
			(layers "F.Cu" "F.Mask" "F.Paste")
			(net "ML_PWR_BLUE_LED")
			(options
				(clearance outline)
				(anchor circle)
			)
			(primitives
				(gr_poly
					(pts
						(arc
							(start -0.3302 -0.4318)
							(mid -0.402042 -0.402042)
							(end -0.4318 -0.3302)
						)
						(arc
							(start -0.4318 0.3302)
							(mid -0.402042 0.402042)
							(end -0.3302 0.4318)
						)
						(arc
							(start 0.3302 0.4318)
							(mid 0.402042 0.402042)
							(end 0.4318 0.3302)
						)
						(arc
							(start 0.4318 -0.3302)
							(mid 0.402042 -0.402042)
							(end 0.3302 -0.4318)
						)
					)
					(width 0)
					(fill yes)
				)
			)
		)
	)
	(footprint ""
		(layer "F.Cu")
		(at 156.5402 -38.4556)
		(property "Reference" "TP179"
			(at 0 0 0)
			(layer "F.SilkS")
			(hide yes)
			(effects
				(font
					(size 1.27 1.27)
				)
			)
		)
		(property "Value" "TPAD28-2-GP"
			(at -0.0127 -1.6637 0)
			(unlocked yes)
			(layer "F.Fab")
			(hide yes)
			(effects
				(font
					(size 1.016 1.016)
					(thickness 0.1524)
				)
			)
		)
		(property "Device Type" "TPAD28"
			(at -0.0127 -3.1877 0)
			(unlocked yes)
			(layer "F.Fab")
			(hide yes)
			(effects
				(font
					(size 1.016 1.016)
					(thickness 0.1524)
				)
			)
		)
		(duplicate_pad_numbers_are_jumpers no)
		(fp_poly
			(pts
				(arc
					(start 0.3556 0)
					(mid -0.3556 0)
					(end 0.3556 0)
				)
			)
			(stroke
				(width 0)
				(type default)
			)
			(fill no)
			(layer "F.CrtYd")
		)
		(fp_poly
			(pts
				(arc
					(start 0.6096 0)
					(mid -0.6096 0)
					(end 0.6096 0)
				)
			)
			(stroke
				(width 0)
				(type default)
			)
			(fill no)
			(layer "F.Fab")
		)
		(pad "1" smd circle
			(at 0 0)
			(size 0.7112 0.7112)
			(layers "F.Cu" "F.Mask" "F.Paste")
			(net "ZDEF_EXTB_TP_C1")
		)
	)
	(footprint ""
		(layer "F.Cu")
		(at 226.983036 -96.814386)
		(property "Reference" "L21"
			(at 0 0 0)
			(layer "F.SilkS")
			(hide yes)
			(effects
				(font
					(size 1.27 1.27)
				)
			)
		)
		(property "Value" "28F0181-1SR-10-GP"
			(at -4.064 -3.5052 0)
			(unlocked yes)
			(layer "F.Fab")
			(hide yes)
			(effects
				(font
					(size 1.016 1.016)
					(thickness 0.1524)
				)
			)
		)
		(property "Device Type" "L9546-152127H121"
			(at -4.064 -5.0292 0)
			(unlocked yes)
			(layer "F.Fab")
			(hide yes)
			(effects
				(font
					(size 1.016 1.016)
					(thickness 0.1524)
				)
			)
		)
		(duplicate_pad_numbers_are_jumpers no)
		(fp_line
			(start -2.54 -5.6642)
			(end -2.54 5.6642)
			(stroke
				(width 0.1524)
				(type default)
			)
			(layer "F.SilkS")
		)
		(fp_line
			(start -2.54 5.6642)
			(end 2.54 5.6642)
			(stroke
				(width 0.1524)
				(type default)
			)
			(layer "F.SilkS")
		)
		(fp_line
			(start 2.54 -5.6642)
			(end -2.54 -5.6642)
			(stroke
				(width 0.1524)
				(type default)
			)
			(layer "F.SilkS")
		)
		(fp_line
			(start 2.54 5.6642)
			(end 2.54 -5.6642)
			(stroke
				(width 0.1524)
				(type default)
			)
			(layer "F.SilkS")
		)
		(fp_rect
			(start -2.286 4.7625)
			(end 2.286 -4.7625)
			(stroke
				(width 0)
				(type default)
			)
			(fill no)
			(layer "F.CrtYd")
		)
		(fp_poly
			(pts
				(xy -2.794 5.7404) (xy -2.794 -5.7404) (xy 2.794 -5.7404) (xy 2.794 5.7404) (xy 0.00254 5.7404)
				(xy 0.00254 4.7625) (xy 2.286 4.7625) (xy 2.286 -4.7625) (xy -2.286 -4.7625) (xy -2.286 4.7625)
				(xy -0.00254 4.7625) (xy -0.00254 5.7404)
			)
			(stroke
				(width 0)
				(type default)
			)
			(fill no)
			(layer "F.CrtYd")
		)
		(fp_rect
			(start -2.794 5.7404)
			(end 2.794 -5.7404)
			(stroke
				(width 0)
				(type default)
			)
			(fill no)
			(layer "F.Fab")
		)
		(pad "1" smd rect
			(at 0 -4.197604)
			(size 1.524 2.413)
			(layers "F.Cu" "F.Mask" "F.Paste")
			(net "P0V975")
		)
		(pad "2" smd rect
			(at 0 4.197604)
			(size 1.524 2.413)
			(layers "F.Cu" "F.Mask" "F.Paste")
			(net "SAS0_AVDD")
		)
	)
	(footprint ""
		(layer "F.Cu")
		(at 132.08 -27.6098)
		(property "Reference" "TP1"
			(at 0 0 0)
			(layer "F.SilkS")
			(hide yes)
			(effects
				(font
					(size 1.27 1.27)
				)
			)
		)
		(property "Value" "TPAD28-2-GP"
			(at -0.0127 -1.6637 0)
			(unlocked yes)
			(layer "F.Fab")
			(hide yes)
			(effects
				(font
					(size 1.016 1.016)
					(thickness 0.1524)
				)
			)
		)
		(property "Device Type" "TPAD28"
			(at -0.0127 -3.1877 0)
			(unlocked yes)
			(layer "F.Fab")
			(hide yes)
			(effects
				(font
					(size 1.016 1.016)
					(thickness 0.1524)
				)
			)
		)
		(duplicate_pad_numbers_are_jumpers no)
		(fp_poly
			(pts
				(arc
					(start 0.3556 0)
					(mid -0.3556 0)
					(end 0.3556 0)
				)
			)
			(stroke
				(width 0)
				(type default)
			)
			(fill no)
			(layer "F.CrtYd")
		)
		(fp_poly
			(pts
				(arc
					(start 0.6096 0)
					(mid -0.6096 0)
					(end 0.6096 0)
				)
			)
			(stroke
				(width 0)
				(type default)
			)
			(fill no)
			(layer "F.Fab")
		)
		(pad "1" smd circle
			(at 0 0)
			(size 0.7112 0.7112)
			(layers "F.Cu" "F.Mask" "F.Paste")
			(net "PCIE_COMP_TO_IOM_CLK_3_DN")
		)
	)
	(footprint ""
		(layer "F.Cu")
		(at 168.6306 -103.9876 -90)
		(property "Reference" "C461"
			(at 0 0 270)
			(layer "F.SilkS")
			(hide yes)
			(effects
				(font
					(size 1.27 1.27)
				)
			)
		)
		(property "Value" "SC1U16V2KX-7-GP"
			(at 1.7526 -1.6002 270)
			(unlocked yes)
			(layer "F.Fab")
			(hide yes)
			(effects
				(font
					(size 1.016 1.016)
					(thickness 0.1524)
				)
			)
		)
		(property "Device Type" "C402-TO0D2H24"
			(at 1.7526 -3.1242 270)
			(unlocked yes)
			(layer "F.Fab")
			(hide yes)
			(effects
				(font
					(size 1.016 1.016)
					(thickness 0.1524)
				)
			)
		)
		(duplicate_pad_numbers_are_jumpers no)
		(fp_rect
			(start -0.4826 0.889)
			(end 0.4826 -0.889)
			(stroke
				(width 0)
				(type default)
			)
			(fill no)
			(layer "F.CrtYd")
		)
		(fp_rect
			(start -0.4826 0.889)
			(end 0.4826 -0.889)
			(stroke
				(width 0)
				(type default)
			)
			(fill no)
			(layer "F.Fab")
		)
		(pad "1" smd custom
			(at 0 -0.4572 270)
			(size 0.1524 0.1524)
			(layers "F.Cu" "F.Mask" "F.Paste")
			(net "P1V8")
			(options
				(clearance outline)
				(anchor circle)
			)
			(primitives
				(gr_poly
					(pts
						(arc
							(start -0.254 0.3048)
							(mid -0.325842 0.275042)
							(end -0.3556 0.2032)
						)
						(arc
							(start -0.3556 -0.2032)
							(mid -0.325842 -0.275042)
							(end -0.254 -0.3048)
						)
						(arc
							(start 0.254 -0.3048)
							(mid 0.325842 -0.275042)
							(end 0.3556 -0.2032)
						)
						(arc
							(start 0.3556 0.2032)
							(mid 0.325842 0.275042)
							(end 0.254 0.3048)
						)
					)
					(width 0)
					(fill yes)
				)
			)
		)
		(pad "2" smd custom
			(at 0 0.4572 270)
			(size 0.1524 0.1524)
			(layers "F.Cu" "F.Mask" "F.Paste")
			(net "GND")
			(options
				(clearance outline)
				(anchor circle)
			)
			(primitives
				(gr_poly
					(pts
						(arc
							(start -0.254 0.3048)
							(mid -0.325842 0.275042)
							(end -0.3556 0.2032)
						)
						(arc
							(start -0.3556 -0.2032)
							(mid -0.325842 -0.275042)
							(end -0.254 -0.3048)
						)
						(arc
							(start 0.254 -0.3048)
							(mid 0.325842 -0.275042)
							(end 0.3556 -0.2032)
						)
						(arc
							(start 0.3556 0.2032)
							(mid 0.325842 0.275042)
							(end 0.254 0.3048)
						)
					)
					(width 0)
					(fill yes)
				)
			)
		)
	)
	(footprint ""
		(layer "F.Cu")
		(at 38.128448 -130.758692 180)
		(property "Reference" "R377"
			(at 0 0 180)
			(layer "F.SilkS")
			(hide yes)
			(effects
				(font
					(size 1.27 1.27)
				)
			)
		)
		(property "Value" "4K7R2F-GP"
			(at 0.064008 -3.993896 180)
			(unlocked yes)
			(layer "F.Fab")
			(hide yes)
			(effects
				(font
					(size 1.016 1.016)
					(thickness 0.1524)
				)
			)
		)
		(property "Device Type" "R402H16"
			(at 0.064008 -5.517896 180)
			(unlocked yes)
			(layer "F.Fab")
			(hide yes)
			(effects
				(font
					(size 1.016 1.016)
					(thickness 0.1524)
				)
			)
		)
		(duplicate_pad_numbers_are_jumpers no)
		(fp_line
			(start 0.508 -0.9398)
			(end -0.508 -0.9398)
			(stroke
				(width 0.1524)
				(type default)
			)
			(layer "F.SilkS")
		)
		(fp_line
			(start -0.508 -0.9398)
			(end -0.508 0.9398)
			(stroke
				(width 0.1524)
				(type default)
			)
			(layer "F.SilkS")
		)
		(fp_rect
			(start -0.508 0.9398)
			(end 0.508 -0.9398)
			(stroke
				(width 0)
				(type default)
			)
			(fill no)
			(layer "F.CrtYd")
		)
		(fp_rect
			(start -0.508 0.9398)
			(end 0.508 -0.9398)
			(stroke
				(width 0)
				(type default)
			)
			(fill no)
			(layer "F.Fab")
		)
		(pad "1" smd custom
			(at 0 -0.4445 180)
			(size 0.1397 0.1397)
			(layers "F.Cu" "F.Mask" "F.Paste")
			(net "P3V3_STBY")
			(options
				(clearance outline)
				(anchor circle)
			)
			(primitives
				(gr_poly
					(pts
						(arc
							(start -0.1778 -0.2794)
							(mid -0.249642 -0.249642)
							(end -0.2794 -0.1778)
						)
						(arc
							(start -0.2794 0.1778)
							(mid -0.249642 0.249642)
							(end -0.1778 0.2794)
						)
						(arc
							(start 0.1778 0.2794)
							(mid 0.249642 0.249642)
							(end 0.2794 0.1778)
						)
						(arc
							(start 0.2794 -0.1778)
							(mid 0.249642 -0.249642)
							(end 0.1778 -0.2794)
						)
					)
					(width 0)
					(fill yes)
				)
			)
		)
		(pad "2" smd custom
			(at 0 0.4445 180)
			(size 0.1397 0.1397)
			(layers "F.Cu" "F.Mask" "F.Paste")
			(net "BMC_GPIOZ5")
			(options
				(clearance outline)
				(anchor circle)
			)
			(primitives
				(gr_poly
					(pts
						(arc
							(start -0.1778 -0.2794)
							(mid -0.249642 -0.249642)
							(end -0.2794 -0.1778)
						)
						(arc
							(start -0.2794 0.1778)
							(mid -0.249642 0.249642)
							(end -0.1778 0.2794)
						)
						(arc
							(start 0.1778 0.2794)
							(mid 0.249642 0.249642)
							(end 0.2794 0.1778)
						)
						(arc
							(start 0.2794 -0.1778)
							(mid 0.249642 -0.249642)
							(end 0.1778 -0.2794)
						)
					)
					(width 0)
					(fill yes)
				)
			)
		)
	)
	(footprint ""
		(layer "F.Cu")
		(at 184.0738 -49.9872)
		(property "Reference" "TP165"
			(at 0 0 0)
			(layer "F.SilkS")
			(hide yes)
			(effects
				(font
					(size 1.27 1.27)
				)
			)
		)
		(property "Value" "TPAD28-2-GP"
			(at -0.0127 -1.6637 0)
			(unlocked yes)
			(layer "F.Fab")
			(hide yes)
			(effects
				(font
					(size 1.016 1.016)
					(thickness 0.1524)
				)
			)
		)
		(property "Device Type" "TPAD28"
			(at -0.0127 -3.1877 0)
			(unlocked yes)
			(layer "F.Fab")
			(hide yes)
			(effects
				(font
					(size 1.016 1.016)
					(thickness 0.1524)
				)
			)
		)
		(duplicate_pad_numbers_are_jumpers no)
		(fp_poly
			(pts
				(arc
					(start 0.3556 0)
					(mid -0.3556 0)
					(end 0.3556 0)
				)
			)
			(stroke
				(width 0)
				(type default)
			)
			(fill no)
			(layer "F.CrtYd")
		)
		(fp_poly
			(pts
				(arc
					(start 0.6096 0)
					(mid -0.6096 0)
					(end 0.6096 0)
				)
			)
			(stroke
				(width 0)
				(type default)
			)
			(fill no)
			(layer "F.Fab")
		)
		(pad "1" smd circle
			(at 0 0)
			(size 0.7112 0.7112)
			(layers "F.Cu" "F.Mask" "F.Paste")
			(net "XM_ALE")
		)
	)
	(footprint ""
		(layer "F.Cu")
		(at 87.67445 -29.39034 180)
		(property "Reference" "C1"
			(at 0 0 180)
			(layer "F.SilkS")
			(hide yes)
			(effects
				(font
					(size 1.27 1.27)
				)
			)
		)
		(property "Value" "SCD1U16V2KX-3GP"
			(at 1.1811 -2.7051 180)
			(unlocked yes)
			(layer "F.Fab")
			(hide yes)
			(effects
				(font
					(size 1.016 1.016)
					(thickness 0.1524)
				)
			)
		)
		(property "Device Type" "C402H22"
			(at 1.1811 -4.2291 180)
			(unlocked yes)
			(layer "F.Fab")
			(hide yes)
			(effects
				(font
					(size 1.016 1.016)
					(thickness 0.1524)
				)
			)
		)
		(duplicate_pad_numbers_are_jumpers no)
		(fp_rect
			(start -0.4318 0.9525)
			(end 0.4318 -0.9525)
			(stroke
				(width 0)
				(type default)
			)
			(fill no)
			(layer "F.CrtYd")
		)
		(fp_rect
			(start -0.4318 0.9525)
			(end 0.4318 -0.9525)
			(stroke
				(width 0)
				(type default)
			)
			(fill no)
			(layer "F.Fab")
		)
		(pad "1" smd custom
			(at 0 -0.4445 180)
			(size 0.1524 0.1524)
			(layers "F.Cu" "F.Mask" "F.Paste")
			(net "P5V_STBY")
			(options
				(clearance outline)
				(anchor circle)
			)
			(primitives
				(gr_poly
					(pts
						(arc
							(start 0.3048 -0.2032)
							(mid 0.275042 -0.275042)
							(end 0.2032 -0.3048)
						)
						(arc
							(start -0.2032 -0.3048)
							(mid -0.275042 -0.275042)
							(end -0.3048 -0.2032)
						)
						(arc
							(start -0.3048 0.2032)
							(mid -0.275042 0.275042)
							(end -0.2032 0.3048)
						)
						(arc
							(start 0.2032 0.3048)
							(mid 0.275042 0.275042)
							(end 0.3048 0.2032)
						)
					)
					(width 0)
					(fill yes)
				)
			)
		)
		(pad "2" smd custom
			(at 0 0.4445 180)
			(size 0.1524 0.1524)
			(layers "F.Cu" "F.Mask" "F.Paste")
			(net "GND")
			(options
				(clearance outline)
				(anchor circle)
			)
			(primitives
				(gr_poly
					(pts
						(arc
							(start 0.3048 -0.2032)
							(mid 0.275042 -0.275042)
							(end 0.2032 -0.3048)
						)
						(arc
							(start -0.2032 -0.3048)
							(mid -0.275042 -0.275042)
							(end -0.3048 -0.2032)
						)
						(arc
							(start -0.3048 0.2032)
							(mid -0.275042 0.275042)
							(end -0.2032 0.3048)
						)
						(arc
							(start 0.2032 0.3048)
							(mid 0.275042 0.275042)
							(end 0.3048 0.2032)
						)
					)
					(width 0)
					(fill yes)
				)
			)
		)
	)
	(footprint ""
		(layer "F.Cu")
		(at 59.524392 -131.296156 180)
		(property "Reference" "R289"
			(at 0 0 180)
			(layer "F.SilkS")
			(hide yes)
			(effects
				(font
					(size 1.27 1.27)
				)
			)
		)
		(property "Value" "0R2J-2-GP"
			(at 0.064008 -3.993896 180)
			(unlocked yes)
			(layer "F.Fab")
			(hide yes)
			(effects
				(font
					(size 1.016 1.016)
					(thickness 0.1524)
				)
			)
		)
		(property "Device Type" "R402H16"
			(at 0.064008 -5.517896 180)
			(unlocked yes)
			(layer "F.Fab")
			(hide yes)
			(effects
				(font
					(size 1.016 1.016)
					(thickness 0.1524)
				)
			)
		)
		(duplicate_pad_numbers_are_jumpers no)
		(fp_line
			(start 0.508 -0.9398)
			(end -0.508 -0.9398)
			(stroke
				(width 0.1524)
				(type default)
			)
			(layer "F.SilkS")
		)
		(fp_line
			(start -0.508 -0.9398)
			(end -0.508 0.9398)
			(stroke
				(width 0.1524)
				(type default)
			)
			(layer "F.SilkS")
		)
		(fp_rect
			(start -0.508 0.9398)
			(end 0.508 -0.9398)
			(stroke
				(width 0)
				(type default)
			)
			(fill no)
			(layer "F.CrtYd")
		)
		(fp_rect
			(start -0.508 0.9398)
			(end 0.508 -0.9398)
			(stroke
				(width 0)
				(type default)
			)
			(fill no)
			(layer "F.Fab")
		)
		(pad "1" smd custom
			(at 0 -0.4445 180)
			(size 0.1397 0.1397)
			(layers "F.Cu" "F.Mask" "F.Paste")
			(net "EXP_SPARE_1")
			(options
				(clearance outline)
				(anchor circle)
			)
			(primitives
				(gr_poly
					(pts
						(arc
							(start -0.1778 -0.2794)
							(mid -0.249642 -0.249642)
							(end -0.2794 -0.1778)
						)
						(arc
							(start -0.2794 0.1778)
							(mid -0.249642 0.249642)
							(end -0.1778 0.2794)
						)
						(arc
							(start 0.1778 0.2794)
							(mid 0.249642 0.249642)
							(end 0.2794 0.1778)
						)
						(arc
							(start 0.2794 -0.1778)
							(mid 0.249642 -0.249642)
							(end 0.1778 -0.2794)
						)
					)
					(width 0)
					(fill yes)
				)
			)
		)
		(pad "2" smd custom
			(at 0 0.4445 180)
			(size 0.1397 0.1397)
			(layers "F.Cu" "F.Mask" "F.Paste")
			(net "EXP_SPARE_1_R")
			(options
				(clearance outline)
				(anchor circle)
			)
			(primitives
				(gr_poly
					(pts
						(arc
							(start -0.1778 -0.2794)
							(mid -0.249642 -0.249642)
							(end -0.2794 -0.1778)
						)
						(arc
							(start -0.2794 0.1778)
							(mid -0.249642 0.249642)
							(end -0.1778 0.2794)
						)
						(arc
							(start 0.1778 0.2794)
							(mid 0.249642 0.249642)
							(end 0.2794 0.1778)
						)
						(arc
							(start 0.2794 -0.1778)
							(mid 0.249642 -0.249642)
							(end 0.1778 -0.2794)
						)
					)
					(width 0)
					(fill yes)
				)
			)
		)
	)
	(footprint ""
		(layer "F.Cu")
		(at 8.904732 -138.145774 90)
		(property "Reference" "R229"
			(at 0 0 90)
			(layer "F.SilkS")
			(hide yes)
			(effects
				(font
					(size 1.27 1.27)
				)
			)
		)
		(property "Value" "120R2F-GP"
			(at 0.064008 -3.993896 90)
			(unlocked yes)
			(layer "F.Fab")
			(hide yes)
			(effects
				(font
					(size 1.016 1.016)
					(thickness 0.1524)
				)
			)
		)
		(property "Device Type" "R402H16"
			(at 0.064008 -5.517896 90)
			(unlocked yes)
			(layer "F.Fab")
			(hide yes)
			(effects
				(font
					(size 1.016 1.016)
					(thickness 0.1524)
				)
			)
		)
		(duplicate_pad_numbers_are_jumpers no)
		(fp_line
			(start 0.508 -0.9398)
			(end -0.508 -0.9398)
			(stroke
				(width 0.1524)
				(type default)
			)
			(layer "F.SilkS")
		)
		(fp_line
			(start -0.508 -0.9398)
			(end -0.508 0.9398)
			(stroke
				(width 0.1524)
				(type default)
			)
			(layer "F.SilkS")
		)
		(fp_rect
			(start -0.508 0.9398)
			(end 0.508 -0.9398)
			(stroke
				(width 0)
				(type default)
			)
			(fill no)
			(layer "F.CrtYd")
		)
		(fp_rect
			(start -0.508 0.9398)
			(end 0.508 -0.9398)
			(stroke
				(width 0)
				(type default)
			)
			(fill no)
			(layer "F.Fab")
		)
		(pad "1" smd custom
			(at 0 -0.4445 90)
			(size 0.1397 0.1397)
			(layers "F.Cu" "F.Mask" "F.Paste")
			(net "GND")
			(options
				(clearance outline)
				(anchor circle)
			)
			(primitives
				(gr_poly
					(pts
						(arc
							(start -0.1778 -0.2794)
							(mid -0.249642 -0.249642)
							(end -0.2794 -0.1778)
						)
						(arc
							(start -0.2794 0.1778)
							(mid -0.249642 0.249642)
							(end -0.1778 0.2794)
						)
						(arc
							(start 0.1778 0.2794)
							(mid 0.249642 0.249642)
							(end 0.2794 0.1778)
						)
						(arc
							(start 0.2794 -0.1778)
							(mid 0.249642 -0.249642)
							(end 0.1778 -0.2794)
						)
					)
					(width 0)
					(fill yes)
				)
			)
		)
		(pad "2" smd custom
			(at 0 0.4445 90)
			(size 0.1397 0.1397)
			(layers "F.Cu" "F.Mask" "F.Paste")
			(net "MEMBA_0")
			(options
				(clearance outline)
				(anchor circle)
			)
			(primitives
				(gr_poly
					(pts
						(arc
							(start -0.1778 -0.2794)
							(mid -0.249642 -0.249642)
							(end -0.2794 -0.1778)
						)
						(arc
							(start -0.2794 0.1778)
							(mid -0.249642 0.249642)
							(end -0.1778 0.2794)
						)
						(arc
							(start 0.1778 0.2794)
							(mid 0.249642 0.249642)
							(end 0.2794 0.1778)
						)
						(arc
							(start 0.2794 -0.1778)
							(mid 0.249642 -0.249642)
							(end 0.1778 -0.2794)
						)
					)
					(width 0)
					(fill yes)
				)
			)
		)
	)
	(footprint ""
		(layer "F.Cu")
		(at 197.0024 -49.9618)
		(property "Reference" "TP135"
			(at 0 0 0)
			(layer "F.SilkS")
			(hide yes)
			(effects
				(font
					(size 1.27 1.27)
				)
			)
		)
		(property "Value" "TPAD28-2-GP"
			(at -0.0127 -1.6637 0)
			(unlocked yes)
			(layer "F.Fab")
			(hide yes)
			(effects
				(font
					(size 1.016 1.016)
					(thickness 0.1524)
				)
			)
		)
		(property "Device Type" "TPAD28"
			(at -0.0127 -3.1877 0)
			(unlocked yes)
			(layer "F.Fab")
			(hide yes)
			(effects
				(font
					(size 1.016 1.016)
					(thickness 0.1524)
				)
			)
		)
		(duplicate_pad_numbers_are_jumpers no)
		(fp_poly
			(pts
				(arc
					(start 0.3556 0)
					(mid -0.3556 0)
					(end 0.3556 0)
				)
			)
			(stroke
				(width 0)
				(type default)
			)
			(fill no)
			(layer "F.CrtYd")
		)
		(fp_poly
			(pts
				(arc
					(start 0.6096 0)
					(mid -0.6096 0)
					(end 0.6096 0)
				)
			)
			(stroke
				(width 0)
				(type default)
			)
			(fill no)
			(layer "F.Fab")
		)
		(pad "1" smd circle
			(at 0 0)
			(size 0.7112 0.7112)
			(layers "F.Cu" "F.Mask" "F.Paste")
			(net "ICE0_TCK")
		)
	)
	(footprint ""
		(layer "F.Cu")
		(at 87.8586 -147.2692)
		(property "Reference" "R422"
			(at 0 0 0)
			(layer "F.SilkS")
			(hide yes)
			(effects
				(font
					(size 1.27 1.27)
				)
			)
		)
		(property "Value" "4K7R2F-GP"
			(at 0.064008 -3.993896 0)
			(unlocked yes)
			(layer "F.Fab")
			(hide yes)
			(effects
				(font
					(size 1.016 1.016)
					(thickness 0.1524)
				)
			)
		)
		(property "Device Type" "R402H16"
			(at 0.064008 -5.517896 0)
			(unlocked yes)
			(layer "F.Fab")
			(hide yes)
			(effects
				(font
					(size 1.016 1.016)
					(thickness 0.1524)
				)
			)
		)
		(duplicate_pad_numbers_are_jumpers no)
		(fp_line
			(start -0.508 -0.9398)
			(end -0.508 0.9398)
			(stroke
				(width 0.1524)
				(type default)
			)
			(layer "F.SilkS")
		)
		(fp_line
			(start 0.508 -0.9398)
			(end -0.508 -0.9398)
			(stroke
				(width 0.1524)
				(type default)
			)
			(layer "F.SilkS")
		)
		(fp_rect
			(start -0.508 0.9398)
			(end 0.508 -0.9398)
			(stroke
				(width 0)
				(type default)
			)
			(fill no)
			(layer "F.CrtYd")
		)
		(fp_rect
			(start -0.508 0.9398)
			(end 0.508 -0.9398)
			(stroke
				(width 0)
				(type default)
			)
			(fill no)
			(layer "F.Fab")
		)
		(pad "1" smd custom
			(at 0 -0.4445)
			(size 0.1397 0.1397)
			(layers "F.Cu" "F.Mask" "F.Paste")
			(net "P3V3_STBY")
			(options
				(clearance outline)
				(anchor circle)
			)
			(primitives
				(gr_poly
					(pts
						(arc
							(start -0.1778 -0.2794)
							(mid -0.249642 -0.249642)
							(end -0.2794 -0.1778)
						)
						(arc
							(start -0.2794 0.1778)
							(mid -0.249642 0.249642)
							(end -0.1778 0.2794)
						)
						(arc
							(start 0.1778 0.2794)
							(mid 0.249642 0.249642)
							(end 0.2794 0.1778)
						)
						(arc
							(start 0.2794 -0.1778)
							(mid 0.249642 -0.249642)
							(end 0.1778 -0.2794)
						)
					)
					(width 0)
					(fill yes)
				)
			)
		)
		(pad "2" smd custom
			(at 0 0.4445)
			(size 0.1397 0.1397)
			(layers "F.Cu" "F.Mask" "F.Paste")
			(net "IO_EXP0_RESET#_FLT")
			(options
				(clearance outline)
				(anchor circle)
			)
			(primitives
				(gr_poly
					(pts
						(arc
							(start -0.1778 -0.2794)
							(mid -0.249642 -0.249642)
							(end -0.2794 -0.1778)
						)
						(arc
							(start -0.2794 0.1778)
							(mid -0.249642 0.249642)
							(end -0.1778 0.2794)
						)
						(arc
							(start 0.1778 0.2794)
							(mid 0.249642 0.249642)
							(end 0.2794 0.1778)
						)
						(arc
							(start 0.2794 -0.1778)
							(mid 0.249642 -0.249642)
							(end 0.1778 -0.2794)
						)
					)
					(width 0)
					(fill yes)
				)
			)
		)
	)
	(footprint ""
		(layer "F.Cu")
		(at 37.9222 -164.2618 180)
		(property "Reference" "R330"
			(at 0 0 180)
			(layer "F.SilkS")
			(hide yes)
			(effects
				(font
					(size 1.27 1.27)
				)
			)
		)
		(property "Value" "4K7R2F-GP"
			(at 0.064008 -3.993896 180)
			(unlocked yes)
			(layer "F.Fab")
			(hide yes)
			(effects
				(font
					(size 1.016 1.016)
					(thickness 0.1524)
				)
			)
		)
		(property "Device Type" "R402H16"
			(at 0.064008 -5.517896 180)
			(unlocked yes)
			(layer "F.Fab")
			(hide yes)
			(effects
				(font
					(size 1.016 1.016)
					(thickness 0.1524)
				)
			)
		)
		(duplicate_pad_numbers_are_jumpers no)
		(fp_line
			(start 0.508 -0.9398)
			(end -0.508 -0.9398)
			(stroke
				(width 0.1524)
				(type default)
			)
			(layer "F.SilkS")
		)
		(fp_line
			(start -0.508 -0.9398)
			(end -0.508 0.9398)
			(stroke
				(width 0.1524)
				(type default)
			)
			(layer "F.SilkS")
		)
		(fp_rect
			(start -0.508 0.9398)
			(end 0.508 -0.9398)
			(stroke
				(width 0)
				(type default)
			)
			(fill no)
			(layer "F.CrtYd")
		)
		(fp_rect
			(start -0.508 0.9398)
			(end 0.508 -0.9398)
			(stroke
				(width 0)
				(type default)
			)
			(fill no)
			(layer "F.Fab")
		)
		(pad "1" smd custom
			(at 0 -0.4445 180)
			(size 0.1397 0.1397)
			(layers "F.Cu" "F.Mask" "F.Paste")
			(net "P3V3_STBY")
			(options
				(clearance outline)
				(anchor circle)
			)
			(primitives
				(gr_poly
					(pts
						(arc
							(start -0.1778 -0.2794)
							(mid -0.249642 -0.249642)
							(end -0.2794 -0.1778)
						)
						(arc
							(start -0.2794 0.1778)
							(mid -0.249642 0.249642)
							(end -0.1778 0.2794)
						)
						(arc
							(start 0.1778 0.2794)
							(mid 0.249642 0.249642)
							(end 0.2794 0.1778)
						)
						(arc
							(start 0.2794 -0.1778)
							(mid 0.249642 -0.249642)
							(end 0.1778 -0.2794)
						)
					)
					(width 0)
					(fill yes)
				)
			)
		)
		(pad "2" smd custom
			(at 0 0.4445 180)
			(size 0.1397 0.1397)
			(layers "F.Cu" "F.Mask" "F.Paste")
			(net "UART_EXP_BMC_TX")
			(options
				(clearance outline)
				(anchor circle)
			)
			(primitives
				(gr_poly
					(pts
						(arc
							(start -0.1778 -0.2794)
							(mid -0.249642 -0.249642)
							(end -0.2794 -0.1778)
						)
						(arc
							(start -0.2794 0.1778)
							(mid -0.249642 0.249642)
							(end -0.1778 0.2794)
						)
						(arc
							(start 0.1778 0.2794)
							(mid 0.249642 0.249642)
							(end 0.2794 0.1778)
						)
						(arc
							(start 0.2794 -0.1778)
							(mid 0.249642 -0.249642)
							(end 0.1778 -0.2794)
						)
					)
					(width 0)
					(fill yes)
				)
			)
		)
	)
	(footprint ""
		(layer "F.Cu")
		(at 81.858358 -139.812522 180)
		(property "Reference" "C30"
			(at 0 0 180)
			(layer "F.SilkS")
			(hide yes)
			(effects
				(font
					(size 1.27 1.27)
				)
			)
		)
		(property "Value" "SCD1U16V2KX-3GP"
			(at 1.1811 -2.7051 180)
			(unlocked yes)
			(layer "F.Fab")
			(hide yes)
			(effects
				(font
					(size 1.016 1.016)
					(thickness 0.1524)
				)
			)
		)
		(property "Device Type" "C402H22"
			(at 1.1811 -4.2291 180)
			(unlocked yes)
			(layer "F.Fab")
			(hide yes)
			(effects
				(font
					(size 1.016 1.016)
					(thickness 0.1524)
				)
			)
		)
		(duplicate_pad_numbers_are_jumpers no)
		(fp_rect
			(start -0.4318 0.9525)
			(end 0.4318 -0.9525)
			(stroke
				(width 0)
				(type default)
			)
			(fill no)
			(layer "F.CrtYd")
		)
		(fp_rect
			(start -0.4318 0.9525)
			(end 0.4318 -0.9525)
			(stroke
				(width 0)
				(type default)
			)
			(fill no)
			(layer "F.Fab")
		)
		(pad "1" smd custom
			(at 0 -0.4445 180)
			(size 0.1524 0.1524)
			(layers "F.Cu" "F.Mask" "F.Paste")
			(net "P3V3_STBY")
			(options
				(clearance outline)
				(anchor circle)
			)
			(primitives
				(gr_poly
					(pts
						(arc
							(start 0.3048 -0.2032)
							(mid 0.275042 -0.275042)
							(end 0.2032 -0.3048)
						)
						(arc
							(start -0.2032 -0.3048)
							(mid -0.275042 -0.275042)
							(end -0.3048 -0.2032)
						)
						(arc
							(start -0.3048 0.2032)
							(mid -0.275042 0.275042)
							(end -0.2032 0.3048)
						)
						(arc
							(start 0.2032 0.3048)
							(mid 0.275042 0.275042)
							(end 0.3048 0.2032)
						)
					)
					(width 0)
					(fill yes)
				)
			)
		)
		(pad "2" smd custom
			(at 0 0.4445 180)
			(size 0.1524 0.1524)
			(layers "F.Cu" "F.Mask" "F.Paste")
			(net "GND")
			(options
				(clearance outline)
				(anchor circle)
			)
			(primitives
				(gr_poly
					(pts
						(arc
							(start 0.3048 -0.2032)
							(mid 0.275042 -0.275042)
							(end 0.2032 -0.3048)
						)
						(arc
							(start -0.2032 -0.3048)
							(mid -0.275042 -0.275042)
							(end -0.3048 -0.2032)
						)
						(arc
							(start -0.3048 0.2032)
							(mid -0.275042 0.275042)
							(end -0.2032 0.3048)
						)
						(arc
							(start 0.2032 0.3048)
							(mid 0.275042 0.275042)
							(end 0.3048 0.2032)
						)
					)
					(width 0)
					(fill yes)
				)
			)
		)
	)
	(footprint ""
		(layer "F.Cu")
		(at 69.883782 -156.277818 180)
		(property "Reference" "X2"
			(at 0 0 180)
			(layer "F.SilkS")
			(hide yes)
			(effects
				(font
					(size 1.27 1.27)
				)
			)
		)
		(property "Value" "OSC-50MHZ-16-GP"
			(at 0.0127 -2.7686 180)
			(unlocked yes)
			(layer "F.Fab")
			(hide yes)
			(effects
				(font
					(size 1.016 1.016)
					(thickness 0.1524)
				)
			)
		)
		(property "Device Type" "OSC-3225-4P-3H48"
			(at 0.0127 -4.2926 180)
			(unlocked yes)
			(layer "F.Fab")
			(hide yes)
			(effects
				(font
					(size 1.016 1.016)
					(thickness 0.1524)
				)
			)
		)
		(duplicate_pad_numbers_are_jumpers no)
		(fp_line
			(start 2.1209 1.5367)
			(end -2.1209 1.5367)
			(stroke
				(width 0.1524)
				(type default)
			)
			(layer "F.SilkS")
		)
		(fp_line
			(start 2.1209 -1.5367)
			(end 2.1209 1.5367)
			(stroke
				(width 0.1524)
				(type default)
			)
			(layer "F.SilkS")
		)
		(fp_line
			(start -1.3208 1.6256)
			(end -2.2352 1.6256)
			(stroke
				(width 0.3302)
				(type default)
			)
			(layer "F.SilkS")
		)
		(fp_line
			(start -2.1209 1.5367)
			(end -2.1209 -1.5367)
			(stroke
				(width 0.1524)
				(type default)
			)
			(layer "F.SilkS")
		)
		(fp_line
			(start -2.1209 -1.5367)
			(end 2.1209 -1.5367)
			(stroke
				(width 0.1524)
				(type default)
			)
			(layer "F.SilkS")
		)
		(fp_line
			(start -2.2352 1.6256)
			(end -2.2352 0.635)
			(stroke
				(width 0.3302)
				(type default)
			)
			(layer "F.SilkS")
		)
		(fp_poly
			(pts
				(xy -2.8321 1.459992) (xy -2.8321 0.189992) (xy -2.1971 0.824992)
			)
			(stroke
				(width 0)
				(type default)
			)
			(fill yes)
			(layer "F.SilkS")
		)
		(fp_rect
			(start -1.6002 1.2446)
			(end 1.6002 -1.2446)
			(stroke
				(width 0)
				(type default)
			)
			(fill no)
			(layer "F.CrtYd")
		)
		(fp_poly
			(pts
				(xy -2.3749 1.7907) (xy -2.3749 -1.7907) (xy 2.3749 -1.7907) (xy 2.3749 1.7907) (xy 1.6002 1.7907)
				(xy 1.6002 -1.2446) (xy -1.6002 -1.2446) (xy -1.6002 1.2446) (xy 1.59512 1.2446) (xy 1.59512 1.7907)
			)
			(stroke
				(width 0)
				(type default)
			)
			(fill no)
			(layer "F.CrtYd")
		)
		(fp_rect
			(start -2.3749 1.7907)
			(end 2.3749 -1.7907)
			(stroke
				(width 0)
				(type default)
			)
			(fill no)
			(layer "F.Fab")
		)
		(pad "1" smd rect
			(at -1.171448 0.824992 180)
			(size 1.397 0.9144)
			(layers "F.Cu" "F.Mask" "F.Paste")
			(net "FM_OSC_50M_EN")
		)
		(pad "2" smd rect
			(at 1.171448 0.824992 180)
			(size 1.397 0.9144)
			(layers "F.Cu" "F.Mask" "F.Paste")
			(net "GND")
		)
		(pad "3" smd rect
			(at 1.171448 -0.824992 180)
			(size 1.397 0.9144)
			(layers "F.Cu" "F.Mask" "F.Paste")
			(net "50M_CLK_OUT")
		)
		(pad "4" smd rect
			(at -1.171448 -0.824992 180)
			(size 1.397 0.9144)
			(layers "F.Cu" "F.Mask" "F.Paste")
			(net "P3V3_STBY")
		)
		(zone
			(layer "F.Cu")
			(hatch none 0.5)
			(connect_pads
				(clearance 0)
			)
			(min_thickness 0.25)
			(keepout
				(tracks not_allowed)
				(vias allowed)
				(pads allowed)
				(copperpour not_allowed)
				(footprints allowed)
			)
			(placement
				(enabled no)
				(sheetname "")
			)
			(fill
				(thermal_gap 0.5)
				(thermal_bridge_width 0.5)
				(island_removal_mode 0)
			)
			(polygon
				(pts
					(xy 70.03161 -156.32049) (xy 69.735954 -156.32049) (xy 69.735954 -156.235146) (xy 70.03161 -156.235146)
				)
			)
		)
		(zone
			(layer "F.Cu")
			(hatch none 0.5)
			(connect_pads
				(clearance 0)
			)
			(min_thickness 0.25)
			(keepout
				(tracks allowed)
				(vias not_allowed)
				(pads allowed)
				(copperpour not_allowed)
				(footprints allowed)
			)
			(placement
				(enabled no)
				(sheetname "")
			)
			(fill
				(thermal_gap 0.5)
				(thermal_bridge_width 0.5)
				(island_removal_mode 0)
			)
			(polygon
				(pts
					(xy 70.35673 -157.56001) (xy 70.35673 -156.64561) (xy 71.75373 -156.64561) (xy 71.75373 -155.910026)
					(xy 70.35673 -155.910026) (xy 70.35673 -154.995626) (xy 69.410834 -154.995626) (xy 69.410834 -155.910026)
					(xy 68.013834 -155.910026) (xy 68.013834 -156.64561) (xy 69.410834 -156.64561) (xy 69.410834 -157.56001)
				)
			)
		)
	)
	(footprint ""
		(layer "F.Cu")
		(at 12.500102 -187.999878)
		(property "Reference" ""
			(at 0 0 0)
			(layer "F.SilkS")
			(hide yes)
			(effects
				(font
					(size 1.27 1.27)
				)
			)
		)
		(property "Value" "*"
			(at 6.2484 0.3429 0)
			(unlocked yes)
			(layer "F.Fab")
			(hide yes)
			(effects
				(font
					(size 1.016 1.016)
					(thickness 0.1524)
				)
			)
		)
		(duplicate_pad_numbers_are_jumpers no)
		(fp_poly
			(pts
				(arc
					(start 5.0673 0)
					(mid -5.0673 0)
					(end 5.0673 0)
				)
			)
			(stroke
				(width 0)
				(type default)
			)
			(fill no)
			(layer "B.CrtYd")
		)
		(fp_poly
			(pts
				(arc
					(start 5.0673 0)
					(mid -5.0673 0)
					(end 5.0673 0)
				)
			)
			(stroke
				(width 0)
				(type default)
			)
			(fill no)
			(layer "F.CrtYd")
		)
		(fp_poly
			(pts
				(arc
					(start 5.0673 0)
					(mid -5.0673 0)
					(end 5.0673 0)
				)
			)
			(stroke
				(width 0)
				(type default)
			)
			(fill no)
			(layer "B.Fab")
		)
		(fp_poly
			(pts
				(arc
					(start 5.0673 0)
					(mid -5.0673 0)
					(end 5.0673 0)
				)
			)
			(stroke
				(width 0)
				(type default)
			)
			(fill no)
			(layer "F.Fab")
		)
		(pad "1" thru_hole circle
			(at 0 0)
			(size 9.525 9.525)
			(drill 4.0132)
			(layers "*.Cu" "*.Mask")
			(remove_unused_layers no)
			(net "Net_72")
			(clearance -2.2479)
			(thermal_gap 0.3048)
			(padstack
				(mode front_inner_back)
				(layer "Inner"
					(shape circle)
					(size 4.4196 4.4196)
					(clearance 0.3048)
				)
				(layer "B.Cu"
					(shape circle)
					(size 9.525 9.525)
					(clearance -2.2479)
				)
			)
		)
	)
	(footprint ""
		(layer "F.Cu")
		(at 178.0794 -38.5064)
		(property "Reference" "TP177"
			(at 0 0 0)
			(layer "F.SilkS")
			(hide yes)
			(effects
				(font
					(size 1.27 1.27)
				)
			)
		)
		(property "Value" "TPAD28-2-GP"
			(at -0.0127 -1.6637 0)
			(unlocked yes)
			(layer "F.Fab")
			(hide yes)
			(effects
				(font
					(size 1.016 1.016)
					(thickness 0.1524)
				)
			)
		)
		(property "Device Type" "TPAD28"
			(at -0.0127 -3.1877 0)
			(unlocked yes)
			(layer "F.Fab")
			(hide yes)
			(effects
				(font
					(size 1.016 1.016)
					(thickness 0.1524)
				)
			)
		)
		(duplicate_pad_numbers_are_jumpers no)
		(fp_poly
			(pts
				(arc
					(start 0.3556 0)
					(mid -0.3556 0)
					(end 0.3556 0)
				)
			)
			(stroke
				(width 0)
				(type default)
			)
			(fill no)
			(layer "F.CrtYd")
		)
		(fp_poly
			(pts
				(arc
					(start 0.6096 0)
					(mid -0.6096 0)
					(end 0.6096 0)
				)
			)
			(stroke
				(width 0)
				(type default)
			)
			(fill no)
			(layer "F.Fab")
		)
		(pad "1" smd circle
			(at 0 0)
			(size 0.7112 0.7112)
			(layers "F.Cu" "F.Mask" "F.Paste")
			(net "ZDEF_EXTA_TP_D2")
		)
	)
	(footprint ""
		(layer "F.Cu")
		(at 57.484264 -167.377618 90)
		(property "Reference" "R197"
			(at 0 0 90)
			(layer "F.SilkS")
			(hide yes)
			(effects
				(font
					(size 1.27 1.27)
				)
			)
		)
		(property "Value" "2K2R2F-GP"
			(at 0.064008 -3.993896 90)
			(unlocked yes)
			(layer "F.Fab")
			(hide yes)
			(effects
				(font
					(size 1.016 1.016)
					(thickness 0.1524)
				)
			)
		)
		(property "Device Type" "R402H16"
			(at 0.064008 -5.517896 90)
			(unlocked yes)
			(layer "F.Fab")
			(hide yes)
			(effects
				(font
					(size 1.016 1.016)
					(thickness 0.1524)
				)
			)
		)
		(duplicate_pad_numbers_are_jumpers no)
		(fp_line
			(start 0.508 -0.9398)
			(end -0.508 -0.9398)
			(stroke
				(width 0.1524)
				(type default)
			)
			(layer "F.SilkS")
		)
		(fp_line
			(start -0.508 -0.9398)
			(end -0.508 0.9398)
			(stroke
				(width 0.1524)
				(type default)
			)
			(layer "F.SilkS")
		)
		(fp_rect
			(start -0.508 0.9398)
			(end 0.508 -0.9398)
			(stroke
				(width 0)
				(type default)
			)
			(fill no)
			(layer "F.CrtYd")
		)
		(fp_rect
			(start -0.508 0.9398)
			(end 0.508 -0.9398)
			(stroke
				(width 0)
				(type default)
			)
			(fill no)
			(layer "F.Fab")
		)
		(pad "1" smd custom
			(at 0 -0.4445 90)
			(size 0.1397 0.1397)
			(layers "F.Cu" "F.Mask" "F.Paste")
			(net "I2C_TPM_SDA")
			(options
				(clearance outline)
				(anchor circle)
			)
			(primitives
				(gr_poly
					(pts
						(arc
							(start -0.1778 -0.2794)
							(mid -0.249642 -0.249642)
							(end -0.2794 -0.1778)
						)
						(arc
							(start -0.2794 0.1778)
							(mid -0.249642 0.249642)
							(end -0.1778 0.2794)
						)
						(arc
							(start 0.1778 0.2794)
							(mid 0.249642 0.249642)
							(end 0.2794 0.1778)
						)
						(arc
							(start 0.2794 -0.1778)
							(mid 0.249642 -0.249642)
							(end 0.1778 -0.2794)
						)
					)
					(width 0)
					(fill yes)
				)
			)
		)
		(pad "2" smd custom
			(at 0 0.4445 90)
			(size 0.1397 0.1397)
			(layers "F.Cu" "F.Mask" "F.Paste")
			(net "P3V3_STBY")
			(options
				(clearance outline)
				(anchor circle)
			)
			(primitives
				(gr_poly
					(pts
						(arc
							(start -0.1778 -0.2794)
							(mid -0.249642 -0.249642)
							(end -0.2794 -0.1778)
						)
						(arc
							(start -0.2794 0.1778)
							(mid -0.249642 0.249642)
							(end -0.1778 0.2794)
						)
						(arc
							(start 0.1778 0.2794)
							(mid 0.249642 0.249642)
							(end 0.2794 0.1778)
						)
						(arc
							(start 0.2794 -0.1778)
							(mid 0.249642 -0.249642)
							(end 0.1778 -0.2794)
						)
					)
					(width 0)
					(fill yes)
				)
			)
		)
	)
	(footprint ""
		(layer "F.Cu")
		(at 177.2412 -52.7304 -90)
		(property "Reference" "R674"
			(at 0 0 270)
			(layer "F.SilkS")
			(hide yes)
			(effects
				(font
					(size 1.27 1.27)
				)
			)
		)
		(property "Value" "10KR2F-2-GP"
			(at 0.064008 -3.993896 270)
			(unlocked yes)
			(layer "F.Fab")
			(hide yes)
			(effects
				(font
					(size 1.016 1.016)
					(thickness 0.1524)
				)
			)
		)
		(property "Device Type" "R402H16"
			(at 0.064008 -5.517896 270)
			(unlocked yes)
			(layer "F.Fab")
			(hide yes)
			(effects
				(font
					(size 1.016 1.016)
					(thickness 0.1524)
				)
			)
		)
		(duplicate_pad_numbers_are_jumpers no)
		(fp_line
			(start -0.508 -0.9398)
			(end -0.508 0.9398)
			(stroke
				(width 0.1524)
				(type default)
			)
			(layer "F.SilkS")
		)
		(fp_line
			(start 0.508 -0.9398)
			(end -0.508 -0.9398)
			(stroke
				(width 0.1524)
				(type default)
			)
			(layer "F.SilkS")
		)
		(fp_rect
			(start -0.508 0.9398)
			(end 0.508 -0.9398)
			(stroke
				(width 0)
				(type default)
			)
			(fill no)
			(layer "F.CrtYd")
		)
		(fp_rect
			(start -0.508 0.9398)
			(end 0.508 -0.9398)
			(stroke
				(width 0)
				(type default)
			)
			(fill no)
			(layer "F.Fab")
		)
		(pad "1" smd custom
			(at 0 -0.4445 270)
			(size 0.1397 0.1397)
			(layers "F.Cu" "F.Mask" "F.Paste")
			(net "XM_ADDR_11")
			(options
				(clearance outline)
				(anchor circle)
			)
			(primitives
				(gr_poly
					(pts
						(arc
							(start -0.1778 -0.2794)
							(mid -0.249642 -0.249642)
							(end -0.2794 -0.1778)
						)
						(arc
							(start -0.2794 0.1778)
							(mid -0.249642 0.249642)
							(end -0.1778 0.2794)
						)
						(arc
							(start 0.1778 0.2794)
							(mid 0.249642 0.249642)
							(end 0.2794 0.1778)
						)
						(arc
							(start 0.2794 -0.1778)
							(mid 0.249642 -0.249642)
							(end 0.1778 -0.2794)
						)
					)
					(width 0)
					(fill yes)
				)
			)
		)
		(pad "2" smd custom
			(at 0 0.4445 270)
			(size 0.1397 0.1397)
			(layers "F.Cu" "F.Mask" "F.Paste")
			(net "GND")
			(options
				(clearance outline)
				(anchor circle)
			)
			(primitives
				(gr_poly
					(pts
						(arc
							(start -0.1778 -0.2794)
							(mid -0.249642 -0.249642)
							(end -0.2794 -0.1778)
						)
						(arc
							(start -0.2794 0.1778)
							(mid -0.249642 0.249642)
							(end -0.1778 0.2794)
						)
						(arc
							(start 0.1778 0.2794)
							(mid 0.249642 0.249642)
							(end 0.2794 0.1778)
						)
						(arc
							(start 0.2794 -0.1778)
							(mid 0.249642 -0.249642)
							(end 0.1778 -0.2794)
						)
					)
					(width 0)
					(fill yes)
				)
			)
		)
	)
	(footprint ""
		(layer "F.Cu")
		(at 98.928174 -158.441644 90)
		(property "Reference" "R26"
			(at 0 0 90)
			(layer "F.SilkS")
			(hide yes)
			(effects
				(font
					(size 1.27 1.27)
				)
			)
		)
		(property "Value" "0R2J-2-GP"
			(at 0.064008 -3.993896 90)
			(unlocked yes)
			(layer "F.Fab")
			(hide yes)
			(effects
				(font
					(size 1.016 1.016)
					(thickness 0.1524)
				)
			)
		)
		(property "Device Type" "R402H16"
			(at 0.064008 -5.517896 90)
			(unlocked yes)
			(layer "F.Fab")
			(hide yes)
			(effects
				(font
					(size 1.016 1.016)
					(thickness 0.1524)
				)
			)
		)
		(duplicate_pad_numbers_are_jumpers no)
		(fp_line
			(start 0.508 -0.9398)
			(end -0.508 -0.9398)
			(stroke
				(width 0.1524)
				(type default)
			)
			(layer "F.SilkS")
		)
		(fp_line
			(start -0.508 -0.9398)
			(end -0.508 0.9398)
			(stroke
				(width 0.1524)
				(type default)
			)
			(layer "F.SilkS")
		)
		(fp_rect
			(start -0.508 0.9398)
			(end 0.508 -0.9398)
			(stroke
				(width 0)
				(type default)
			)
			(fill no)
			(layer "F.CrtYd")
		)
		(fp_rect
			(start -0.508 0.9398)
			(end 0.508 -0.9398)
			(stroke
				(width 0)
				(type default)
			)
			(fill no)
			(layer "F.Fab")
		)
		(pad "1" smd custom
			(at 0 -0.4445 90)
			(size 0.1397 0.1397)
			(layers "F.Cu" "F.Mask" "F.Paste")
			(net "USB_RESET_N")
			(options
				(clearance outline)
				(anchor circle)
			)
			(primitives
				(gr_poly
					(pts
						(arc
							(start -0.1778 -0.2794)
							(mid -0.249642 -0.249642)
							(end -0.2794 -0.1778)
						)
						(arc
							(start -0.2794 0.1778)
							(mid -0.249642 0.249642)
							(end -0.1778 0.2794)
						)
						(arc
							(start 0.1778 0.2794)
							(mid 0.249642 0.249642)
							(end 0.2794 0.1778)
						)
						(arc
							(start 0.2794 -0.1778)
							(mid 0.249642 -0.249642)
							(end 0.1778 -0.2794)
						)
					)
					(width 0)
					(fill yes)
				)
			)
		)
		(pad "2" smd custom
			(at 0 0.4445 90)
			(size 0.1397 0.1397)
			(layers "F.Cu" "F.Mask" "F.Paste")
			(net "PCIE_COMP_TO_IOM_RST_4")
			(options
				(clearance outline)
				(anchor circle)
			)
			(primitives
				(gr_poly
					(pts
						(arc
							(start -0.1778 -0.2794)
							(mid -0.249642 -0.249642)
							(end -0.2794 -0.1778)
						)
						(arc
							(start -0.2794 0.1778)
							(mid -0.249642 0.249642)
							(end -0.1778 0.2794)
						)
						(arc
							(start 0.1778 0.2794)
							(mid 0.249642 0.249642)
							(end 0.2794 0.1778)
						)
						(arc
							(start 0.2794 -0.1778)
							(mid 0.249642 -0.249642)
							(end 0.1778 -0.2794)
						)
					)
					(width 0)
					(fill yes)
				)
			)
		)
	)
	(footprint ""
		(layer "F.Cu")
		(at 74.9554 -145.7198 90)
		(property "Reference" "R329"
			(at 0 0 90)
			(layer "F.SilkS")
			(hide yes)
			(effects
				(font
					(size 1.27 1.27)
				)
			)
		)
		(property "Value" "0R2J-2-GP"
			(at 0.064008 -3.993896 90)
			(unlocked yes)
			(layer "F.Fab")
			(hide yes)
			(effects
				(font
					(size 1.016 1.016)
					(thickness 0.1524)
				)
			)
		)
		(property "Device Type" "R402H16"
			(at 0.064008 -5.517896 90)
			(unlocked yes)
			(layer "F.Fab")
			(hide yes)
			(effects
				(font
					(size 1.016 1.016)
					(thickness 0.1524)
				)
			)
		)
		(duplicate_pad_numbers_are_jumpers no)
		(fp_line
			(start 0.508 -0.9398)
			(end -0.508 -0.9398)
			(stroke
				(width 0.1524)
				(type default)
			)
			(layer "F.SilkS")
		)
		(fp_line
			(start -0.508 -0.9398)
			(end -0.508 0.9398)
			(stroke
				(width 0.1524)
				(type default)
			)
			(layer "F.SilkS")
		)
		(fp_rect
			(start -0.508 0.9398)
			(end 0.508 -0.9398)
			(stroke
				(width 0)
				(type default)
			)
			(fill no)
			(layer "F.CrtYd")
		)
		(fp_rect
			(start -0.508 0.9398)
			(end 0.508 -0.9398)
			(stroke
				(width 0)
				(type default)
			)
			(fill no)
			(layer "F.Fab")
		)
		(pad "1" smd custom
			(at 0 -0.4445 90)
			(size 0.1397 0.1397)
			(layers "F.Cu" "F.Mask" "F.Paste")
			(net "I2C_DPB_SCL")
			(options
				(clearance outline)
				(anchor circle)
			)
			(primitives
				(gr_poly
					(pts
						(arc
							(start -0.1778 -0.2794)
							(mid -0.249642 -0.249642)
							(end -0.2794 -0.1778)
						)
						(arc
							(start -0.2794 0.1778)
							(mid -0.249642 0.249642)
							(end -0.1778 0.2794)
						)
						(arc
							(start 0.1778 0.2794)
							(mid 0.249642 0.249642)
							(end 0.2794 0.1778)
						)
						(arc
							(start 0.2794 -0.1778)
							(mid 0.249642 -0.249642)
							(end 0.1778 -0.2794)
						)
					)
					(width 0)
					(fill yes)
				)
			)
		)
		(pad "2" smd custom
			(at 0 0.4445 90)
			(size 0.1397 0.1397)
			(layers "F.Cu" "F.Mask" "F.Paste")
			(net "I2C_DPB_SCL_R")
			(options
				(clearance outline)
				(anchor circle)
			)
			(primitives
				(gr_poly
					(pts
						(arc
							(start -0.1778 -0.2794)
							(mid -0.249642 -0.249642)
							(end -0.2794 -0.1778)
						)
						(arc
							(start -0.2794 0.1778)
							(mid -0.249642 0.249642)
							(end -0.1778 0.2794)
						)
						(arc
							(start 0.1778 0.2794)
							(mid 0.249642 0.249642)
							(end 0.2794 0.1778)
						)
						(arc
							(start 0.2794 -0.1778)
							(mid 0.249642 -0.249642)
							(end 0.1778 -0.2794)
						)
					)
					(width 0)
					(fill yes)
				)
			)
		)
	)
	(footprint ""
		(layer "F.Cu")
		(at 198.755 -106.172)
		(property "Reference" "C263"
			(at 0 0 0)
			(layer "F.SilkS")
			(hide yes)
			(effects
				(font
					(size 1.27 1.27)
				)
			)
		)
		(property "Value" "SCD1U50V3KX-GP"
			(at 0 -2.8194 0)
			(unlocked yes)
			(layer "F.Fab")
			(hide yes)
			(effects
				(font
					(size 1.016 1.016)
					(thickness 0.1524)
				)
			)
		)
		(property "Device Type" "C603H36"
			(at 0 -4.3434 0)
			(unlocked yes)
			(layer "F.Fab")
			(hide yes)
			(effects
				(font
					(size 1.016 1.016)
					(thickness 0.1524)
				)
			)
		)
		(duplicate_pad_numbers_are_jumpers no)
		(fp_line
			(start 0.508 0)
			(end -0.508 0)
			(stroke
				(width 0.2032)
				(type default)
			)
			(layer "F.SilkS")
		)
		(fp_rect
			(start -0.5842 1.3335)
			(end 0.5842 -1.3335)
			(stroke
				(width 0)
				(type default)
			)
			(fill no)
			(layer "F.CrtYd")
		)
		(fp_rect
			(start -0.5842 1.3335)
			(end 0.5842 -1.3335)
			(stroke
				(width 0)
				(type default)
			)
			(fill no)
			(layer "F.Fab")
		)
		(pad "1" smd custom
			(at 0 -0.762)
			(size 0.2159 0.2159)
			(layers "F.Cu" "F.Mask" "F.Paste")
			(net "P0V975")
			(options
				(clearance outline)
				(anchor circle)
			)
			(primitives
				(gr_poly
					(pts
						(arc
							(start -0.3302 -0.4318)
							(mid -0.402042 -0.402042)
							(end -0.4318 -0.3302)
						)
						(arc
							(start -0.4318 0.3302)
							(mid -0.402042 0.402042)
							(end -0.3302 0.4318)
						)
						(arc
							(start 0.3302 0.4318)
							(mid 0.402042 0.402042)
							(end 0.4318 0.3302)
						)
						(arc
							(start 0.4318 -0.3302)
							(mid 0.402042 -0.402042)
							(end 0.3302 -0.4318)
						)
					)
					(width 0)
					(fill yes)
				)
			)
		)
		(pad "2" smd custom
			(at 0 0.762)
			(size 0.2159 0.2159)
			(layers "F.Cu" "F.Mask" "F.Paste")
			(net "GND")
			(options
				(clearance outline)
				(anchor circle)
			)
			(primitives
				(gr_poly
					(pts
						(arc
							(start -0.3302 -0.4318)
							(mid -0.402042 -0.402042)
							(end -0.4318 -0.3302)
						)
						(arc
							(start -0.4318 0.3302)
							(mid -0.402042 0.402042)
							(end -0.3302 0.4318)
						)
						(arc
							(start 0.3302 0.4318)
							(mid 0.402042 0.402042)
							(end 0.4318 0.3302)
						)
						(arc
							(start 0.4318 -0.3302)
							(mid 0.402042 -0.402042)
							(end 0.3302 -0.4318)
						)
					)
					(width 0)
					(fill yes)
				)
			)
		)
	)
	(footprint ""
		(layer "F.Cu")
		(at 188.1886 -49.9745)
		(property "Reference" "TP151"
			(at 0 0 0)
			(layer "F.SilkS")
			(hide yes)
			(effects
				(font
					(size 1.27 1.27)
				)
			)
		)
		(property "Value" "TPAD28-2-GP"
			(at -0.0127 -1.6637 0)
			(unlocked yes)
			(layer "F.Fab")
			(hide yes)
			(effects
				(font
					(size 1.016 1.016)
					(thickness 0.1524)
				)
			)
		)
		(property "Device Type" "TPAD28"
			(at -0.0127 -3.1877 0)
			(unlocked yes)
			(layer "F.Fab")
			(hide yes)
			(effects
				(font
					(size 1.016 1.016)
					(thickness 0.1524)
				)
			)
		)
		(duplicate_pad_numbers_are_jumpers no)
		(fp_poly
			(pts
				(arc
					(start 0.3556 0)
					(mid -0.3556 0)
					(end 0.3556 0)
				)
			)
			(stroke
				(width 0)
				(type default)
			)
			(fill no)
			(layer "F.CrtYd")
		)
		(fp_poly
			(pts
				(arc
					(start 0.6096 0)
					(mid -0.6096 0)
					(end 0.6096 0)
				)
			)
			(stroke
				(width 0)
				(type default)
			)
			(fill no)
			(layer "F.Fab")
		)
		(pad "1" smd circle
			(at 0 0)
			(size 0.7112 0.7112)
			(layers "F.Cu" "F.Mask" "F.Paste")
			(net "JTAG_IOC_TMS")
		)
	)
	(footprint ""
		(layer "F.Cu")
		(at 213.106 -67.6148 -45)
		(property "Reference" "VIA46"
			(at 0 0 315)
			(layer "F.SilkS")
			(hide yes)
			(effects
				(font
					(size 1.27 1.27)
				)
			)
		)
		(property "Value" "100OHM-8L-1D6MM-L18L16-GP"
			(at -3.720879 -4.508552 315)
			(unlocked yes)
			(layer "F.Fab")
			(hide yes)
			(effects
				(font
					(size 1.016 1.016)
					(thickness 0.1524)
				)
			)
		)
		(property "Device Type" "VIA-PCIE-4P-394076"
			(at -3.721059 -6.032502 315)
			(unlocked yes)
			(layer "F.Fab")
			(hide yes)
			(effects
				(font
					(size 1.016 1.016)
					(thickness 0.1524)
				)
			)
		)
		(duplicate_pad_numbers_are_jumpers no)
		(fp_poly
			(pts
				(xy -1.968472 -0.380877) (xy 1.968528 -0.380878) (xy 1.968527 0.381122) (xy -1.968472 0.381122)
			)
			(stroke
				(width 0)
				(type default)
			)
			(fill no)
			(layer "F.CrtYd")
		)
		(fp_poly
			(pts
				(xy -1.968472 -0.380877) (xy 1.968528 -0.380878) (xy 1.968527 0.381122) (xy -1.968472 0.381122)
			)
			(stroke
				(width 0)
				(type default)
			)
			(fill no)
			(layer "F.Fab")
		)
		(pad "1" thru_hole circle
			(at -1.5875 0 315)
			(size 0.508 0.508)
			(drill 0.254)
			(layers "*.Cu" "*.Mask")
			(remove_unused_layers no)
			(net "GND")
			(clearance 0.127)
			(thermal_gap 0.127)
		)
		(pad "2" thru_hole circle
			(at -0.571501 0 315)
			(size 0.508 0.508)
			(drill 0.254)
			(layers "*.Cu" "*.Mask")
			(remove_unused_layers no)
			(net "PHY_IOC_TO_CON_B_1_DP")
			(clearance 0.127)
			(thermal_gap 0.127)
		)
		(pad "3" thru_hole circle
			(at 0.571501 0 315)
			(size 0.508 0.508)
			(drill 0.254)
			(layers "*.Cu" "*.Mask")
			(remove_unused_layers no)
			(net "PHY_IOC_TO_CON_B_1_DN")
			(clearance 0.127)
			(thermal_gap 0.127)
		)
		(pad "4" thru_hole circle
			(at 1.5875 0 315)
			(size 0.508 0.508)
			(drill 0.254)
			(layers "*.Cu" "*.Mask")
			(remove_unused_layers no)
			(net "GND")
			(clearance 0.127)
			(thermal_gap 0.127)
		)
	)
	(footprint ""
		(layer "F.Cu")
		(at 197.1548 -13.462)
		(property "Reference" "C514"
			(at 0 0 0)
			(layer "F.SilkS")
			(hide yes)
			(effects
				(font
					(size 1.27 1.27)
				)
			)
		)
		(property "Value" "SCD1U16V2KX-3GP"
			(at 1.1811 -2.7051 0)
			(unlocked yes)
			(layer "F.Fab")
			(hide yes)
			(effects
				(font
					(size 1.016 1.016)
					(thickness 0.1524)
				)
			)
		)
		(property "Device Type" "C402H22"
			(at 1.1811 -4.2291 0)
			(unlocked yes)
			(layer "F.Fab")
			(hide yes)
			(effects
				(font
					(size 1.016 1.016)
					(thickness 0.1524)
				)
			)
		)
		(duplicate_pad_numbers_are_jumpers no)
		(fp_rect
			(start -0.4318 0.9525)
			(end 0.4318 -0.9525)
			(stroke
				(width 0)
				(type default)
			)
			(fill no)
			(layer "F.CrtYd")
		)
		(fp_rect
			(start -0.4318 0.9525)
			(end 0.4318 -0.9525)
			(stroke
				(width 0)
				(type default)
			)
			(fill no)
			(layer "F.Fab")
		)
		(pad "1" smd custom
			(at 0 -0.4445)
			(size 0.1524 0.1524)
			(layers "F.Cu" "F.Mask" "F.Paste")
			(net "P1V8")
			(options
				(clearance outline)
				(anchor circle)
			)
			(primitives
				(gr_poly
					(pts
						(arc
							(start 0.3048 -0.2032)
							(mid 0.275042 -0.275042)
							(end 0.2032 -0.3048)
						)
						(arc
							(start -0.2032 -0.3048)
							(mid -0.275042 -0.275042)
							(end -0.3048 -0.2032)
						)
						(arc
							(start -0.3048 0.2032)
							(mid -0.275042 0.275042)
							(end -0.2032 0.3048)
						)
						(arc
							(start 0.2032 0.3048)
							(mid 0.275042 0.275042)
							(end 0.3048 0.2032)
						)
					)
					(width 0)
					(fill yes)
				)
			)
		)
		(pad "2" smd custom
			(at 0 0.4445)
			(size 0.1524 0.1524)
			(layers "F.Cu" "F.Mask" "F.Paste")
			(net "GND")
			(options
				(clearance outline)
				(anchor circle)
			)
			(primitives
				(gr_poly
					(pts
						(arc
							(start 0.3048 -0.2032)
							(mid 0.275042 -0.275042)
							(end 0.2032 -0.3048)
						)
						(arc
							(start -0.2032 -0.3048)
							(mid -0.275042 -0.275042)
							(end -0.3048 -0.2032)
						)
						(arc
							(start -0.3048 0.2032)
							(mid -0.275042 0.275042)
							(end -0.2032 0.3048)
						)
						(arc
							(start 0.2032 0.3048)
							(mid 0.275042 0.275042)
							(end 0.3048 0.2032)
						)
					)
					(width 0)
					(fill yes)
				)
			)
		)
	)
	(footprint ""
		(layer "F.Cu")
		(at 215.519 -73.787 -45)
		(property "Reference" "VIA43"
			(at 0 0 315)
			(layer "F.SilkS")
			(hide yes)
			(effects
				(font
					(size 1.27 1.27)
				)
			)
		)
		(property "Value" "100OHM-8L-1D6MM-L18L16-GP"
			(at -3.721059 -4.508373 315)
			(unlocked yes)
			(layer "F.Fab")
			(hide yes)
			(effects
				(font
					(size 1.016 1.016)
					(thickness 0.1524)
				)
			)
		)
		(property "Device Type" "VIA-PCIE-4P-394076"
			(at -3.721059 -6.032502 315)
			(unlocked yes)
			(layer "F.Fab")
			(hide yes)
			(effects
				(font
					(size 1.016 1.016)
					(thickness 0.1524)
				)
			)
		)
		(duplicate_pad_numbers_are_jumpers no)
		(fp_poly
			(pts
				(xy -1.968472 -0.380877) (xy 1.968528 -0.380878) (xy 1.968527 0.381122) (xy -1.968472 0.381122)
			)
			(stroke
				(width 0)
				(type default)
			)
			(fill no)
			(layer "F.CrtYd")
		)
		(fp_poly
			(pts
				(xy -1.968472 -0.380877) (xy 1.968528 -0.380878) (xy 1.968527 0.381122) (xy -1.968472 0.381122)
			)
			(stroke
				(width 0)
				(type default)
			)
			(fill no)
			(layer "F.Fab")
		)
		(pad "1" thru_hole circle
			(at -1.5875 0 315)
			(size 0.508 0.508)
			(drill 0.254)
			(layers "*.Cu" "*.Mask")
			(remove_unused_layers no)
			(net "GND")
			(clearance 0.127)
			(thermal_gap 0.127)
		)
		(pad "2" thru_hole circle
			(at -0.571501 0 315)
			(size 0.508 0.508)
			(drill 0.254)
			(layers "*.Cu" "*.Mask")
			(remove_unused_layers no)
			(net "PHY_IOC_TO_CON_A_2_DP")
			(clearance 0.127)
			(thermal_gap 0.127)
		)
		(pad "3" thru_hole circle
			(at 0.571501 0 315)
			(size 0.508 0.508)
			(drill 0.254)
			(layers "*.Cu" "*.Mask")
			(remove_unused_layers no)
			(net "PHY_IOC_TO_CON_A_2_DN")
			(clearance 0.127)
			(thermal_gap 0.127)
		)
		(pad "4" thru_hole circle
			(at 1.5875 0 315)
			(size 0.508 0.508)
			(drill 0.254)
			(layers "*.Cu" "*.Mask")
			(remove_unused_layers no)
			(net "GND")
			(clearance 0.127)
			(thermal_gap 0.127)
		)
	)
	(footprint ""
		(layer "F.Cu")
		(at 49.142904 -161.180272 180)
		(property "Reference" "R203"
			(at 0 0 180)
			(layer "F.SilkS")
			(hide yes)
			(effects
				(font
					(size 1.27 1.27)
				)
			)
		)
		(property "Value" "2K2R2F-GP"
			(at 0.064008 -3.993896 180)
			(unlocked yes)
			(layer "F.Fab")
			(hide yes)
			(effects
				(font
					(size 1.016 1.016)
					(thickness 0.1524)
				)
			)
		)
		(property "Device Type" "R402H16"
			(at 0.064008 -5.517896 180)
			(unlocked yes)
			(layer "F.Fab")
			(hide yes)
			(effects
				(font
					(size 1.016 1.016)
					(thickness 0.1524)
				)
			)
		)
		(duplicate_pad_numbers_are_jumpers no)
		(fp_line
			(start 0.508 -0.9398)
			(end -0.508 -0.9398)
			(stroke
				(width 0.1524)
				(type default)
			)
			(layer "F.SilkS")
		)
		(fp_line
			(start -0.508 -0.9398)
			(end -0.508 0.9398)
			(stroke
				(width 0.1524)
				(type default)
			)
			(layer "F.SilkS")
		)
		(fp_rect
			(start -0.508 0.9398)
			(end 0.508 -0.9398)
			(stroke
				(width 0)
				(type default)
			)
			(fill no)
			(layer "F.CrtYd")
		)
		(fp_rect
			(start -0.508 0.9398)
			(end 0.508 -0.9398)
			(stroke
				(width 0)
				(type default)
			)
			(fill no)
			(layer "F.Fab")
		)
		(pad "1" smd custom
			(at 0 -0.4445 180)
			(size 0.1397 0.1397)
			(layers "F.Cu" "F.Mask" "F.Paste")
			(net "I2C_DPB_MISC_SCL_OUT")
			(options
				(clearance outline)
				(anchor circle)
			)
			(primitives
				(gr_poly
					(pts
						(arc
							(start -0.1778 -0.2794)
							(mid -0.249642 -0.249642)
							(end -0.2794 -0.1778)
						)
						(arc
							(start -0.2794 0.1778)
							(mid -0.249642 0.249642)
							(end -0.1778 0.2794)
						)
						(arc
							(start 0.1778 0.2794)
							(mid 0.249642 0.249642)
							(end 0.2794 0.1778)
						)
						(arc
							(start 0.2794 -0.1778)
							(mid 0.249642 -0.249642)
							(end 0.1778 -0.2794)
						)
					)
					(width 0)
					(fill yes)
				)
			)
		)
		(pad "2" smd custom
			(at 0 0.4445 180)
			(size 0.1397 0.1397)
			(layers "F.Cu" "F.Mask" "F.Paste")
			(net "P3V3_STBY")
			(options
				(clearance outline)
				(anchor circle)
			)
			(primitives
				(gr_poly
					(pts
						(arc
							(start -0.1778 -0.2794)
							(mid -0.249642 -0.249642)
							(end -0.2794 -0.1778)
						)
						(arc
							(start -0.2794 0.1778)
							(mid -0.249642 0.249642)
							(end -0.1778 0.2794)
						)
						(arc
							(start 0.1778 0.2794)
							(mid 0.249642 0.249642)
							(end 0.2794 0.1778)
						)
						(arc
							(start 0.2794 -0.1778)
							(mid 0.249642 -0.249642)
							(end 0.1778 -0.2794)
						)
					)
					(width 0)
					(fill yes)
				)
			)
		)
	)
	(footprint ""
		(layer "F.Cu")
		(at 205.8924 -48.2854 180)
		(property "Reference" "R635"
			(at 0 0 180)
			(layer "F.SilkS")
			(hide yes)
			(effects
				(font
					(size 1.27 1.27)
				)
			)
		)
		(property "Value" "4K7R2F-GP"
			(at 0.064008 -3.993896 180)
			(unlocked yes)
			(layer "F.Fab")
			(hide yes)
			(effects
				(font
					(size 1.016 1.016)
					(thickness 0.1524)
				)
			)
		)
		(property "Device Type" "R402H16"
			(at 0.064008 -5.517896 180)
			(unlocked yes)
			(layer "F.Fab")
			(hide yes)
			(effects
				(font
					(size 1.016 1.016)
					(thickness 0.1524)
				)
			)
		)
		(duplicate_pad_numbers_are_jumpers no)
		(fp_line
			(start 0.508 -0.9398)
			(end -0.508 -0.9398)
			(stroke
				(width 0.1524)
				(type default)
			)
			(layer "F.SilkS")
		)
		(fp_line
			(start -0.508 -0.9398)
			(end -0.508 0.9398)
			(stroke
				(width 0.1524)
				(type default)
			)
			(layer "F.SilkS")
		)
		(fp_rect
			(start -0.508 0.9398)
			(end 0.508 -0.9398)
			(stroke
				(width 0)
				(type default)
			)
			(fill no)
			(layer "F.CrtYd")
		)
		(fp_rect
			(start -0.508 0.9398)
			(end 0.508 -0.9398)
			(stroke
				(width 0)
				(type default)
			)
			(fill no)
			(layer "F.Fab")
		)
		(pad "1" smd custom
			(at 0 -0.4445 180)
			(size 0.1397 0.1397)
			(layers "F.Cu" "F.Mask" "F.Paste")
			(net "P1V8")
			(options
				(clearance outline)
				(anchor circle)
			)
			(primitives
				(gr_poly
					(pts
						(arc
							(start -0.1778 -0.2794)
							(mid -0.249642 -0.249642)
							(end -0.2794 -0.1778)
						)
						(arc
							(start -0.2794 0.1778)
							(mid -0.249642 0.249642)
							(end -0.1778 0.2794)
						)
						(arc
							(start 0.1778 0.2794)
							(mid 0.249642 0.249642)
							(end 0.2794 0.1778)
						)
						(arc
							(start 0.2794 -0.1778)
							(mid 0.249642 -0.249642)
							(end 0.1778 -0.2794)
						)
					)
					(width 0)
					(fill yes)
				)
			)
		)
		(pad "2" smd custom
			(at 0 0.4445 180)
			(size 0.1397 0.1397)
			(layers "F.Cu" "F.Mask" "F.Paste")
			(net "ICE0_TMS")
			(options
				(clearance outline)
				(anchor circle)
			)
			(primitives
				(gr_poly
					(pts
						(arc
							(start -0.1778 -0.2794)
							(mid -0.249642 -0.249642)
							(end -0.2794 -0.1778)
						)
						(arc
							(start -0.2794 0.1778)
							(mid -0.249642 0.249642)
							(end -0.1778 0.2794)
						)
						(arc
							(start 0.1778 0.2794)
							(mid 0.249642 0.249642)
							(end 0.2794 0.1778)
						)
						(arc
							(start 0.2794 -0.1778)
							(mid 0.249642 -0.249642)
							(end 0.1778 -0.2794)
						)
					)
					(width 0)
					(fill yes)
				)
			)
		)
	)
	(footprint ""
		(layer "F.Cu")
		(at 77.274674 -67.766692 90)
		(property "Reference" "VIA25"
			(at 0 0 90)
			(layer "F.SilkS")
			(hide yes)
			(effects
				(font
					(size 1.27 1.27)
				)
			)
		)
		(property "Value" "85OHM-8L-1D6MM-L16L18-GP"
			(at 4.064 0.6096 90)
			(unlocked yes)
			(layer "F.Fab")
			(hide yes)
			(effects
				(font
					(size 1.016 1.016)
					(thickness 0.1524)
				)
			)
		)
		(property "Device Type" "VIA-PCIE-4P-368076"
			(at 4.064 -0.9144 90)
			(unlocked yes)
			(layer "F.Fab")
			(hide yes)
			(effects
				(font
					(size 1.016 1.016)
					(thickness 0.1524)
				)
			)
		)
		(duplicate_pad_numbers_are_jumpers no)
		(fp_rect
			(start -1.8415 0.381)
			(end 1.8415 -0.381)
			(stroke
				(width 0)
				(type default)
			)
			(fill no)
			(layer "F.CrtYd")
		)
		(fp_rect
			(start -1.8415 0.381)
			(end 1.8415 -0.381)
			(stroke
				(width 0)
				(type default)
			)
			(fill no)
			(layer "F.Fab")
		)
		(pad "1" thru_hole circle
			(at -1.4605 0 90)
			(size 0.508 0.508)
			(drill 0.254)
			(layers "*.Cu" "*.Mask")
			(remove_unused_layers no)
			(net "GND")
			(clearance 0.127)
			(thermal_gap 0.127)
		)
		(pad "2" thru_hole circle
			(at -0.4445 0 90)
			(size 0.508 0.508)
			(drill 0.254)
			(layers "*.Cu" "*.Mask")
			(remove_unused_layers no)
			(net "PCIE_COMP_TO_IOM_CLK_4_DP")
			(clearance 0.127)
			(thermal_gap 0.127)
		)
		(pad "3" thru_hole circle
			(at 0.4445 0 90)
			(size 0.508 0.508)
			(drill 0.254)
			(layers "*.Cu" "*.Mask")
			(remove_unused_layers no)
			(net "PCIE_COMP_TO_IOM_CLK_4_DN")
			(clearance 0.127)
			(thermal_gap 0.127)
		)
		(pad "4" thru_hole circle
			(at 1.4605 0 90)
			(size 0.508 0.508)
			(drill 0.254)
			(layers "*.Cu" "*.Mask")
			(remove_unused_layers no)
			(net "GND")
			(clearance 0.127)
			(thermal_gap 0.127)
		)
	)
	(footprint ""
		(layer "F.Cu")
		(at 37.5412 -161.4424)
		(property "Reference" "R300"
			(at 0 0 0)
			(layer "F.SilkS")
			(hide yes)
			(effects
				(font
					(size 1.27 1.27)
				)
			)
		)
		(property "Value" "4K7R2F-GP"
			(at 0.064008 -3.993896 0)
			(unlocked yes)
			(layer "F.Fab")
			(hide yes)
			(effects
				(font
					(size 1.016 1.016)
					(thickness 0.1524)
				)
			)
		)
		(property "Device Type" "R402H16"
			(at 0.064008 -5.517896 0)
			(unlocked yes)
			(layer "F.Fab")
			(hide yes)
			(effects
				(font
					(size 1.016 1.016)
					(thickness 0.1524)
				)
			)
		)
		(duplicate_pad_numbers_are_jumpers no)
		(fp_line
			(start -0.508 -0.9398)
			(end -0.508 0.9398)
			(stroke
				(width 0.1524)
				(type default)
			)
			(layer "F.SilkS")
		)
		(fp_line
			(start 0.508 -0.9398)
			(end -0.508 -0.9398)
			(stroke
				(width 0.1524)
				(type default)
			)
			(layer "F.SilkS")
		)
		(fp_rect
			(start -0.508 0.9398)
			(end 0.508 -0.9398)
			(stroke
				(width 0)
				(type default)
			)
			(fill no)
			(layer "F.CrtYd")
		)
		(fp_rect
			(start -0.508 0.9398)
			(end 0.508 -0.9398)
			(stroke
				(width 0)
				(type default)
			)
			(fill no)
			(layer "F.Fab")
		)
		(pad "1" smd custom
			(at 0 -0.4445)
			(size 0.1397 0.1397)
			(layers "F.Cu" "F.Mask" "F.Paste")
			(net "P3V3_STBY")
			(options
				(clearance outline)
				(anchor circle)
			)
			(primitives
				(gr_poly
					(pts
						(arc
							(start -0.1778 -0.2794)
							(mid -0.249642 -0.249642)
							(end -0.2794 -0.1778)
						)
						(arc
							(start -0.2794 0.1778)
							(mid -0.249642 0.249642)
							(end -0.1778 0.2794)
						)
						(arc
							(start 0.1778 0.2794)
							(mid 0.249642 0.249642)
							(end 0.2794 0.1778)
						)
						(arc
							(start 0.2794 -0.1778)
							(mid 0.249642 -0.249642)
							(end 0.1778 -0.2794)
						)
					)
					(width 0)
					(fill yes)
				)
			)
		)
		(pad "2" smd custom
			(at 0 0.4445)
			(size 0.1397 0.1397)
			(layers "F.Cu" "F.Mask" "F.Paste")
			(net "UART_COMP_OUT_TX")
			(options
				(clearance outline)
				(anchor circle)
			)
			(primitives
				(gr_poly
					(pts
						(arc
							(start -0.1778 -0.2794)
							(mid -0.249642 -0.249642)
							(end -0.2794 -0.1778)
						)
						(arc
							(start -0.2794 0.1778)
							(mid -0.249642 0.249642)
							(end -0.1778 0.2794)
						)
						(arc
							(start 0.1778 0.2794)
							(mid 0.249642 0.249642)
							(end 0.2794 0.1778)
						)
						(arc
							(start 0.2794 -0.1778)
							(mid 0.249642 -0.249642)
							(end 0.1778 -0.2794)
						)
					)
					(width 0)
					(fill yes)
				)
			)
		)
	)
	(footprint ""
		(layer "F.Cu")
		(at 86.846918 -58.713624 90)
		(property "Reference" "R4"
			(at 0 0 90)
			(layer "F.SilkS")
			(hide yes)
			(effects
				(font
					(size 1.27 1.27)
				)
			)
		)
		(property "Value" "0R2J-2-GP"
			(at 0.064008 -3.993896 90)
			(unlocked yes)
			(layer "F.Fab")
			(hide yes)
			(effects
				(font
					(size 1.016 1.016)
					(thickness 0.1524)
				)
			)
		)
		(property "Device Type" "R402H16"
			(at 0.064008 -5.517896 90)
			(unlocked yes)
			(layer "F.Fab")
			(hide yes)
			(effects
				(font
					(size 1.016 1.016)
					(thickness 0.1524)
				)
			)
		)
		(duplicate_pad_numbers_are_jumpers no)
		(fp_line
			(start 0.508 -0.9398)
			(end -0.508 -0.9398)
			(stroke
				(width 0.1524)
				(type default)
			)
			(layer "F.SilkS")
		)
		(fp_line
			(start -0.508 -0.9398)
			(end -0.508 0.9398)
			(stroke
				(width 0.1524)
				(type default)
			)
			(layer "F.SilkS")
		)
		(fp_rect
			(start -0.508 0.9398)
			(end 0.508 -0.9398)
			(stroke
				(width 0)
				(type default)
			)
			(fill no)
			(layer "F.CrtYd")
		)
		(fp_rect
			(start -0.508 0.9398)
			(end 0.508 -0.9398)
			(stroke
				(width 0)
				(type default)
			)
			(fill no)
			(layer "F.Fab")
		)
		(pad "1" smd custom
			(at 0 -0.4445 90)
			(size 0.1397 0.1397)
			(layers "F.Cu" "F.Mask" "F.Paste")
			(net "I2C_MEZZ_ALERT_R_N")
			(options
				(clearance outline)
				(anchor circle)
			)
			(primitives
				(gr_poly
					(pts
						(arc
							(start -0.1778 -0.2794)
							(mid -0.249642 -0.249642)
							(end -0.2794 -0.1778)
						)
						(arc
							(start -0.2794 0.1778)
							(mid -0.249642 0.249642)
							(end -0.1778 0.2794)
						)
						(arc
							(start 0.1778 0.2794)
							(mid 0.249642 0.249642)
							(end 0.2794 0.1778)
						)
						(arc
							(start 0.2794 -0.1778)
							(mid 0.249642 -0.249642)
							(end 0.1778 -0.2794)
						)
					)
					(width 0)
					(fill yes)
				)
			)
		)
		(pad "2" smd custom
			(at 0 0.4445 90)
			(size 0.1397 0.1397)
			(layers "F.Cu" "F.Mask" "F.Paste")
			(net "I2C_MEZZ_ALERT_N")
			(options
				(clearance outline)
				(anchor circle)
			)
			(primitives
				(gr_poly
					(pts
						(arc
							(start -0.1778 -0.2794)
							(mid -0.249642 -0.249642)
							(end -0.2794 -0.1778)
						)
						(arc
							(start -0.2794 0.1778)
							(mid -0.249642 0.249642)
							(end -0.1778 0.2794)
						)
						(arc
							(start 0.1778 0.2794)
							(mid 0.249642 0.249642)
							(end 0.2794 0.1778)
						)
						(arc
							(start 0.2794 -0.1778)
							(mid 0.249642 -0.249642)
							(end 0.1778 -0.2794)
						)
					)
					(width 0)
					(fill yes)
				)
			)
		)
	)
	(footprint ""
		(layer "F.Cu")
		(at 56.3626 -158.8516)
		(property "Reference" "R395"
			(at 0 0 0)
			(layer "F.SilkS")
			(hide yes)
			(effects
				(font
					(size 1.27 1.27)
				)
			)
		)
		(property "Value" "4K7R2F-GP"
			(at 0.064008 -3.993896 0)
			(unlocked yes)
			(layer "F.Fab")
			(hide yes)
			(effects
				(font
					(size 1.016 1.016)
					(thickness 0.1524)
				)
			)
		)
		(property "Device Type" "R402H16"
			(at 0.064008 -5.517896 0)
			(unlocked yes)
			(layer "F.Fab")
			(hide yes)
			(effects
				(font
					(size 1.016 1.016)
					(thickness 0.1524)
				)
			)
		)
		(duplicate_pad_numbers_are_jumpers no)
		(fp_line
			(start -0.508 -0.9398)
			(end -0.508 0.9398)
			(stroke
				(width 0.1524)
				(type default)
			)
			(layer "F.SilkS")
		)
		(fp_line
			(start 0.508 -0.9398)
			(end -0.508 -0.9398)
			(stroke
				(width 0.1524)
				(type default)
			)
			(layer "F.SilkS")
		)
		(fp_rect
			(start -0.508 0.9398)
			(end 0.508 -0.9398)
			(stroke
				(width 0)
				(type default)
			)
			(fill no)
			(layer "F.CrtYd")
		)
		(fp_rect
			(start -0.508 0.9398)
			(end 0.508 -0.9398)
			(stroke
				(width 0)
				(type default)
			)
			(fill no)
			(layer "F.Fab")
		)
		(pad "1" smd custom
			(at 0 -0.4445)
			(size 0.1397 0.1397)
			(layers "F.Cu" "F.Mask" "F.Paste")
			(net "GND")
			(options
				(clearance outline)
				(anchor circle)
			)
			(primitives
				(gr_poly
					(pts
						(arc
							(start -0.1778 -0.2794)
							(mid -0.249642 -0.249642)
							(end -0.2794 -0.1778)
						)
						(arc
							(start -0.2794 0.1778)
							(mid -0.249642 0.249642)
							(end -0.1778 0.2794)
						)
						(arc
							(start 0.1778 0.2794)
							(mid 0.249642 0.249642)
							(end 0.2794 0.1778)
						)
						(arc
							(start 0.2794 -0.1778)
							(mid 0.249642 -0.249642)
							(end 0.1778 -0.2794)
						)
					)
					(width 0)
					(fill yes)
				)
			)
		)
		(pad "2" smd custom
			(at 0 0.4445)
			(size 0.1397 0.1397)
			(layers "F.Cu" "F.Mask" "F.Paste")
			(net "MAC2_TXCTL")
			(options
				(clearance outline)
				(anchor circle)
			)
			(primitives
				(gr_poly
					(pts
						(arc
							(start -0.1778 -0.2794)
							(mid -0.249642 -0.249642)
							(end -0.2794 -0.1778)
						)
						(arc
							(start -0.2794 0.1778)
							(mid -0.249642 0.249642)
							(end -0.1778 0.2794)
						)
						(arc
							(start 0.1778 0.2794)
							(mid 0.249642 0.249642)
							(end 0.2794 0.1778)
						)
						(arc
							(start 0.2794 -0.1778)
							(mid 0.249642 -0.249642)
							(end 0.1778 -0.2794)
						)
					)
					(width 0)
					(fill yes)
				)
			)
		)
	)
	(footprint ""
		(layer "F.Cu")
		(at 63.9826 -172.212 180)
		(property "Reference" "R71"
			(at 0 0 180)
			(layer "F.SilkS")
			(hide yes)
			(effects
				(font
					(size 1.27 1.27)
				)
			)
		)
		(property "Value" "4K75R2F-1-GP"
			(at 0.064008 -3.993896 180)
			(unlocked yes)
			(layer "F.Fab")
			(hide yes)
			(effects
				(font
					(size 1.016 1.016)
					(thickness 0.1524)
				)
			)
		)
		(property "Device Type" "R402H16"
			(at 0.064008 -5.517896 180)
			(unlocked yes)
			(layer "F.Fab")
			(hide yes)
			(effects
				(font
					(size 1.016 1.016)
					(thickness 0.1524)
				)
			)
		)
		(duplicate_pad_numbers_are_jumpers no)
		(fp_line
			(start 0.508 -0.9398)
			(end -0.508 -0.9398)
			(stroke
				(width 0.1524)
				(type default)
			)
			(layer "F.SilkS")
		)
		(fp_line
			(start -0.508 -0.9398)
			(end -0.508 0.9398)
			(stroke
				(width 0.1524)
				(type default)
			)
			(layer "F.SilkS")
		)
		(fp_rect
			(start -0.508 0.9398)
			(end 0.508 -0.9398)
			(stroke
				(width 0)
				(type default)
			)
			(fill no)
			(layer "F.CrtYd")
		)
		(fp_rect
			(start -0.508 0.9398)
			(end 0.508 -0.9398)
			(stroke
				(width 0)
				(type default)
			)
			(fill no)
			(layer "F.Fab")
		)
		(pad "1" smd custom
			(at 0 -0.4445 180)
			(size 0.1397 0.1397)
			(layers "F.Cu" "F.Mask" "F.Paste")
			(net "P3V3_STBY")
			(options
				(clearance outline)
				(anchor circle)
			)
			(primitives
				(gr_poly
					(pts
						(arc
							(start -0.1778 -0.2794)
							(mid -0.249642 -0.249642)
							(end -0.2794 -0.1778)
						)
						(arc
							(start -0.2794 0.1778)
							(mid -0.249642 0.249642)
							(end -0.1778 0.2794)
						)
						(arc
							(start 0.1778 0.2794)
							(mid 0.249642 0.249642)
							(end 0.2794 0.1778)
						)
						(arc
							(start 0.2794 -0.1778)
							(mid 0.249642 -0.249642)
							(end 0.1778 -0.2794)
						)
					)
					(width 0)
					(fill yes)
				)
			)
		)
		(pad "2" smd custom
			(at 0 0.4445 180)
			(size 0.1397 0.1397)
			(layers "F.Cu" "F.Mask" "F.Paste")
			(net "FM_TPM_PRSNT_RST_N_C")
			(options
				(clearance outline)
				(anchor circle)
			)
			(primitives
				(gr_poly
					(pts
						(arc
							(start -0.1778 -0.2794)
							(mid -0.249642 -0.249642)
							(end -0.2794 -0.1778)
						)
						(arc
							(start -0.2794 0.1778)
							(mid -0.249642 0.249642)
							(end -0.1778 0.2794)
						)
						(arc
							(start 0.1778 0.2794)
							(mid 0.249642 0.249642)
							(end 0.2794 0.1778)
						)
						(arc
							(start 0.2794 -0.1778)
							(mid 0.249642 -0.249642)
							(end 0.1778 -0.2794)
						)
					)
					(width 0)
					(fill yes)
				)
			)
		)
	)
	(footprint ""
		(layer "F.Cu")
		(at 124.841 -7.62 -90)
		(property "Reference" "R438"
			(at 0 0 270)
			(layer "F.SilkS")
			(hide yes)
			(effects
				(font
					(size 1.27 1.27)
				)
			)
		)
		(property "Value" "10KR2J-3-GP"
			(at 0.064008 -3.993896 270)
			(unlocked yes)
			(layer "F.Fab")
			(hide yes)
			(effects
				(font
					(size 1.016 1.016)
					(thickness 0.1524)
				)
			)
		)
		(property "Device Type" "R402H16"
			(at 0.064008 -5.517896 270)
			(unlocked yes)
			(layer "F.Fab")
			(hide yes)
			(effects
				(font
					(size 1.016 1.016)
					(thickness 0.1524)
				)
			)
		)
		(duplicate_pad_numbers_are_jumpers no)
		(fp_line
			(start -0.508 -0.9398)
			(end -0.508 0.9398)
			(stroke
				(width 0.1524)
				(type default)
			)
			(layer "F.SilkS")
		)
		(fp_line
			(start 0.508 -0.9398)
			(end -0.508 -0.9398)
			(stroke
				(width 0.1524)
				(type default)
			)
			(layer "F.SilkS")
		)
		(fp_rect
			(start -0.508 0.9398)
			(end 0.508 -0.9398)
			(stroke
				(width 0)
				(type default)
			)
			(fill no)
			(layer "F.CrtYd")
		)
		(fp_rect
			(start -0.508 0.9398)
			(end 0.508 -0.9398)
			(stroke
				(width 0)
				(type default)
			)
			(fill no)
			(layer "F.Fab")
		)
		(pad "1" smd custom
			(at 0 -0.4445 270)
			(size 0.1397 0.1397)
			(layers "F.Cu" "F.Mask" "F.Paste")
			(net "GND")
			(options
				(clearance outline)
				(anchor circle)
			)
			(primitives
				(gr_poly
					(pts
						(arc
							(start -0.1778 -0.2794)
							(mid -0.249642 -0.249642)
							(end -0.2794 -0.1778)
						)
						(arc
							(start -0.2794 0.1778)
							(mid -0.249642 0.249642)
							(end -0.1778 0.2794)
						)
						(arc
							(start 0.1778 0.2794)
							(mid 0.249642 0.249642)
							(end 0.2794 0.1778)
						)
						(arc
							(start 0.2794 -0.1778)
							(mid 0.249642 -0.249642)
							(end 0.1778 -0.2794)
						)
					)
					(width 0)
					(fill yes)
				)
			)
		)
		(pad "2" smd custom
			(at 0 0.4445 270)
			(size 0.1397 0.1397)
			(layers "F.Cu" "F.Mask" "F.Paste")
			(net "MB0_RETRY_R")
			(options
				(clearance outline)
				(anchor circle)
			)
			(primitives
				(gr_poly
					(pts
						(arc
							(start -0.1778 -0.2794)
							(mid -0.249642 -0.249642)
							(end -0.2794 -0.1778)
						)
						(arc
							(start -0.2794 0.1778)
							(mid -0.249642 0.249642)
							(end -0.1778 0.2794)
						)
						(arc
							(start 0.1778 0.2794)
							(mid 0.249642 0.249642)
							(end 0.2794 0.1778)
						)
						(arc
							(start 0.2794 -0.1778)
							(mid 0.249642 -0.249642)
							(end 0.1778 -0.2794)
						)
					)
					(width 0)
					(fill yes)
				)
			)
		)
	)
	(footprint ""
		(layer "F.Cu")
		(at 156.464 -117.602 180)
		(property "Reference" "G4"
			(at 0 0 180)
			(layer "F.SilkS")
			(hide yes)
			(effects
				(font
					(size 1.27 1.27)
				)
			)
		)
		(property "Value" "GAP-CLOSE-PWR-4-GP"
			(at -2.4638 -0.5461 180)
			(unlocked yes)
			(layer "F.Fab")
			(hide yes)
			(effects
				(font
					(size 1.016 1.016)
					(thickness 0.1524)
				)
			)
		)
		(property "Device Type" "GAP-CLOSE-PWR-4"
			(at -2.4638 -2.0701 180)
			(unlocked yes)
			(layer "F.Fab")
			(hide yes)
			(effects
				(font
					(size 1.016 1.016)
					(thickness 0.1524)
				)
			)
		)
		(duplicate_pad_numbers_are_jumpers no)
		(fp_rect
			(start -0.2794 0.254)
			(end 0.2794 -0.254)
			(stroke
				(width 0)
				(type default)
			)
			(fill no)
			(layer "F.CrtYd")
		)
		(fp_rect
			(start -0.2794 0.254)
			(end 0.2794 -0.254)
			(stroke
				(width 0)
				(type default)
			)
			(fill no)
			(layer "F.Fab")
		)
		(pad "1" smd rect
			(at -0.0635 0 180)
			(size 0.1778 0.254)
			(layers "F.Cu" "F.Mask" "F.Paste")
			(net "P1V8_STBY")
		)
		(pad "2" smd rect
			(at 0.0635 0 180)
			(size 0.1778 0.254)
			(layers "F.Cu" "F.Mask" "F.Paste")
			(net "P1V8_STBY_CC")
		)
	)
	(footprint ""
		(layer "F.Cu")
		(at 153.926032 -94.852998 90)
		(property "Reference" "R638"
			(at 0 0 90)
			(layer "F.SilkS")
			(hide yes)
			(effects
				(font
					(size 1.27 1.27)
				)
			)
		)
		(property "Value" "4K7R2F-GP"
			(at 0.064008 -3.993896 90)
			(unlocked yes)
			(layer "F.Fab")
			(hide yes)
			(effects
				(font
					(size 1.016 1.016)
					(thickness 0.1524)
				)
			)
		)
		(property "Device Type" "R402H16"
			(at 0.064008 -5.517896 90)
			(unlocked yes)
			(layer "F.Fab")
			(hide yes)
			(effects
				(font
					(size 1.016 1.016)
					(thickness 0.1524)
				)
			)
		)
		(duplicate_pad_numbers_are_jumpers no)
		(fp_line
			(start 0.508 -0.9398)
			(end -0.508 -0.9398)
			(stroke
				(width 0.1524)
				(type default)
			)
			(layer "F.SilkS")
		)
		(fp_line
			(start -0.508 -0.9398)
			(end -0.508 0.9398)
			(stroke
				(width 0.1524)
				(type default)
			)
			(layer "F.SilkS")
		)
		(fp_rect
			(start -0.508 0.9398)
			(end 0.508 -0.9398)
			(stroke
				(width 0)
				(type default)
			)
			(fill no)
			(layer "F.CrtYd")
		)
		(fp_rect
			(start -0.508 0.9398)
			(end 0.508 -0.9398)
			(stroke
				(width 0)
				(type default)
			)
			(fill no)
			(layer "F.Fab")
		)
		(pad "1" smd custom
			(at 0 -0.4445 90)
			(size 0.1397 0.1397)
			(layers "F.Cu" "F.Mask" "F.Paste")
			(net "SYS_RST_N_0")
			(options
				(clearance outline)
				(anchor circle)
			)
			(primitives
				(gr_poly
					(pts
						(arc
							(start -0.1778 -0.2794)
							(mid -0.249642 -0.249642)
							(end -0.2794 -0.1778)
						)
						(arc
							(start -0.2794 0.1778)
							(mid -0.249642 0.249642)
							(end -0.1778 0.2794)
						)
						(arc
							(start 0.1778 0.2794)
							(mid 0.249642 0.249642)
							(end 0.2794 0.1778)
						)
						(arc
							(start 0.2794 -0.1778)
							(mid 0.249642 -0.249642)
							(end 0.1778 -0.2794)
						)
					)
					(width 0)
					(fill yes)
				)
			)
		)
		(pad "2" smd custom
			(at 0 0.4445 90)
			(size 0.1397 0.1397)
			(layers "F.Cu" "F.Mask" "F.Paste")
			(net "P1V8")
			(options
				(clearance outline)
				(anchor circle)
			)
			(primitives
				(gr_poly
					(pts
						(arc
							(start -0.1778 -0.2794)
							(mid -0.249642 -0.249642)
							(end -0.2794 -0.1778)
						)
						(arc
							(start -0.2794 0.1778)
							(mid -0.249642 0.249642)
							(end -0.1778 0.2794)
						)
						(arc
							(start 0.1778 0.2794)
							(mid 0.249642 0.249642)
							(end 0.2794 0.1778)
						)
						(arc
							(start 0.2794 -0.1778)
							(mid 0.249642 -0.249642)
							(end 0.1778 -0.2794)
						)
					)
					(width 0)
					(fill yes)
				)
			)
		)
	)
	(footprint ""
		(layer "F.Cu")
		(at 16.023336 -163.5506 -90)
		(property "Reference" "C222"
			(at 0 0 270)
			(layer "F.SilkS")
			(hide yes)
			(effects
				(font
					(size 1.27 1.27)
				)
			)
		)
		(property "Value" "SC1KP50V2KX-1GP"
			(at 1.1811 -2.7051 270)
			(unlocked yes)
			(layer "F.Fab")
			(hide yes)
			(effects
				(font
					(size 1.016 1.016)
					(thickness 0.1524)
				)
			)
		)
		(property "Device Type" "C402H22"
			(at 1.1811 -4.2291 270)
			(unlocked yes)
			(layer "F.Fab")
			(hide yes)
			(effects
				(font
					(size 1.016 1.016)
					(thickness 0.1524)
				)
			)
		)
		(duplicate_pad_numbers_are_jumpers no)
		(fp_rect
			(start -0.4318 0.9525)
			(end 0.4318 -0.9525)
			(stroke
				(width 0)
				(type default)
			)
			(fill no)
			(layer "F.CrtYd")
		)
		(fp_rect
			(start -0.4318 0.9525)
			(end 0.4318 -0.9525)
			(stroke
				(width 0)
				(type default)
			)
			(fill no)
			(layer "F.Fab")
		)
		(pad "1" smd custom
			(at 0 -0.4445 270)
			(size 0.1524 0.1524)
			(layers "F.Cu" "F.Mask" "F.Paste")
			(net "TPS74801_P1V2_STBY_OUT")
			(options
				(clearance outline)
				(anchor circle)
			)
			(primitives
				(gr_poly
					(pts
						(arc
							(start 0.3048 -0.2032)
							(mid 0.275042 -0.275042)
							(end 0.2032 -0.3048)
						)
						(arc
							(start -0.2032 -0.3048)
							(mid -0.275042 -0.275042)
							(end -0.3048 -0.2032)
						)
						(arc
							(start -0.3048 0.2032)
							(mid -0.275042 0.275042)
							(end -0.2032 0.3048)
						)
						(arc
							(start 0.2032 0.3048)
							(mid 0.275042 0.275042)
							(end 0.3048 0.2032)
						)
					)
					(width 0)
					(fill yes)
				)
			)
		)
		(pad "2" smd custom
			(at 0 0.4445 270)
			(size 0.1524 0.1524)
			(layers "F.Cu" "F.Mask" "F.Paste")
			(net "TPS74801_P1V2_STBY_FB")
			(options
				(clearance outline)
				(anchor circle)
			)
			(primitives
				(gr_poly
					(pts
						(arc
							(start 0.3048 -0.2032)
							(mid 0.275042 -0.275042)
							(end 0.2032 -0.3048)
						)
						(arc
							(start -0.2032 -0.3048)
							(mid -0.275042 -0.275042)
							(end -0.3048 -0.2032)
						)
						(arc
							(start -0.3048 0.2032)
							(mid -0.275042 0.275042)
							(end -0.2032 0.3048)
						)
						(arc
							(start 0.2032 0.3048)
							(mid 0.275042 0.275042)
							(end 0.3048 0.2032)
						)
					)
					(width 0)
					(fill yes)
				)
			)
		)
	)
	(footprint ""
		(layer "F.Cu")
		(at 192.79997 -65.099946 180)
		(property "Reference" "U1"
			(at 0 0 180)
			(layer "F.SilkS")
			(hide yes)
			(effects
				(font
					(size 1.27 1.27)
				)
			)
		)
		(property "Value" "SAS3008C0-1-DB-500020657-1-GP"
			(at -20.374102 -5.0292 180)
			(unlocked yes)
			(layer "F.Fab")
			(hide yes)
			(effects
				(font
					(size 1.016 1.016)
					(thickness 0.1524)
				)
			)
		)
		(property "Device Type" "BGA896D25H78"
			(at -20.374102 -6.5532 180)
			(unlocked yes)
			(layer "F.Fab")
			(hide yes)
			(effects
				(font
					(size 1.016 1.016)
					(thickness 0.1524)
				)
			)
		)
		(duplicate_pad_numbers_are_jumpers no)
		(fp_line
			(start 12.500102 12.030202)
			(end 12.500102 10.86993)
			(stroke
				(width 0.1524)
				(type default)
			)
			(layer "F.SilkS")
		)
		(fp_line
			(start 12.500102 -9.93013)
			(end 12.500102 9.93013)
			(stroke
				(width 0.1524)
				(type default)
			)
			(layer "F.SilkS")
		)
		(fp_line
			(start 12.500102 -12.030202)
			(end 12.500102 -10.86993)
			(stroke
				(width 0.1524)
				(type default)
			)
			(layer "F.SilkS")
		)
		(fp_line
			(start 12.030202 12.500102)
			(end 10.86993 12.500102)
			(stroke
				(width 0.1524)
				(type default)
			)
			(layer "F.SilkS")
		)
		(fp_line
			(start 12.030202 -12.500102)
			(end 10.86993 -12.500102)
			(stroke
				(width 0.1524)
				(type default)
			)
			(layer "F.SilkS")
		)
		(fp_line
			(start 9.93013 12.500102)
			(end -9.93013 12.500102)
			(stroke
				(width 0.1524)
				(type default)
			)
			(layer "F.SilkS")
		)
		(fp_line
			(start 9.93013 -12.500102)
			(end -9.93013 -12.500102)
			(stroke
				(width 0.1524)
				(type default)
			)
			(layer "F.SilkS")
		)
		(fp_line
			(start -12.030202 12.500102)
			(end -10.86993 12.500102)
			(stroke
				(width 0.1524)
				(type default)
			)
			(layer "F.SilkS")
		)
		(fp_line
			(start -12.030202 -12.500102)
			(end -10.86993 -12.500102)
			(stroke
				(width 0.1524)
				(type default)
			)
			(layer "F.SilkS")
		)
		(fp_line
			(start -12.500102 12.030202)
			(end -12.500102 10.86993)
			(stroke
				(width 0.1524)
				(type default)
			)
			(layer "F.SilkS")
		)
		(fp_line
			(start -12.500102 -9.93013)
			(end -12.500102 9.93013)
			(stroke
				(width 0.1524)
				(type default)
			)
			(layer "F.SilkS")
		)
		(fp_line
			(start -12.500102 -12.030202)
			(end -12.500102 -10.86993)
			(stroke
				(width 0.1524)
				(type default)
			)
			(layer "F.SilkS")
		)
		(fp_circle
			(center 12.500102 12.500102)
			(end 12.030202 12.500102)
			(stroke
				(width 0.1524)
				(type default)
			)
			(fill no)
			(layer "F.SilkS")
		)
		(fp_circle
			(center 12.500102 10.40003)
			(end 12.030202 10.40003)
			(stroke
				(width 0.1524)
				(type default)
			)
			(fill no)
			(layer "F.SilkS")
		)
		(fp_circle
			(center 12.500102 -10.40003)
			(end 12.030202 -10.40003)
			(stroke
				(width 0.1524)
				(type default)
			)
			(fill no)
			(layer "F.SilkS")
		)
		(fp_circle
			(center 12.500102 -12.500102)
			(end 12.030202 -12.500102)
			(stroke
				(width 0.1524)
				(type default)
			)
			(fill no)
			(layer "F.SilkS")
		)
		(fp_circle
			(center 10.40003 12.500102)
			(end 9.93013 12.500102)
			(stroke
				(width 0.1524)
				(type default)
			)
			(fill no)
			(layer "F.SilkS")
		)
		(fp_circle
			(center 10.40003 -12.500102)
			(end 9.93013 -12.500102)
			(stroke
				(width 0.1524)
				(type default)
			)
			(fill no)
			(layer "F.SilkS")
		)
		(fp_circle
			(center -10.40003 12.500102)
			(end -10.86993 12.500102)
			(stroke
				(width 0.1524)
				(type default)
			)
			(fill no)
			(layer "F.SilkS")
		)
		(fp_circle
			(center -10.40003 -12.500102)
			(end -10.86993 -12.500102)
			(stroke
				(width 0.1524)
				(type default)
			)
			(fill no)
			(layer "F.SilkS")
		)
		(fp_circle
			(center -12.500102 12.500102)
			(end -12.970002 12.500102)
			(stroke
				(width 0.1524)
				(type default)
			)
			(fill no)
			(layer "F.SilkS")
		)
		(fp_circle
			(center -12.500102 10.40003)
			(end -12.970002 10.40003)
			(stroke
				(width 0.1524)
				(type default)
			)
			(fill no)
			(layer "F.SilkS")
		)
		(fp_circle
			(center -12.500102 -10.40003)
			(end -12.970002 -10.40003)
			(stroke
				(width 0.1524)
				(type default)
			)
			(fill no)
			(layer "F.SilkS")
		)
		(fp_circle
			(center -12.500102 -12.500102)
			(end -12.970002 -12.500102)
			(stroke
				(width 0.1524)
				(type default)
			)
			(fill no)
			(layer "F.SilkS")
		)
		(fp_poly
			(pts
				(xy -12.931902 -12.931902) (xy -12.931902 -14.455902) (xy -14.455902 -12.931902)
			)
			(stroke
				(width 0)
				(type default)
			)
			(fill yes)
			(layer "F.SilkS")
		)
		(fp_rect
			(start -12.500102 12.500102)
			(end 12.500102 -12.500102)
			(stroke
				(width 0)
				(type default)
			)
			(fill no)
			(layer "F.CrtYd")
		)
		(fp_poly
			(pts
				(xy 13.5001 -12.500102) (xy -12.500102 -12.500102) (xy -12.500102 12.500102) (xy 12.500102 12.500102)
				(xy 12.500102 -12.487402) (xy 13.5001 -12.487402) (xy 13.5001 13.5001) (xy -13.5001 13.5001) (xy -13.5001 -13.5001)
				(xy 13.5001 -13.5001)
			)
			(stroke
				(width 0)
				(type default)
			)
			(fill no)
			(layer "F.CrtYd")
		)
		(fp_rect
			(start -14.500098 14.500098)
			(end 14.500098 -14.500098)
			(stroke
				(width 0)
				(type default)
			)
			(fill no)
			(layer "F.Fab")
		)
		(pad "A2" smd circle
			(at -10.80008 -11.599926 180)
			(size 0.4064 0.4064)
			(layers "F.Cu" "F.Mask" "F.Paste")
			(net "Net_1211")
		)
		(pad "A3" smd circle
			(at -9.99998 -11.599926 180)
			(size 0.4064 0.4064)
			(layers "F.Cu" "F.Mask" "F.Paste")
			(net "Net_1212")
		)
		(pad "A4" smd circle
			(at -9.19988 -11.599926 180)
			(size 0.3556 0.3556)
			(layers "F.Cu" "F.Mask" "F.Paste")
			(net "GND")
		)
		(pad "A5" smd circle
			(at -8.400034 -11.599926 180)
			(size 0.3556 0.3556)
			(layers "F.Cu" "F.Mask" "F.Paste")
			(net "Net_1213")
		)
		(pad "A6" smd circle
			(at -7.599934 -11.599926 180)
			(size 0.3556 0.3556)
			(layers "F.Cu" "F.Mask" "F.Paste")
			(net "ICE1_TMS")
		)
		(pad "A7" smd circle
			(at -6.800088 -11.599926 180)
			(size 0.3556 0.3556)
			(layers "F.Cu" "F.Mask" "F.Paste")
			(net "Net_1214")
		)
		(pad "A8" smd circle
			(at -5.999988 -11.599926 180)
			(size 0.3556 0.3556)
			(layers "F.Cu" "F.Mask" "F.Paste")
			(net "ICE0_TRST#")
		)
		(pad "A9" smd circle
			(at -5.199888 -11.599926 180)
			(size 0.3556 0.3556)
			(layers "F.Cu" "F.Mask" "F.Paste")
			(net "ICE0_TCK")
		)
		(pad "A10" smd circle
			(at -4.400042 -11.599926 180)
			(size 0.3556 0.3556)
			(layers "F.Cu" "F.Mask" "F.Paste")
			(net "ICE1_TDO")
		)
		(pad "A11" smd circle
			(at -3.599942 -11.599926 180)
			(size 0.3556 0.3556)
			(layers "F.Cu" "F.Mask" "F.Paste")
			(net "GND")
		)
		(pad "A12" smd circle
			(at -2.800096 -11.599926 180)
			(size 0.3556 0.3556)
			(layers "F.Cu" "F.Mask" "F.Paste")
			(net "Net_1204")
		)
		(pad "A13" smd circle
			(at -1.999996 -11.599926 180)
			(size 0.3556 0.3556)
			(layers "F.Cu" "F.Mask" "F.Paste")
			(net "PWRGD_P0V975")
		)
		(pad "A14" smd circle
			(at -1.199896 -11.599926 180)
			(size 0.3556 0.3556)
			(layers "F.Cu" "F.Mask" "F.Paste")
			(net "HM40ADC_VDDA")
		)
		(pad "A15" smd circle
			(at -0.40005 -11.599926 180)
			(size 0.3556 0.3556)
			(layers "F.Cu" "F.Mask" "F.Paste")
			(net "GND")
		)
		(pad "A16" smd circle
			(at 0.40005 -11.599926 180)
			(size 0.3556 0.3556)
			(layers "F.Cu" "F.Mask" "F.Paste")
			(net "IOC_TRST_N")
		)
		(pad "A17" smd circle
			(at 1.199896 -11.599926 180)
			(size 0.3556 0.3556)
			(layers "F.Cu" "F.Mask" "F.Paste")
			(net "JTAG_IOC_TDI")
		)
		(pad "A18" smd circle
			(at 1.999996 -11.599926 180)
			(size 0.3556 0.3556)
			(layers "F.Cu" "F.Mask" "F.Paste")
			(net "LSI_IDDT")
		)
		(pad "A19" smd circle
			(at 2.800096 -11.599926 180)
			(size 0.3556 0.3556)
			(layers "F.Cu" "F.Mask" "F.Paste")
			(net "Net_1205")
		)
		(pad "A20" smd circle
			(at 3.599942 -11.599926 180)
			(size 0.3556 0.3556)
			(layers "F.Cu" "F.Mask" "F.Paste")
			(net "Net_1206")
		)
		(pad "A21" smd circle
			(at 4.400042 -11.599926 180)
			(size 0.3556 0.3556)
			(layers "F.Cu" "F.Mask" "F.Paste")
			(net "XM_NOR_CS_N")
		)
		(pad "A22" smd circle
			(at 5.199888 -11.599926 180)
			(size 0.3556 0.3556)
			(layers "F.Cu" "F.Mask" "F.Paste")
			(net "XM_RB")
		)
		(pad "A23" smd circle
			(at 5.999988 -11.599926 180)
			(size 0.3556 0.3556)
			(layers "F.Cu" "F.Mask" "F.Paste")
			(net "Net_1200")
		)
		(pad "A24" smd circle
			(at 6.800088 -11.599926 180)
			(size 0.3556 0.3556)
			(layers "F.Cu" "F.Mask" "F.Paste")
			(net "XM_WE_N")
		)
		(pad "A25" smd circle
			(at 7.599934 -11.599926 180)
			(size 0.3556 0.3556)
			(layers "F.Cu" "F.Mask" "F.Paste")
			(net "XM_WP")
		)
		(pad "A26" smd circle
			(at 8.400034 -11.599926 180)
			(size 0.3556 0.3556)
			(layers "F.Cu" "F.Mask" "F.Paste")
			(net "XM_ADDR_3")
		)
		(pad "A27" smd circle
			(at 9.19988 -11.599926 180)
			(size 0.3556 0.3556)
			(layers "F.Cu" "F.Mask" "F.Paste")
			(net "Net_1201")
		)
		(pad "A28" smd circle
			(at 9.99998 -11.599926 180)
			(size 0.4064 0.4064)
			(layers "F.Cu" "F.Mask" "F.Paste")
			(net "XM_ADDR_4")
		)
		(pad "A29" smd circle
			(at 10.80008 -11.599926 180)
			(size 0.4064 0.4064)
			(layers "F.Cu" "F.Mask" "F.Paste")
			(net "XM_DATA_11")
		)
		(pad "AA1" smd circle
			(at -11.599926 4.400042 180)
			(size 0.3556 0.3556)
			(layers "F.Cu" "F.Mask" "F.Paste")
			(net "PHY_IOC_TO_CON_B_1_DP_C")
		)
		(pad "AA2" smd circle
			(at -10.80008 4.400042 180)
			(size 0.3556 0.3556)
			(layers "F.Cu" "F.Mask" "F.Paste")
			(net "PHY_IOC_TO_CON_B_1_DN_C")
		)
		(pad "AA3" smd circle
			(at -9.99998 4.400042 180)
			(size 0.3556 0.3556)
			(layers "F.Cu" "F.Mask" "F.Paste")
			(net "GND")
		)
		(pad "AA4" smd circle
			(at -9.19988 4.400042 180)
			(size 0.3556 0.3556)
			(layers "F.Cu" "F.Mask" "F.Paste")
			(net "PHY_CON_B_TO_IOC_1_DP")
		)
		(pad "AA5" smd circle
			(at -8.400034 4.400042 180)
			(size 0.3556 0.3556)
			(layers "F.Cu" "F.Mask" "F.Paste")
			(net "PHY_CON_B_TO_IOC_1_DN")
		)
		(pad "AA6" smd circle
			(at -7.599934 4.400042 180)
			(size 0.3556 0.3556)
			(layers "F.Cu" "F.Mask" "F.Paste")
			(net "GND")
		)
		(pad "AA7" smd circle
			(at -6.800088 4.400042 180)
			(size 0.3556 0.3556)
			(layers "F.Cu" "F.Mask" "F.Paste")
			(net "GND")
		)
		(pad "AA8" smd circle
			(at -5.999988 4.400042 180)
			(size 0.3556 0.3556)
			(layers "F.Cu" "F.Mask" "F.Paste")
			(net "GND")
		)
		(pad "AA9" smd circle
			(at -5.199888 4.400042 180)
			(size 0.3556 0.3556)
			(layers "F.Cu" "F.Mask" "F.Paste")
			(net "GND")
		)
		(pad "AA10" smd circle
			(at -4.400042 4.400042 180)
			(size 0.3556 0.3556)
			(layers "F.Cu" "F.Mask" "F.Paste")
			(net "GND")
		)
		(pad "AA11" smd circle
			(at -3.599942 4.400042 180)
			(size 0.3556 0.3556)
			(layers "F.Cu" "F.Mask" "F.Paste")
			(net "GND")
		)
		(pad "AA12" smd circle
			(at -2.800096 4.400042 180)
			(size 0.3556 0.3556)
			(layers "F.Cu" "F.Mask" "F.Paste")
			(net "GND")
		)
		(pad "AA13" smd circle
			(at -1.999996 4.400042 180)
			(size 0.3556 0.3556)
			(layers "F.Cu" "F.Mask" "F.Paste")
			(net "GND")
		)
		(pad "AA14" smd circle
			(at -1.199896 4.400042 180)
			(size 0.3556 0.3556)
			(layers "F.Cu" "F.Mask" "F.Paste")
			(net "GND")
		)
		(pad "AA15" smd circle
			(at -0.40005 4.400042 180)
			(size 0.3556 0.3556)
			(layers "F.Cu" "F.Mask" "F.Paste")
			(net "GND")
		)
		(pad "AA16" smd circle
			(at 0.40005 4.400042 180)
			(size 0.3556 0.3556)
			(layers "F.Cu" "F.Mask" "F.Paste")
			(net "GND")
		)
		(pad "AA17" smd circle
			(at 1.199896 4.400042 180)
			(size 0.3556 0.3556)
			(layers "F.Cu" "F.Mask" "F.Paste")
			(net "GND")
		)
		(pad "AA18" smd circle
			(at 1.999996 4.400042 180)
			(size 0.3556 0.3556)
			(layers "F.Cu" "F.Mask" "F.Paste")
			(net "GND")
		)
		(pad "AA19" smd circle
			(at 2.800096 4.400042 180)
			(size 0.3556 0.3556)
			(layers "F.Cu" "F.Mask" "F.Paste")
			(net "GND")
		)
		(pad "AA20" smd circle
			(at 3.599942 4.400042 180)
			(size 0.3556 0.3556)
			(layers "F.Cu" "F.Mask" "F.Paste")
			(net "GND")
		)
		(pad "AA21" smd circle
			(at 4.400042 4.400042 180)
			(size 0.3556 0.3556)
			(layers "F.Cu" "F.Mask" "F.Paste")
			(net "GND")
		)
		(pad "AA22" smd circle
			(at 5.199888 4.400042 180)
			(size 0.3556 0.3556)
			(layers "F.Cu" "F.Mask" "F.Paste")
			(net "GND")
		)
		(pad "AA23" smd circle
			(at 5.999988 4.400042 180)
			(size 0.3556 0.3556)
			(layers "F.Cu" "F.Mask" "F.Paste")
			(net "PLL_VDD")
		)
		(pad "AA24" smd circle
			(at 6.800088 4.400042 180)
			(size 0.3556 0.3556)
			(layers "F.Cu" "F.Mask" "F.Paste")
			(net "GND")
		)
		(pad "AA25" smd circle
			(at 7.599934 4.400042 180)
			(size 0.3556 0.3556)
			(layers "F.Cu" "F.Mask" "F.Paste")
			(net "GND")
		)
		(pad "AA26" smd circle
			(at 8.400034 4.400042 180)
			(size 0.3556 0.3556)
			(layers "F.Cu" "F.Mask" "F.Paste")
			(net "GND")
		)
		(pad "AA27" smd circle
			(at 9.19988 4.400042 180)
			(size 0.3556 0.3556)
			(layers "F.Cu" "F.Mask" "F.Paste")
			(net "P1V8")
		)
		(pad "AA28" smd circle
			(at 9.99998 4.400042 180)
			(size 0.3556 0.3556)
			(layers "F.Cu" "F.Mask" "F.Paste")
			(net "IOC_EXT1_LED_B")
		)
		(pad "AA29" smd circle
			(at 10.80008 4.400042 180)
			(size 0.3556 0.3556)
			(layers "F.Cu" "F.Mask" "F.Paste")
			(net "IOC_GPIO_33")
		)
		(pad "AA30" smd circle
			(at 11.599926 4.400042 180)
			(size 0.3556 0.3556)
			(layers "F.Cu" "F.Mask" "F.Paste")
			(net "IOC_EXT1_LED_Y")
		)
		(pad "AB1" smd circle
			(at -11.599926 5.199888 180)
			(size 0.3556 0.3556)
			(layers "F.Cu" "F.Mask" "F.Paste")
			(net "PHY_IOC_TO_CON_B_0_DP_C")
		)
		(pad "AB2" smd circle
			(at -10.80008 5.199888 180)
			(size 0.3556 0.3556)
			(layers "F.Cu" "F.Mask" "F.Paste")
			(net "PHY_IOC_TO_CON_B_0_DN_C")
		)
		(pad "AB3" smd circle
			(at -9.99998 5.199888 180)
			(size 0.3556 0.3556)
			(layers "F.Cu" "F.Mask" "F.Paste")
			(net "GND")
		)
		(pad "AB4" smd circle
			(at -9.19988 5.199888 180)
			(size 0.3556 0.3556)
			(layers "F.Cu" "F.Mask" "F.Paste")
			(net "PHY_CON_B_TO_IOC_0_DP")
		)
		(pad "AB5" smd circle
			(at -8.400034 5.199888 180)
			(size 0.3556 0.3556)
			(layers "F.Cu" "F.Mask" "F.Paste")
			(net "PHY_CON_B_TO_IOC_0_DN")
		)
		(pad "AB6" smd circle
			(at -7.599934 5.199888 180)
			(size 0.3556 0.3556)
			(layers "F.Cu" "F.Mask" "F.Paste")
			(net "GND")
		)
		(pad "AB7" smd circle
			(at -6.800088 5.199888 180)
			(size 0.3556 0.3556)
			(layers "F.Cu" "F.Mask" "F.Paste")
			(net "SAS0_AVDD")
		)
		(pad "AB8" smd circle
			(at -5.999988 5.199888 180)
			(size 0.3556 0.3556)
			(layers "F.Cu" "F.Mask" "F.Paste")
			(net "GND")
		)
		(pad "AB9" smd circle
			(at -5.199888 5.199888 180)
			(size 0.3556 0.3556)
			(layers "F.Cu" "F.Mask" "F.Paste")
			(net "GND")
		)
		(pad "AB10" smd circle
			(at -4.400042 5.199888 180)
			(size 0.3556 0.3556)
			(layers "F.Cu" "F.Mask" "F.Paste")
			(net "GND")
		)
		(pad "AB11" smd circle
			(at -3.599942 5.199888 180)
			(size 0.3556 0.3556)
			(layers "F.Cu" "F.Mask" "F.Paste")
			(net "GND")
		)
		(pad "AB12" smd circle
			(at -2.800096 5.199888 180)
			(size 0.3556 0.3556)
			(layers "F.Cu" "F.Mask" "F.Paste")
			(net "GND")
		)
		(pad "AB13" smd circle
			(at -1.999996 5.199888 180)
			(size 0.3556 0.3556)
			(layers "F.Cu" "F.Mask" "F.Paste")
			(net "GND")
		)
		(pad "AB14" smd circle
			(at -1.199896 5.199888 180)
			(size 0.3556 0.3556)
			(layers "F.Cu" "F.Mask" "F.Paste")
			(net "GND")
		)
		(pad "AB15" smd circle
			(at -0.40005 5.199888 180)
			(size 0.3556 0.3556)
			(layers "F.Cu" "F.Mask" "F.Paste")
			(net "GND")
		)
		(pad "AB16" smd circle
			(at 0.40005 5.199888 180)
			(size 0.3556 0.3556)
			(layers "F.Cu" "F.Mask" "F.Paste")
			(net "GND")
		)
		(pad "AB17" smd circle
			(at 1.199896 5.199888 180)
			(size 0.3556 0.3556)
			(layers "F.Cu" "F.Mask" "F.Paste")
			(net "GND")
		)
		(pad "AB18" smd circle
			(at 1.999996 5.199888 180)
			(size 0.3556 0.3556)
			(layers "F.Cu" "F.Mask" "F.Paste")
			(net "GND")
		)
		(pad "AB19" smd circle
			(at 2.800096 5.199888 180)
			(size 0.3556 0.3556)
			(layers "F.Cu" "F.Mask" "F.Paste")
			(net "GND")
		)
		(pad "AB20" smd circle
			(at 3.599942 5.199888 180)
			(size 0.3556 0.3556)
			(layers "F.Cu" "F.Mask" "F.Paste")
			(net "GND")
		)
		(pad "AB21" smd circle
			(at 4.400042 5.199888 180)
			(size 0.3556 0.3556)
			(layers "F.Cu" "F.Mask" "F.Paste")
			(net "GND")
		)
		(pad "AB22" smd circle
			(at 5.199888 5.199888 180)
			(size 0.3556 0.3556)
			(layers "F.Cu" "F.Mask" "F.Paste")
			(net "GND")
		)
		(pad "AB23" smd circle
			(at 5.999988 5.199888 180)
			(size 0.3556 0.3556)
			(layers "F.Cu" "F.Mask" "F.Paste")
			(net "GND")
		)
		(pad "AB24" smd circle
			(at 6.800088 5.199888 180)
			(size 0.3556 0.3556)
			(layers "F.Cu" "F.Mask" "F.Paste")
			(net "GND")
		)
		(pad "AB25" smd circle
			(at 7.599934 5.199888 180)
			(size 0.3556 0.3556)
			(layers "F.Cu" "F.Mask" "F.Paste")
			(net "GND")
		)
		(pad "AB26" smd circle
			(at 8.400034 5.199888 180)
			(size 0.3556 0.3556)
			(layers "F.Cu" "F.Mask" "F.Paste")
			(net "P1V8")
		)
		(pad "AB27" smd circle
			(at 9.19988 5.199888 180)
			(size 0.3556 0.3556)
			(layers "F.Cu" "F.Mask" "F.Paste")
			(net "GND")
		)
		(pad "AB28" smd circle
			(at 9.99998 5.199888 180)
			(size 0.3556 0.3556)
			(layers "F.Cu" "F.Mask" "F.Paste")
			(net "IOC_GPIO_34")
		)
		(pad "AB29" smd circle
			(at 10.80008 5.199888 180)
			(size 0.3556 0.3556)
			(layers "F.Cu" "F.Mask" "F.Paste")
			(net "IOC_GPIO_23")
		)
		(pad "AB30" smd circle
			(at 11.599926 5.199888 180)
			(size 0.3556 0.3556)
			(layers "F.Cu" "F.Mask" "F.Paste")
			(net "IOC_GPIO_35")
		)
		(pad "AC1" smd circle
			(at -11.599926 5.999988 180)
			(size 0.3556 0.3556)
			(layers "F.Cu" "F.Mask" "F.Paste")
			(net "SAS0_VDDH")
		)
		(pad "AC2" smd circle
			(at -10.80008 5.999988 180)
			(size 0.3556 0.3556)
			(layers "F.Cu" "F.Mask" "F.Paste")
			(net "GND")
		)
		(pad "AC3" smd circle
			(at -9.99998 5.999988 180)
			(size 0.3556 0.3556)
			(layers "F.Cu" "F.Mask" "F.Paste")
			(net "GND")
		)
		(pad "AC4" smd circle
			(at -9.19988 5.999988 180)
			(size 0.3556 0.3556)
			(layers "F.Cu" "F.Mask" "F.Paste")
			(net "SAS0_AVDD")
		)
		(pad "AC5" smd circle
			(at -8.400034 5.999988 180)
			(size 0.3556 0.3556)
			(layers "F.Cu" "F.Mask" "F.Paste")
			(net "GND")
		)
		(pad "AC6" smd circle
			(at -7.599934 5.999988 180)
			(size 0.3556 0.3556)
			(layers "F.Cu" "F.Mask" "F.Paste")
			(net "SAS0_VDDH")
		)
		(pad "AC7" smd circle
			(at -6.800088 5.999988 180)
			(size 0.3556 0.3556)
			(layers "F.Cu" "F.Mask" "F.Paste")
			(net "GND")
		)
		(pad "AC8" smd circle
			(at -5.999988 5.999988 180)
			(size 0.3556 0.3556)
			(layers "F.Cu" "F.Mask" "F.Paste")
			(net "GND")
		)
		(pad "AC9" smd circle
			(at -5.199888 5.999988 180)
			(size 0.3556 0.3556)
			(layers "F.Cu" "F.Mask" "F.Paste")
			(net "GND")
		)
		(pad "AC10" smd circle
			(at -4.400042 5.999988 180)
			(size 0.3556 0.3556)
			(layers "F.Cu" "F.Mask" "F.Paste")
			(net "GND")
		)
		(pad "AC11" smd circle
			(at -3.599942 5.999988 180)
			(size 0.3556 0.3556)
			(layers "F.Cu" "F.Mask" "F.Paste")
			(net "PCE_AVDD")
		)
		(pad "AC12" smd circle
			(at -2.800096 5.999988 180)
			(size 0.3556 0.3556)
			(layers "F.Cu" "F.Mask" "F.Paste")
			(net "GND")
		)
		(pad "AC13" smd circle
			(at -1.999996 5.999988 180)
			(size 0.3556 0.3556)
			(layers "F.Cu" "F.Mask" "F.Paste")
			(net "GND")
		)
		(pad "AC14" smd circle
			(at -1.199896 5.999988 180)
			(size 0.3556 0.3556)
			(layers "F.Cu" "F.Mask" "F.Paste")
			(net "GND")
		)
		(pad "AC15" smd circle
			(at -0.40005 5.999988 180)
			(size 0.3556 0.3556)
			(layers "F.Cu" "F.Mask" "F.Paste")
			(net "GND")
		)
		(pad "AC16" smd circle
			(at 0.40005 5.999988 180)
			(size 0.3556 0.3556)
			(layers "F.Cu" "F.Mask" "F.Paste")
			(net "GND")
		)
		(pad "AC17" smd circle
			(at 1.199896 5.999988 180)
			(size 0.3556 0.3556)
			(layers "F.Cu" "F.Mask" "F.Paste")
			(net "GND")
		)
		(pad "AC18" smd circle
			(at 1.999996 5.999988 180)
			(size 0.3556 0.3556)
			(layers "F.Cu" "F.Mask" "F.Paste")
			(net "GND")
		)
		(pad "AC19" smd circle
			(at 2.800096 5.999988 180)
			(size 0.3556 0.3556)
			(layers "F.Cu" "F.Mask" "F.Paste")
			(net "GND")
		)
		(pad "AC20" smd circle
			(at 3.599942 5.999988 180)
			(size 0.3556 0.3556)
			(layers "F.Cu" "F.Mask" "F.Paste")
			(net "GND")
		)
		(pad "AC21" smd circle
			(at 4.400042 5.999988 180)
			(size 0.3556 0.3556)
			(layers "F.Cu" "F.Mask" "F.Paste")
			(net "GND")
		)
		(pad "AC22" smd circle
			(at 5.199888 5.999988 180)
			(size 0.3556 0.3556)
			(layers "F.Cu" "F.Mask" "F.Paste")
			(net "GND")
		)
		(pad "AC23" smd circle
			(at 5.999988 5.999988 180)
			(size 0.3556 0.3556)
			(layers "F.Cu" "F.Mask" "F.Paste")
			(net "GND")
		)
		(pad "AC24" smd circle
			(at 6.800088 5.999988 180)
			(size 0.3556 0.3556)
			(layers "F.Cu" "F.Mask" "F.Paste")
			(net "GND")
		)
		(pad "AC25" smd circle
			(at 7.599934 5.999988 180)
			(size 0.3556 0.3556)
			(layers "F.Cu" "F.Mask" "F.Paste")
			(net "GND")
		)
		(pad "AC26" smd circle
			(at 8.400034 5.999988 180)
			(size 0.3556 0.3556)
			(layers "F.Cu" "F.Mask" "F.Paste")
			(net "GND")
		)
		(pad "AC27" smd circle
			(at 9.19988 5.999988 180)
			(size 0.3556 0.3556)
			(layers "F.Cu" "F.Mask" "F.Paste")
			(net "P1V8")
		)
		(pad "AC28" smd circle
			(at 9.99998 5.999988 180)
			(size 0.3556 0.3556)
			(layers "F.Cu" "F.Mask" "F.Paste")
			(net "IOC_GPIO_28")
		)
		(pad "AC29" smd circle
			(at 10.80008 5.999988 180)
			(size 0.3556 0.3556)
			(layers "F.Cu" "F.Mask" "F.Paste")
			(net "IOC_GPIO_30")
		)
		(pad "AC30" smd circle
			(at 11.599926 5.999988 180)
			(size 0.3556 0.3556)
			(layers "F.Cu" "F.Mask" "F.Paste")
			(net "IOC_GPIO_8")
		)
		(pad "AD1" smd circle
			(at -11.599926 6.800088 180)
			(size 0.3556 0.3556)
			(layers "F.Cu" "F.Mask" "F.Paste")
			(net "PHY_IOC_TO_CON_A_3_DP_C")
		)
		(pad "AD2" smd circle
			(at -10.80008 6.800088 180)
			(size 0.3556 0.3556)
			(layers "F.Cu" "F.Mask" "F.Paste")
			(net "PHY_IOC_TO_CON_A_3_DN_C")
		)
		(pad "AD3" smd circle
			(at -9.99998 6.800088 180)
			(size 0.3556 0.3556)
			(layers "F.Cu" "F.Mask" "F.Paste")
			(net "GND")
		)
		(pad "AD4" smd circle
			(at -9.19988 6.800088 180)
			(size 0.3556 0.3556)
			(layers "F.Cu" "F.Mask" "F.Paste")
			(net "PHY_CON_A_TO_IOC_3_DP")
		)
		(pad "AD5" smd circle
			(at -8.400034 6.800088 180)
			(size 0.3556 0.3556)
			(layers "F.Cu" "F.Mask" "F.Paste")
			(net "PHY_CON_A_TO_IOC_3_DN")
		)
		(pad "AD6" smd circle
			(at -7.599934 6.800088 180)
			(size 0.3556 0.3556)
			(layers "F.Cu" "F.Mask" "F.Paste")
			(net "GND")
		)
		(pad "AD7" smd circle
			(at -6.800088 6.800088 180)
			(size 0.3556 0.3556)
			(layers "F.Cu" "F.Mask" "F.Paste")
			(net "SAS0_AVDD")
		)
		(pad "AD8" smd circle
			(at -5.999988 6.800088 180)
			(size 0.3556 0.3556)
			(layers "F.Cu" "F.Mask" "F.Paste")
			(net "GND")
		)
		(pad "AD9" smd circle
			(at -5.199888 6.800088 180)
			(size 0.3556 0.3556)
			(layers "F.Cu" "F.Mask" "F.Paste")
			(net "PCE_AVDD")
		)
		(pad "AD10" smd circle
			(at -4.400042 6.800088 180)
			(size 0.3556 0.3556)
			(layers "F.Cu" "F.Mask" "F.Paste")
			(net "GND")
		)
		(pad "AD11" smd circle
			(at -3.599942 6.800088 180)
			(size 0.3556 0.3556)
			(layers "F.Cu" "F.Mask" "F.Paste")
			(net "PCE_AVDD")
		)
		(pad "AD12" smd circle
			(at -2.800096 6.800088 180)
			(size 0.3556 0.3556)
			(layers "F.Cu" "F.Mask" "F.Paste")
			(net "GND")
		)
		(pad "AD13" smd circle
			(at -1.999996 6.800088 180)
			(size 0.3556 0.3556)
			(layers "F.Cu" "F.Mask" "F.Paste")
			(net "PCE_AVDD")
		)
		(pad "AD14" smd circle
			(at -1.199896 6.800088 180)
			(size 0.3556 0.3556)
			(layers "F.Cu" "F.Mask" "F.Paste")
			(net "GND")
		)
		(pad "AD15" smd circle
			(at -0.40005 6.800088 180)
			(size 0.3556 0.3556)
			(layers "F.Cu" "F.Mask" "F.Paste")
			(net "PCE_AVDD")
		)
		(pad "AD16" smd circle
			(at 0.40005 6.800088 180)
			(size 0.3556 0.3556)
			(layers "F.Cu" "F.Mask" "F.Paste")
			(net "GND")
		)
		(pad "AD17" smd circle
			(at 1.199896 6.800088 180)
			(size 0.3556 0.3556)
			(layers "F.Cu" "F.Mask" "F.Paste")
			(net "GND")
		)
		(pad "AD18" smd circle
			(at 1.999996 6.800088 180)
			(size 0.3556 0.3556)
			(layers "F.Cu" "F.Mask" "F.Paste")
			(net "GND")
		)
		(pad "AD19" smd circle
			(at 2.800096 6.800088 180)
			(size 0.3556 0.3556)
			(layers "F.Cu" "F.Mask" "F.Paste")
			(net "GND")
		)
		(pad "AD20" smd circle
			(at 3.599942 6.800088 180)
			(size 0.3556 0.3556)
			(layers "F.Cu" "F.Mask" "F.Paste")
			(net "GND")
		)
		(pad "AD21" smd circle
			(at 4.400042 6.800088 180)
			(size 0.3556 0.3556)
			(layers "F.Cu" "F.Mask" "F.Paste")
			(net "GND")
		)
		(pad "AD22" smd circle
			(at 5.199888 6.800088 180)
			(size 0.3556 0.3556)
			(layers "F.Cu" "F.Mask" "F.Paste")
			(net "GND")
		)
		(pad "AD23" smd circle
			(at 5.999988 6.800088 180)
			(size 0.3556 0.3556)
			(layers "F.Cu" "F.Mask" "F.Paste")
			(net "GND")
		)
		(pad "AD24" smd circle
			(at 6.800088 6.800088 180)
			(size 0.3556 0.3556)
			(layers "F.Cu" "F.Mask" "F.Paste")
			(net "GND")
		)
		(pad "AD25" smd circle
			(at 7.599934 6.800088 180)
			(size 0.3556 0.3556)
			(layers "F.Cu" "F.Mask" "F.Paste")
			(net "GND")
		)
		(pad "AD26" smd circle
			(at 8.400034 6.800088 180)
			(size 0.3556 0.3556)
			(layers "F.Cu" "F.Mask" "F.Paste")
			(net "P1V8")
		)
		(pad "AD27" smd circle
			(at 9.19988 6.800088 180)
			(size 0.3556 0.3556)
			(layers "F.Cu" "F.Mask" "F.Paste")
			(net "GND")
		)
		(pad "AD28" smd circle
			(at 9.99998 6.800088 180)
			(size 0.3556 0.3556)
			(layers "F.Cu" "F.Mask" "F.Paste")
			(net "IOC_GPIO_29")
		)
		(pad "AD29" smd circle
			(at 10.80008 6.800088 180)
			(size 0.3556 0.3556)
			(layers "F.Cu" "F.Mask" "F.Paste")
			(net "IOC_GPIO_27")
		)
		(pad "AD30" smd circle
			(at 11.599926 6.800088 180)
			(size 0.3556 0.3556)
			(layers "F.Cu" "F.Mask" "F.Paste")
			(net "IOC_GPIO_17")
		)
		(pad "AE1" smd circle
			(at -11.599926 7.599934 180)
			(size 0.3556 0.3556)
			(layers "F.Cu" "F.Mask" "F.Paste")
			(net "PHY_IOC_TO_CON_A_2_DP_C")
		)
		(pad "AE2" smd circle
			(at -10.80008 7.599934 180)
			(size 0.3556 0.3556)
			(layers "F.Cu" "F.Mask" "F.Paste")
			(net "PHY_IOC_TO_CON_A_2_DN_C")
		)
		(pad "AE3" smd circle
			(at -9.99998 7.599934 180)
			(size 0.3556 0.3556)
			(layers "F.Cu" "F.Mask" "F.Paste")
			(net "GND")
		)
		(pad "AE4" smd circle
			(at -9.19988 7.599934 180)
			(size 0.3556 0.3556)
			(layers "F.Cu" "F.Mask" "F.Paste")
			(net "PHY_CON_A_TO_IOC_2_DP")
		)
		(pad "AE5" smd circle
			(at -8.400034 7.599934 180)
			(size 0.3556 0.3556)
			(layers "F.Cu" "F.Mask" "F.Paste")
			(net "PHY_CON_A_TO_IOC_2_DN")
		)
		(pad "AE6" smd circle
			(at -7.599934 7.599934 180)
			(size 0.3556 0.3556)
			(layers "F.Cu" "F.Mask" "F.Paste")
			(net "GND")
		)
		(pad "AE7" smd circle
			(at -6.800088 7.599934 180)
			(size 0.3556 0.3556)
			(layers "F.Cu" "F.Mask" "F.Paste")
			(net "GND")
		)
		(pad "AE8" smd circle
			(at -5.999988 7.599934 180)
			(size 0.3556 0.3556)
			(layers "F.Cu" "F.Mask" "F.Paste")
			(net "PCE_VDDH")
		)
		(pad "AE9" smd circle
			(at -5.199888 7.599934 180)
			(size 0.3556 0.3556)
			(layers "F.Cu" "F.Mask" "F.Paste")
			(net "GND")
		)
		(pad "AE10" smd circle
			(at -4.400042 7.599934 180)
			(size 0.3556 0.3556)
			(layers "F.Cu" "F.Mask" "F.Paste")
			(net "PCE_VDDH")
		)
		(pad "AE11" smd circle
			(at -3.599942 7.599934 180)
			(size 0.3556 0.3556)
			(layers "F.Cu" "F.Mask" "F.Paste")
			(net "GND")
		)
		(pad "AE12" smd circle
			(at -2.800096 7.599934 180)
			(size 0.3556 0.3556)
			(layers "F.Cu" "F.Mask" "F.Paste")
			(net "PCE_VDDH")
		)
		(pad "AE13" smd circle
			(at -1.999996 7.599934 180)
			(size 0.3556 0.3556)
			(layers "F.Cu" "F.Mask" "F.Paste")
			(net "GND")
		)
		(pad "AE14" smd circle
			(at -1.199896 7.599934 180)
			(size 0.3556 0.3556)
			(layers "F.Cu" "F.Mask" "F.Paste")
			(net "PCE_VDDH")
		)
		(pad "AE15" smd circle
			(at -0.40005 7.599934 180)
			(size 0.3556 0.3556)
			(layers "F.Cu" "F.Mask" "F.Paste")
			(net "GND")
		)
		(pad "AE16" smd circle
			(at 0.40005 7.599934 180)
			(size 0.3556 0.3556)
			(layers "F.Cu" "F.Mask" "F.Paste")
			(net "PCE_VDDH")
		)
		(pad "AE17" smd circle
			(at 1.199896 7.599934 180)
			(size 0.3556 0.3556)
			(layers "F.Cu" "F.Mask" "F.Paste")
			(net "GND")
		)
		(pad "AE18" smd circle
			(at 1.999996 7.599934 180)
			(size 0.3556 0.3556)
			(layers "F.Cu" "F.Mask" "F.Paste")
			(net "GND")
		)
		(pad "AE19" smd circle
			(at 2.800096 7.599934 180)
			(size 0.3556 0.3556)
			(layers "F.Cu" "F.Mask" "F.Paste")
			(net "SPARE5")
		)
		(pad "AE20" smd circle
			(at 3.599942 7.599934 180)
			(size 0.3556 0.3556)
			(layers "F.Cu" "F.Mask" "F.Paste")
			(net "SPARE3")
		)
		(pad "AE21" smd circle
			(at 4.400042 7.599934 180)
			(size 0.3556 0.3556)
			(layers "F.Cu" "F.Mask" "F.Paste")
			(net "IOC_GPIO_7")
		)
		(pad "AE22" smd circle
			(at 5.199888 7.599934 180)
			(size 0.3556 0.3556)
			(layers "F.Cu" "F.Mask" "F.Paste")
			(net "SYS_DBMODE0")
		)
		(pad "AE23" smd circle
			(at 5.999988 7.599934 180)
			(size 0.3556 0.3556)
			(layers "F.Cu" "F.Mask" "F.Paste")
			(net "SYS_RST_N_1")
		)
		(pad "AE24" smd circle
			(at 6.800088 7.599934 180)
			(size 0.3556 0.3556)
			(layers "F.Cu" "F.Mask" "F.Paste")
			(net "GND")
		)
		(pad "AE25" smd circle
			(at 7.599934 7.599934 180)
			(size 0.3556 0.3556)
			(layers "F.Cu" "F.Mask" "F.Paste")
			(net "GND")
		)
		(pad "AE26" smd circle
			(at 8.400034 7.599934 180)
			(size 0.3556 0.3556)
			(layers "F.Cu" "F.Mask" "F.Paste")
			(net "GND")
		)
		(pad "AE27" smd circle
			(at 9.19988 7.599934 180)
			(size 0.3556 0.3556)
			(layers "F.Cu" "F.Mask" "F.Paste")
			(net "P1V8")
		)
		(pad "AE28" smd circle
			(at 9.99998 7.599934 180)
			(size 0.3556 0.3556)
			(layers "F.Cu" "F.Mask" "F.Paste")
			(net "UART_SERCLK")
		)
		(pad "AE29" smd circle
			(at 10.80008 7.599934 180)
			(size 0.3556 0.3556)
			(layers "F.Cu" "F.Mask" "F.Paste")
			(net "IOC_EXT2_LED_Y")
		)
		(pad "AE30" smd circle
			(at 11.599926 7.599934 180)
			(size 0.3556 0.3556)
			(layers "F.Cu" "F.Mask" "F.Paste")
			(net "IOC_GPIO_31")
		)
		(pad "AF1" smd circle
			(at -11.599926 8.400034 180)
			(size 0.3556 0.3556)
			(layers "F.Cu" "F.Mask" "F.Paste")
			(net "SAS0_VDDH")
		)
		(pad "AF2" smd circle
			(at -10.80008 8.400034 180)
			(size 0.3556 0.3556)
			(layers "F.Cu" "F.Mask" "F.Paste")
			(net "GND")
		)
		(pad "AF3" smd circle
			(at -9.99998 8.400034 180)
			(size 0.3556 0.3556)
			(layers "F.Cu" "F.Mask" "F.Paste")
			(net "GND")
		)
		(pad "AF4" smd circle
			(at -9.19988 8.400034 180)
			(size 0.3556 0.3556)
			(layers "F.Cu" "F.Mask" "F.Paste")
			(net "SAS0_AVDD")
		)
		(pad "AF5" smd circle
			(at -8.400034 8.400034 180)
			(size 0.3556 0.3556)
			(layers "F.Cu" "F.Mask" "F.Paste")
			(net "GND")
		)
		(pad "AF6" smd circle
			(at -7.599934 8.400034 180)
			(size 0.3556 0.3556)
			(layers "F.Cu" "F.Mask" "F.Paste")
			(net "GND")
		)
		(pad "AF7" smd circle
			(at -6.800088 8.400034 180)
			(size 0.3556 0.3556)
			(layers "F.Cu" "F.Mask" "F.Paste")
			(net "PCIE_IOM_TO_COMP_8_DN_C")
		)
		(pad "AF8" smd circle
			(at -5.999988 8.400034 180)
			(size 0.3556 0.3556)
			(layers "F.Cu" "F.Mask" "F.Paste")
			(net "PCIE_IOM_TO_COMP_9_DN_C")
		)
		(pad "AF9" smd circle
			(at -5.199888 8.400034 180)
			(size 0.3556 0.3556)
			(layers "F.Cu" "F.Mask" "F.Paste")
			(net "GND")
		)
		(pad "AF10" smd circle
			(at -4.400042 8.400034 180)
			(size 0.3556 0.3556)
			(layers "F.Cu" "F.Mask" "F.Paste")
			(net "PCIE_IOM_TO_COMP_10_DN_C")
		)
		(pad "AF11" smd circle
			(at -3.599942 8.400034 180)
			(size 0.3556 0.3556)
			(layers "F.Cu" "F.Mask" "F.Paste")
			(net "PCIE_IOM_TO_COMP_11_DN_C")
		)
		(pad "AF12" smd circle
			(at -2.800096 8.400034 180)
			(size 0.3556 0.3556)
			(layers "F.Cu" "F.Mask" "F.Paste")
			(net "GND")
		)
		(pad "AF13" smd circle
			(at -1.999996 8.400034 180)
			(size 0.3556 0.3556)
			(layers "F.Cu" "F.Mask" "F.Paste")
			(net "PCIE_IOM_TO_COMP_12_DN_C")
		)
		(pad "AF14" smd circle
			(at -1.199896 8.400034 180)
			(size 0.3556 0.3556)
			(layers "F.Cu" "F.Mask" "F.Paste")
			(net "PCIE_IOM_TO_COMP_13_DN_C")
		)
		(pad "AF15" smd circle
			(at -0.40005 8.400034 180)
			(size 0.3556 0.3556)
			(layers "F.Cu" "F.Mask" "F.Paste")
			(net "GND")
		)
		(pad "AF16" smd circle
			(at 0.40005 8.400034 180)
			(size 0.3556 0.3556)
			(layers "F.Cu" "F.Mask" "F.Paste")
			(net "PCIE_IOM_TO_COMP_14_DN_C")
		)
		(pad "AF17" smd circle
			(at 1.199896 8.400034 180)
			(size 0.3556 0.3556)
			(layers "F.Cu" "F.Mask" "F.Paste")
			(net "PCIE_IOM_TO_COMP_15_DN_C")
		)
		(pad "AF18" smd circle
			(at 1.999996 8.400034 180)
			(size 0.3556 0.3556)
			(layers "F.Cu" "F.Mask" "F.Paste")
			(net "GND")
		)
		(pad "AF19" smd circle
			(at 2.800096 8.400034 180)
			(size 0.3556 0.3556)
			(layers "F.Cu" "F.Mask" "F.Paste")
			(net "GND")
		)
		(pad "AF20" smd circle
			(at 3.599942 8.400034 180)
			(size 0.3556 0.3556)
			(layers "F.Cu" "F.Mask" "F.Paste")
			(net "P1V8")
		)
		(pad "AF21" smd circle
			(at 4.400042 8.400034 180)
			(size 0.3556 0.3556)
			(layers "F.Cu" "F.Mask" "F.Paste")
			(net "GND")
		)
		(pad "AF22" smd circle
			(at 5.199888 8.400034 180)
			(size 0.3556 0.3556)
			(layers "F.Cu" "F.Mask" "F.Paste")
			(net "P1V8")
		)
		(pad "AF23" smd circle
			(at 5.999988 8.400034 180)
			(size 0.3556 0.3556)
			(layers "F.Cu" "F.Mask" "F.Paste")
			(net "GND")
		)
		(pad "AF24" smd circle
			(at 6.800088 8.400034 180)
			(size 0.3556 0.3556)
			(layers "F.Cu" "F.Mask" "F.Paste")
			(net "P1V8")
		)
		(pad "AF25" smd circle
			(at 7.599934 8.400034 180)
			(size 0.3556 0.3556)
			(layers "F.Cu" "F.Mask" "F.Paste")
			(net "GND")
		)
		(pad "AF26" smd circle
			(at 8.400034 8.400034 180)
			(size 0.3556 0.3556)
			(layers "F.Cu" "F.Mask" "F.Paste")
			(net "P1V8")
		)
		(pad "AF27" smd circle
			(at 9.19988 8.400034 180)
			(size 0.3556 0.3556)
			(layers "F.Cu" "F.Mask" "F.Paste")
			(net "GND")
		)
		(pad "AF28" smd circle
			(at 9.99998 8.400034 180)
			(size 0.3556 0.3556)
			(layers "F.Cu" "F.Mask" "F.Paste")
			(net "IOC_GPIO_26")
		)
		(pad "AF29" smd circle
			(at 10.80008 8.400034 180)
			(size 0.3556 0.3556)
			(layers "F.Cu" "F.Mask" "F.Paste")
			(net "IOC_GPIO_0")
		)
		(pad "AF30" smd circle
			(at 11.599926 8.400034 180)
			(size 0.3556 0.3556)
			(layers "F.Cu" "F.Mask" "F.Paste")
			(net "IOC_GPIO_16")
		)
		(pad "AG1" smd circle
			(at -11.599926 9.19988 180)
			(size 0.3556 0.3556)
			(layers "F.Cu" "F.Mask" "F.Paste")
			(net "PHY_IOC_TO_CON_A_1_DP_C")
		)
		(pad "AG2" smd circle
			(at -10.80008 9.19988 180)
			(size 0.3556 0.3556)
			(layers "F.Cu" "F.Mask" "F.Paste")
			(net "PHY_IOC_TO_CON_A_1_DN_C")
		)
		(pad "AG3" smd circle
			(at -9.99998 9.19988 180)
			(size 0.3556 0.3556)
			(layers "F.Cu" "F.Mask" "F.Paste")
			(net "GND")
		)
		(pad "AG4" smd circle
			(at -9.19988 9.19988 180)
			(size 0.3556 0.3556)
			(layers "F.Cu" "F.Mask" "F.Paste")
			(net "PHY_CON_A_TO_IOC_1_DP")
		)
		(pad "AG5" smd circle
			(at -8.400034 9.19988 180)
			(size 0.3556 0.3556)
			(layers "F.Cu" "F.Mask" "F.Paste")
			(net "PHY_CON_A_TO_IOC_1_DN")
		)
		(pad "AG6" smd circle
			(at -7.599934 9.19988 180)
			(size 0.3556 0.3556)
			(layers "F.Cu" "F.Mask" "F.Paste")
			(net "GND")
		)
		(pad "AG7" smd circle
			(at -6.800088 9.19988 180)
			(size 0.3556 0.3556)
			(layers "F.Cu" "F.Mask" "F.Paste")
			(net "PCIE_IOM_TO_COMP_8_DP_C")
		)
		(pad "AG8" smd circle
			(at -5.999988 9.19988 180)
			(size 0.3556 0.3556)
			(layers "F.Cu" "F.Mask" "F.Paste")
			(net "PCIE_IOM_TO_COMP_9_DP_C")
		)
		(pad "AG9" smd circle
			(at -5.199888 9.19988 180)
			(size 0.3556 0.3556)
			(layers "F.Cu" "F.Mask" "F.Paste")
			(net "PCE_VDDH")
		)
		(pad "AG10" smd circle
			(at -4.400042 9.19988 180)
			(size 0.3556 0.3556)
			(layers "F.Cu" "F.Mask" "F.Paste")
			(net "PCIE_IOM_TO_COMP_10_DP_C")
		)
		(pad "AG11" smd circle
			(at -3.599942 9.19988 180)
			(size 0.3556 0.3556)
			(layers "F.Cu" "F.Mask" "F.Paste")
			(net "PCIE_IOM_TO_COMP_11_DP_C")
		)
		(pad "AG12" smd circle
			(at -2.800096 9.19988 180)
			(size 0.3556 0.3556)
			(layers "F.Cu" "F.Mask" "F.Paste")
			(net "PCE_VDDH")
		)
		(pad "AG13" smd circle
			(at -1.999996 9.19988 180)
			(size 0.3556 0.3556)
			(layers "F.Cu" "F.Mask" "F.Paste")
			(net "PCIE_IOM_TO_COMP_12_DP_C")
		)
		(pad "AG14" smd circle
			(at -1.199896 9.19988 180)
			(size 0.3556 0.3556)
			(layers "F.Cu" "F.Mask" "F.Paste")
			(net "PCIE_IOM_TO_COMP_13_DP_C")
		)
		(pad "AG15" smd circle
			(at -0.40005 9.19988 180)
			(size 0.3556 0.3556)
			(layers "F.Cu" "F.Mask" "F.Paste")
			(net "GND")
		)
		(pad "AG16" smd circle
			(at 0.40005 9.19988 180)
			(size 0.3556 0.3556)
			(layers "F.Cu" "F.Mask" "F.Paste")
			(net "PCIE_IOM_TO_COMP_14_DP_C")
		)
		(pad "AG17" smd circle
			(at 1.199896 9.19988 180)
			(size 0.3556 0.3556)
			(layers "F.Cu" "F.Mask" "F.Paste")
			(net "PCIE_IOM_TO_COMP_15_DP_C")
		)
		(pad "AG18" smd circle
			(at 1.999996 9.19988 180)
			(size 0.3556 0.3556)
			(layers "F.Cu" "F.Mask" "F.Paste")
			(net "PCE_VDDH")
		)
		(pad "AG19" smd circle
			(at 2.800096 9.19988 180)
			(size 0.3556 0.3556)
			(layers "F.Cu" "F.Mask" "F.Paste")
			(net "P1V8")
		)
		(pad "AG20" smd circle
			(at 3.599942 9.19988 180)
			(size 0.3556 0.3556)
			(layers "F.Cu" "F.Mask" "F.Paste")
			(net "GND")
		)
		(pad "AG21" smd circle
			(at 4.400042 9.19988 180)
			(size 0.3556 0.3556)
			(layers "F.Cu" "F.Mask" "F.Paste")
			(net "P1V8")
		)
		(pad "AG22" smd circle
			(at 5.199888 9.19988 180)
			(size 0.3556 0.3556)
			(layers "F.Cu" "F.Mask" "F.Paste")
			(net "GND")
		)
		(pad "AG23" smd circle
			(at 5.999988 9.19988 180)
			(size 0.3556 0.3556)
			(layers "F.Cu" "F.Mask" "F.Paste")
			(net "P1V8")
		)
		(pad "AG24" smd circle
			(at 6.800088 9.19988 180)
			(size 0.3556 0.3556)
			(layers "F.Cu" "F.Mask" "F.Paste")
			(net "GND")
		)
		(pad "AG25" smd circle
			(at 7.599934 9.19988 180)
			(size 0.3556 0.3556)
			(layers "F.Cu" "F.Mask" "F.Paste")
			(net "P1V8")
		)
		(pad "AG26" smd circle
			(at 8.400034 9.19988 180)
			(size 0.3556 0.3556)
			(layers "F.Cu" "F.Mask" "F.Paste")
			(net "GND")
		)
		(pad "AG27" smd circle
			(at 9.19988 9.19988 180)
			(size 0.3556 0.3556)
			(layers "F.Cu" "F.Mask" "F.Paste")
			(net "P1V8")
		)
		(pad "AG28" smd circle
			(at 9.99998 9.19988 180)
			(size 0.3556 0.3556)
			(layers "F.Cu" "F.Mask" "F.Paste")
			(net "IOC_GPIO_25")
		)
		(pad "AG29" smd circle
			(at 10.80008 9.19988 180)
			(size 0.3556 0.3556)
			(layers "F.Cu" "F.Mask" "F.Paste")
			(net "IOC_GPIO_18")
		)
		(pad "AG30" smd circle
			(at 11.599926 9.19988 180)
			(size 0.3556 0.3556)
			(layers "F.Cu" "F.Mask" "F.Paste")
			(net "IOC_GPIO_21")
		)
		(pad "AH1" smd circle
			(at -11.599926 9.99998 180)
			(size 0.4064 0.4064)
			(layers "F.Cu" "F.Mask" "F.Paste")
			(net "PHY_IOC_TO_CON_A_0_DP_C")
		)
		(pad "AH2" smd circle
			(at -10.80008 9.99998 180)
			(size 0.4064 0.4064)
			(layers "F.Cu" "F.Mask" "F.Paste")
			(net "PHY_IOC_TO_CON_A_0_DN_C")
		)
		(pad "AH3" smd circle
			(at -9.99998 9.99998 180)
			(size 0.4064 0.4064)
			(layers "F.Cu" "F.Mask" "F.Paste")
			(net "GND")
		)
		(pad "AH4" smd circle
			(at -9.19988 9.99998 180)
			(size 0.3556 0.3556)
			(layers "F.Cu" "F.Mask" "F.Paste")
			(net "PHY_CON_A_TO_IOC_0_DP")
		)
		(pad "AH5" smd circle
			(at -8.400034 9.99998 180)
			(size 0.3556 0.3556)
			(layers "F.Cu" "F.Mask" "F.Paste")
			(net "PHY_CON_A_TO_IOC_0_DN")
		)
		(pad "AH6" smd circle
			(at -7.599934 9.99998 180)
			(size 0.3556 0.3556)
			(layers "F.Cu" "F.Mask" "F.Paste")
			(net "GND")
		)
		(pad "AH7" smd circle
			(at -6.800088 9.99998 180)
			(size 0.3556 0.3556)
			(layers "F.Cu" "F.Mask" "F.Paste")
			(net "GND")
		)
		(pad "AH8" smd circle
			(at -5.999988 9.99998 180)
			(size 0.3556 0.3556)
			(layers "F.Cu" "F.Mask" "F.Paste")
			(net "GND")
		)
		(pad "AH9" smd circle
			(at -5.199888 9.99998 180)
			(size 0.3556 0.3556)
			(layers "F.Cu" "F.Mask" "F.Paste")
			(net "GND")
		)
		(pad "AH10" smd circle
			(at -4.400042 9.99998 180)
			(size 0.3556 0.3556)
			(layers "F.Cu" "F.Mask" "F.Paste")
			(net "GND")
		)
		(pad "AH11" smd circle
			(at -3.599942 9.99998 180)
			(size 0.3556 0.3556)
			(layers "F.Cu" "F.Mask" "F.Paste")
			(net "GND")
		)
		(pad "AH12" smd circle
			(at -2.800096 9.99998 180)
			(size 0.3556 0.3556)
			(layers "F.Cu" "F.Mask" "F.Paste")
			(net "GND")
		)
		(pad "AH13" smd circle
			(at -1.999996 9.99998 180)
			(size 0.3556 0.3556)
			(layers "F.Cu" "F.Mask" "F.Paste")
			(net "GND")
		)
		(pad "AH14" smd circle
			(at -1.199896 9.99998 180)
			(size 0.3556 0.3556)
			(layers "F.Cu" "F.Mask" "F.Paste")
			(net "GND")
		)
		(pad "AH15" smd circle
			(at -0.40005 9.99998 180)
			(size 0.3556 0.3556)
			(layers "F.Cu" "F.Mask" "F.Paste")
			(net "PCE_VDDH")
		)
		(pad "AH16" smd circle
			(at 0.40005 9.99998 180)
			(size 0.3556 0.3556)
			(layers "F.Cu" "F.Mask" "F.Paste")
			(net "GND")
		)
		(pad "AH17" smd circle
			(at 1.199896 9.99998 180)
			(size 0.3556 0.3556)
			(layers "F.Cu" "F.Mask" "F.Paste")
			(net "GND")
		)
		(pad "AH18" smd circle
			(at 1.999996 9.99998 180)
			(size 0.3556 0.3556)
			(layers "F.Cu" "F.Mask" "F.Paste")
			(net "GND")
		)
		(pad "AH19" smd circle
			(at 2.800096 9.99998 180)
			(size 0.3556 0.3556)
			(layers "F.Cu" "F.Mask" "F.Paste")
			(net "Net_1208")
		)
		(pad "AH20" smd circle
			(at 3.599942 9.99998 180)
			(size 0.3556 0.3556)
			(layers "F.Cu" "F.Mask" "F.Paste")
			(net "SYS_RST_N_0")
		)
		(pad "AH21" smd circle
			(at 4.400042 9.99998 180)
			(size 0.3556 0.3556)
			(layers "F.Cu" "F.Mask" "F.Paste")
			(net "IOC_UART_1_TX")
		)
		(pad "AH22" smd circle
			(at 5.199888 9.99998 180)
			(size 0.3556 0.3556)
			(layers "F.Cu" "F.Mask" "F.Paste")
			(net "IOC_GPIO_2")
		)
		(pad "AH23" smd circle
			(at 5.999988 9.99998 180)
			(size 0.3556 0.3556)
			(layers "F.Cu" "F.Mask" "F.Paste")
			(net "IOC_GPIO_3")
		)
		(pad "AH24" smd circle
			(at 6.800088 9.99998 180)
			(size 0.3556 0.3556)
			(layers "F.Cu" "F.Mask" "F.Paste")
			(net "IOC_GPIO_5")
		)
		(pad "AH25" smd circle
			(at 7.599934 9.99998 180)
			(size 0.3556 0.3556)
			(layers "F.Cu" "F.Mask" "F.Paste")
			(net "IOC_GPIO_6")
		)
		(pad "AH26" smd circle
			(at 8.400034 9.99998 180)
			(size 0.3556 0.3556)
			(layers "F.Cu" "F.Mask" "F.Paste")
			(net "IOC_UART_1_RX")
		)
		(pad "AH27" smd circle
			(at 9.19988 9.99998 180)
			(size 0.3556 0.3556)
			(layers "F.Cu" "F.Mask" "F.Paste")
			(net "SPARE0")
		)
		(pad "AH28" smd circle
			(at 9.99998 9.99998 180)
			(size 0.4064 0.4064)
			(layers "F.Cu" "F.Mask" "F.Paste")
			(net "IOC_GPIO_10")
		)
		(pad "AH29" smd circle
			(at 10.80008 9.99998 180)
			(size 0.4064 0.4064)
			(layers "F.Cu" "F.Mask" "F.Paste")
			(net "IOC_GPIO_22")
		)
		(pad "AH30" smd circle
			(at 11.599926 9.99998 180)
			(size 0.4064 0.4064)
			(layers "F.Cu" "F.Mask" "F.Paste")
			(net "IOC_GPIO_11")
		)
		(pad "AJ1" smd circle
			(at -11.599926 10.80008 180)
			(size 0.4064 0.4064)
			(layers "F.Cu" "F.Mask" "F.Paste")
			(net "SAS0_VDDH")
		)
		(pad "AJ2" smd circle
			(at -10.80008 10.80008 180)
			(size 0.4064 0.4064)
			(layers "F.Cu" "F.Mask" "F.Paste")
			(net "GND")
		)
		(pad "AJ3" smd circle
			(at -9.99998 10.80008 180)
			(size 0.4064 0.4064)
			(layers "F.Cu" "F.Mask" "F.Paste")
			(net "SAS0_AVDD")
		)
		(pad "AJ4" smd circle
			(at -9.19988 10.80008 180)
			(size 0.3556 0.3556)
			(layers "F.Cu" "F.Mask" "F.Paste")
			(net "GND")
		)
		(pad "AJ5" smd circle
			(at -8.400034 10.80008 180)
			(size 0.3556 0.3556)
			(layers "F.Cu" "F.Mask" "F.Paste")
			(net "GND")
		)
		(pad "AJ6" smd circle
			(at -7.599934 10.80008 180)
			(size 0.3556 0.3556)
			(layers "F.Cu" "F.Mask" "F.Paste")
			(net "GND")
		)
		(pad "AJ7" smd circle
			(at -6.800088 10.80008 180)
			(size 0.3556 0.3556)
			(layers "F.Cu" "F.Mask" "F.Paste")
			(net "PCIE_COMP_TO_IOM_8_DN")
		)
		(pad "AJ8" smd circle
			(at -5.999988 10.80008 180)
			(size 0.3556 0.3556)
			(layers "F.Cu" "F.Mask" "F.Paste")
			(net "PCIE_COMP_TO_IOM_9_DN")
		)
		(pad "AJ9" smd circle
			(at -5.199888 10.80008 180)
			(size 0.3556 0.3556)
			(layers "F.Cu" "F.Mask" "F.Paste")
			(net "GND")
		)
		(pad "AJ10" smd circle
			(at -4.400042 10.80008 180)
			(size 0.3556 0.3556)
			(layers "F.Cu" "F.Mask" "F.Paste")
			(net "PCIE_COMP_TO_IOM_10_DN")
		)
		(pad "AJ11" smd circle
			(at -3.599942 10.80008 180)
			(size 0.3556 0.3556)
			(layers "F.Cu" "F.Mask" "F.Paste")
			(net "PCIE_COMP_TO_IOM_11_DN")
		)
		(pad "AJ12" smd circle
			(at -2.800096 10.80008 180)
			(size 0.3556 0.3556)
			(layers "F.Cu" "F.Mask" "F.Paste")
			(net "GND")
		)
		(pad "AJ13" smd circle
			(at -1.999996 10.80008 180)
			(size 0.3556 0.3556)
			(layers "F.Cu" "F.Mask" "F.Paste")
			(net "PCIE_COMP_TO_IOM_12_DN")
		)
		(pad "AJ14" smd circle
			(at -1.199896 10.80008 180)
			(size 0.3556 0.3556)
			(layers "F.Cu" "F.Mask" "F.Paste")
			(net "PCIE_COMP_TO_IOM_13_DN")
		)
		(pad "AJ15" smd circle
			(at -0.40005 10.80008 180)
			(size 0.3556 0.3556)
			(layers "F.Cu" "F.Mask" "F.Paste")
			(net "GND")
		)
		(pad "AJ16" smd circle
			(at 0.40005 10.80008 180)
			(size 0.3556 0.3556)
			(layers "F.Cu" "F.Mask" "F.Paste")
			(net "PCIE_COMP_TO_IOM_14_DN")
		)
		(pad "AJ17" smd circle
			(at 1.199896 10.80008 180)
			(size 0.3556 0.3556)
			(layers "F.Cu" "F.Mask" "F.Paste")
			(net "PCIE_COMP_TO_IOM_15_DN")
		)
		(pad "AJ18" smd circle
			(at 1.999996 10.80008 180)
			(size 0.3556 0.3556)
			(layers "F.Cu" "F.Mask" "F.Paste")
			(net "GND")
		)
		(pad "AJ19" smd circle
			(at 2.800096 10.80008 180)
			(size 0.3556 0.3556)
			(layers "F.Cu" "F.Mask" "F.Paste")
			(net "Net_1209")
		)
		(pad "AJ20" smd circle
			(at 3.599942 10.80008 180)
			(size 0.3556 0.3556)
			(layers "F.Cu" "F.Mask" "F.Paste")
			(net "SYS_ERR_0")
		)
		(pad "AJ21" smd circle
			(at 4.400042 10.80008 180)
			(size 0.3556 0.3556)
			(layers "F.Cu" "F.Mask" "F.Paste")
			(net "IOC_RESET#")
		)
		(pad "AJ22" smd circle
			(at 5.199888 10.80008 180)
			(size 0.3556 0.3556)
			(layers "F.Cu" "F.Mask" "F.Paste")
			(net "SPARE2")
		)
		(pad "AJ23" smd circle
			(at 5.999988 10.80008 180)
			(size 0.3556 0.3556)
			(layers "F.Cu" "F.Mask" "F.Paste")
			(net "SYS_DBMODE3")
		)
		(pad "AJ24" smd circle
			(at 6.800088 10.80008 180)
			(size 0.3556 0.3556)
			(layers "F.Cu" "F.Mask" "F.Paste")
			(net "IOC_UART_0_RX")
		)
		(pad "AJ25" smd circle
			(at 7.599934 10.80008 180)
			(size 0.3556 0.3556)
			(layers "F.Cu" "F.Mask" "F.Paste")
			(net "IOC_GPIO_13")
		)
		(pad "AJ26" smd circle
			(at 8.400034 10.80008 180)
			(size 0.3556 0.3556)
			(layers "F.Cu" "F.Mask" "F.Paste")
			(net "IOC_GPIO_1")
		)
		(pad "AJ27" smd circle
			(at 9.19988 10.80008 180)
			(size 0.3556 0.3556)
			(layers "F.Cu" "F.Mask" "F.Paste")
			(net "IOC_GPIO_14")
		)
		(pad "AJ28" smd circle
			(at 9.99998 10.80008 180)
			(size 0.4064 0.4064)
			(layers "F.Cu" "F.Mask" "F.Paste")
			(net "IOC_GPIO_20")
		)
		(pad "AJ29" smd circle
			(at 10.80008 10.80008 180)
			(size 0.4064 0.4064)
			(layers "F.Cu" "F.Mask" "F.Paste")
			(net "IOC_GPIO_12")
		)
		(pad "AJ30" smd circle
			(at 11.599926 10.80008 180)
			(size 0.4064 0.4064)
			(layers "F.Cu" "F.Mask" "F.Paste")
			(net "IOC_GPIO_4")
		)
		(pad "AK2" smd circle
			(at -10.80008 11.599926 180)
			(size 0.4064 0.4064)
			(layers "F.Cu" "F.Mask" "F.Paste")
			(net "GND")
		)
		(pad "AK3" smd circle
			(at -9.99998 11.599926 180)
			(size 0.4064 0.4064)
			(layers "F.Cu" "F.Mask" "F.Paste")
			(net "GND")
		)
		(pad "AK4" smd circle
			(at -9.19988 11.599926 180)
			(size 0.3556 0.3556)
			(layers "F.Cu" "F.Mask" "F.Paste")
			(net "PCIE_COMP_TO_IOM_CLK_2_DP")
		)
		(pad "AK5" smd circle
			(at -8.400034 11.599926 180)
			(size 0.3556 0.3556)
			(layers "F.Cu" "F.Mask" "F.Paste")
			(net "PCIE_COMP_TO_IOM_CLK_2_DN")
		)
		(pad "AK6" smd circle
			(at -7.599934 11.599926 180)
			(size 0.3556 0.3556)
			(layers "F.Cu" "F.Mask" "F.Paste")
			(net "PCE_AVDD")
		)
		(pad "AK7" smd circle
			(at -6.800088 11.599926 180)
			(size 0.3556 0.3556)
			(layers "F.Cu" "F.Mask" "F.Paste")
			(net "PCIE_COMP_TO_IOM_8_DP")
		)
		(pad "AK8" smd circle
			(at -5.999988 11.599926 180)
			(size 0.3556 0.3556)
			(layers "F.Cu" "F.Mask" "F.Paste")
			(net "PCIE_COMP_TO_IOM_9_DP")
		)
		(pad "AK9" smd circle
			(at -5.199888 11.599926 180)
			(size 0.3556 0.3556)
			(layers "F.Cu" "F.Mask" "F.Paste")
			(net "PCE_AVDD")
		)
		(pad "AK10" smd circle
			(at -4.400042 11.599926 180)
			(size 0.3556 0.3556)
			(layers "F.Cu" "F.Mask" "F.Paste")
			(net "PCIE_COMP_TO_IOM_10_DP")
		)
		(pad "AK11" smd circle
			(at -3.599942 11.599926 180)
			(size 0.3556 0.3556)
			(layers "F.Cu" "F.Mask" "F.Paste")
			(net "PCIE_COMP_TO_IOM_11_DP")
		)
		(pad "AK12" smd circle
			(at -2.800096 11.599926 180)
			(size 0.3556 0.3556)
			(layers "F.Cu" "F.Mask" "F.Paste")
			(net "PCE_AVDD")
		)
		(pad "AK13" smd circle
			(at -1.999996 11.599926 180)
			(size 0.3556 0.3556)
			(layers "F.Cu" "F.Mask" "F.Paste")
			(net "PCIE_COMP_TO_IOM_12_DP")
		)
		(pad "AK14" smd circle
			(at -1.199896 11.599926 180)
			(size 0.3556 0.3556)
			(layers "F.Cu" "F.Mask" "F.Paste")
			(net "PCIE_COMP_TO_IOM_13_DP")
		)
		(pad "AK15" smd circle
			(at -0.40005 11.599926 180)
			(size 0.3556 0.3556)
			(layers "F.Cu" "F.Mask" "F.Paste")
			(net "PCE_AVDD")
		)
		(pad "AK16" smd circle
			(at 0.40005 11.599926 180)
			(size 0.3556 0.3556)
			(layers "F.Cu" "F.Mask" "F.Paste")
			(net "PCIE_COMP_TO_IOM_14_DP")
		)
		(pad "AK17" smd circle
			(at 1.199896 11.599926 180)
			(size 0.3556 0.3556)
			(layers "F.Cu" "F.Mask" "F.Paste")
			(net "PCIE_COMP_TO_IOM_15_DP")
		)
		(pad "AK18" smd circle
			(at 1.999996 11.599926 180)
			(size 0.3556 0.3556)
			(layers "F.Cu" "F.Mask" "F.Paste")
			(net "PCE_AVDD")
		)
		(pad "AK19" smd circle
			(at 2.800096 11.599926 180)
			(size 0.3556 0.3556)
			(layers "F.Cu" "F.Mask" "F.Paste")
			(net "Net_1210")
		)
		(pad "AK20" smd circle
			(at 3.599942 11.599926 180)
			(size 0.3556 0.3556)
			(layers "F.Cu" "F.Mask" "F.Paste")
			(net "SYS_DBMODE1")
		)
		(pad "AK21" smd circle
			(at 4.400042 11.599926 180)
			(size 0.3556 0.3556)
			(layers "F.Cu" "F.Mask" "F.Paste")
			(net "SYS_DBMODE4")
		)
		(pad "AK22" smd circle
			(at 5.199888 11.599926 180)
			(size 0.3556 0.3556)
			(layers "F.Cu" "F.Mask" "F.Paste")
			(net "SYS_ERROR1")
		)
		(pad "AK23" smd circle
			(at 5.999988 11.599926 180)
			(size 0.3556 0.3556)
			(layers "F.Cu" "F.Mask" "F.Paste")
			(net "SYS_HALT0#")
		)
		(pad "AK24" smd circle
			(at 6.800088 11.599926 180)
			(size 0.3556 0.3556)
			(layers "F.Cu" "F.Mask" "F.Paste")
			(net "SYS_DBMODE2")
		)
		(pad "AK25" smd circle
			(at 7.599934 11.599926 180)
			(size 0.3556 0.3556)
			(layers "F.Cu" "F.Mask" "F.Paste")
			(net "SPARE1")
		)
		(pad "AK26" smd circle
			(at 8.400034 11.599926 180)
			(size 0.3556 0.3556)
			(layers "F.Cu" "F.Mask" "F.Paste")
			(net "SYS_HALT1#")
		)
		(pad "AK27" smd circle
			(at 9.19988 11.599926 180)
			(size 0.3556 0.3556)
			(layers "F.Cu" "F.Mask" "F.Paste")
			(net "IOC_UART_0_TX")
		)
		(pad "AK28" smd circle
			(at 9.99998 11.599926 180)
			(size 0.4064 0.4064)
			(layers "F.Cu" "F.Mask" "F.Paste")
			(net "IOC_GPIO_19")
		)
		(pad "AK29" smd circle
			(at 10.80008 11.599926 180)
			(size 0.4064 0.4064)
			(layers "F.Cu" "F.Mask" "F.Paste")
			(net "IOC_GPIO_9")
		)
		(pad "B1" smd circle
			(at -11.599926 -10.80008 180)
			(size 0.4064 0.4064)
			(layers "F.Cu" "F.Mask" "F.Paste")
			(net "Net_1249")
		)
		(pad "B2" smd circle
			(at -10.80008 -10.80008 180)
			(size 0.4064 0.4064)
			(layers "F.Cu" "F.Mask" "F.Paste")
			(net "GND")
		)
		(pad "B3" smd circle
			(at -9.99998 -10.80008 180)
			(size 0.4064 0.4064)
			(layers "F.Cu" "F.Mask" "F.Paste")
			(net "Net_1215")
		)
		(pad "B4" smd circle
			(at -9.19988 -10.80008 180)
			(size 0.3556 0.3556)
			(layers "F.Cu" "F.Mask" "F.Paste")
			(net "Net_1216")
		)
		(pad "B5" smd circle
			(at -8.400034 -10.80008 180)
			(size 0.3556 0.3556)
			(layers "F.Cu" "F.Mask" "F.Paste")
			(net "Net_1217")
		)
		(pad "B6" smd circle
			(at -7.599934 -10.80008 180)
			(size 0.3556 0.3556)
			(layers "F.Cu" "F.Mask" "F.Paste")
			(net "GND")
		)
		(pad "B7" smd circle
			(at -6.800088 -10.80008 180)
			(size 0.3556 0.3556)
			(layers "F.Cu" "F.Mask" "F.Paste")
			(net "ICE1_TCK")
		)
		(pad "B8" smd circle
			(at -5.999988 -10.80008 180)
			(size 0.3556 0.3556)
			(layers "F.Cu" "F.Mask" "F.Paste")
			(net "ICE0_TDI")
		)
		(pad "B9" smd circle
			(at -5.199888 -10.80008 180)
			(size 0.3556 0.3556)
			(layers "F.Cu" "F.Mask" "F.Paste")
			(net "IOC_VREF_SET")
		)
		(pad "B10" smd circle
			(at -4.400042 -10.80008 180)
			(size 0.3556 0.3556)
			(layers "F.Cu" "F.Mask" "F.Paste")
			(net "Net_1218")
		)
		(pad "B11" smd circle
			(at -3.599942 -10.80008 180)
			(size 0.3556 0.3556)
			(layers "F.Cu" "F.Mask" "F.Paste")
			(net "GND")
		)
		(pad "B12" smd circle
			(at -2.800096 -10.80008 180)
			(size 0.3556 0.3556)
			(layers "F.Cu" "F.Mask" "F.Paste")
			(net "AVSO_IDDTN18")
		)
		(pad "B13" smd circle
			(at -1.999996 -10.80008 180)
			(size 0.3556 0.3556)
			(layers "F.Cu" "F.Mask" "F.Paste")
			(net "AVSO_VREF")
		)
		(pad "B14" smd circle
			(at -1.199896 -10.80008 180)
			(size 0.3556 0.3556)
			(layers "F.Cu" "F.Mask" "F.Paste")
			(net "GND")
		)
		(pad "B15" smd circle
			(at -0.40005 -10.80008 180)
			(size 0.3556 0.3556)
			(layers "F.Cu" "F.Mask" "F.Paste")
			(net "GND")
		)
		(pad "B16" smd circle
			(at 0.40005 -10.80008 180)
			(size 0.3556 0.3556)
			(layers "F.Cu" "F.Mask" "F.Paste")
			(net "LSI_JTAG_EN_N")
		)
		(pad "B17" smd circle
			(at 1.199896 -10.80008 180)
			(size 0.3556 0.3556)
			(layers "F.Cu" "F.Mask" "F.Paste")
			(net "LSI_SCAN_EN")
		)
		(pad "B18" smd circle
			(at 1.999996 -10.80008 180)
			(size 0.3556 0.3556)
			(layers "F.Cu" "F.Mask" "F.Paste")
			(net "JTAG_IOC_TMS")
		)
		(pad "B19" smd circle
			(at 2.800096 -10.80008 180)
			(size 0.3556 0.3556)
			(layers "F.Cu" "F.Mask" "F.Paste")
			(net "XM_CS0_N")
		)
		(pad "B20" smd circle
			(at 3.599942 -10.80008 180)
			(size 0.3556 0.3556)
			(layers "F.Cu" "F.Mask" "F.Paste")
			(net "XM_F_RST_N")
		)
		(pad "B21" smd circle
			(at 4.400042 -10.80008 180)
			(size 0.3556 0.3556)
			(layers "F.Cu" "F.Mask" "F.Paste")
			(net "XM_NAND_CS_N")
		)
		(pad "B22" smd circle
			(at 5.199888 -10.80008 180)
			(size 0.3556 0.3556)
			(layers "F.Cu" "F.Mask" "F.Paste")
			(net "XM_OE_N")
		)
		(pad "B23" smd circle
			(at 5.999988 -10.80008 180)
			(size 0.3556 0.3556)
			(layers "F.Cu" "F.Mask" "F.Paste")
			(net "Net_1202")
		)
		(pad "B24" smd circle
			(at 6.800088 -10.80008 180)
			(size 0.3556 0.3556)
			(layers "F.Cu" "F.Mask" "F.Paste")
			(net "Net_1203")
		)
		(pad "B25" smd circle
			(at 7.599934 -10.80008 180)
			(size 0.3556 0.3556)
			(layers "F.Cu" "F.Mask" "F.Paste")
			(net "XM_ADDR_0")
		)
		(pad "B26" smd circle
			(at 8.400034 -10.80008 180)
			(size 0.3556 0.3556)
			(layers "F.Cu" "F.Mask" "F.Paste")
			(net "XM_ALE")
		)
		(pad "B27" smd circle
			(at 9.19988 -10.80008 180)
			(size 0.3556 0.3556)
			(layers "F.Cu" "F.Mask" "F.Paste")
			(net "XM_ADDR_1")
		)
		(pad "B28" smd circle
			(at 9.99998 -10.80008 180)
			(size 0.4064 0.4064)
			(layers "F.Cu" "F.Mask" "F.Paste")
			(net "XM_ADDR_6")
		)
		(pad "B29" smd circle
			(at 10.80008 -10.80008 180)
			(size 0.4064 0.4064)
			(layers "F.Cu" "F.Mask" "F.Paste")
			(net "XM_ADDR_8")
		)
		(pad "B30" smd circle
			(at 11.599926 -10.80008 180)
			(size 0.4064 0.4064)
			(layers "F.Cu" "F.Mask" "F.Paste")
			(net "XM_ADDR_7")
		)
		(pad "C1" smd circle
			(at -11.599926 -9.99998 180)
			(size 0.4064 0.4064)
			(layers "F.Cu" "F.Mask" "F.Paste")
			(net "GND")
		)
		(pad "C2" smd circle
			(at -10.80008 -9.99998 180)
			(size 0.4064 0.4064)
			(layers "F.Cu" "F.Mask" "F.Paste")
			(net "Net_1219")
		)
		(pad "C3" smd circle
			(at -9.99998 -9.99998 180)
			(size 0.4064 0.4064)
			(layers "F.Cu" "F.Mask" "F.Paste")
			(net "Net_1220")
		)
		(pad "C4" smd circle
			(at -9.19988 -9.99998 180)
			(size 0.3556 0.3556)
			(layers "F.Cu" "F.Mask" "F.Paste")
			(net "Net_1221")
		)
		(pad "C5" smd circle
			(at -8.400034 -9.99998 180)
			(size 0.3556 0.3556)
			(layers "F.Cu" "F.Mask" "F.Paste")
			(net "GND")
		)
		(pad "C6" smd circle
			(at -7.599934 -9.99998 180)
			(size 0.3556 0.3556)
			(layers "F.Cu" "F.Mask" "F.Paste")
			(net "ICE1_TRST#")
		)
		(pad "C7" smd circle
			(at -6.800088 -9.99998 180)
			(size 0.3556 0.3556)
			(layers "F.Cu" "F.Mask" "F.Paste")
			(net "ICE0_TMS")
		)
		(pad "C8" smd circle
			(at -5.999988 -9.99998 180)
			(size 0.3556 0.3556)
			(layers "F.Cu" "F.Mask" "F.Paste")
			(net "ICE0_TDO")
		)
		(pad "C9" smd circle
			(at -5.199888 -9.99998 180)
			(size 0.3556 0.3556)
			(layers "F.Cu" "F.Mask" "F.Paste")
			(net "Net_1222")
		)
		(pad "C10" smd circle
			(at -4.400042 -9.99998 180)
			(size 0.3556 0.3556)
			(layers "F.Cu" "F.Mask" "F.Paste")
			(net "Net_1223")
		)
		(pad "C11" smd circle
			(at -3.599942 -9.99998 180)
			(size 0.3556 0.3556)
			(layers "F.Cu" "F.Mask" "F.Paste")
			(net "GND")
		)
		(pad "C12" smd circle
			(at -2.800096 -9.99998 180)
			(size 0.3556 0.3556)
			(layers "F.Cu" "F.Mask" "F.Paste")
			(net "PWRGD_P1V8")
		)
		(pad "C13" smd circle
			(at -1.999996 -9.99998 180)
			(size 0.3556 0.3556)
			(layers "F.Cu" "F.Mask" "F.Paste")
			(net "Net_1207")
		)
		(pad "C14" smd circle
			(at -1.199896 -9.99998 180)
			(size 0.3556 0.3556)
			(layers "F.Cu" "F.Mask" "F.Paste")
			(net "GND")
		)
		(pad "C15" smd circle
			(at -0.40005 -9.99998 180)
			(size 0.3556 0.3556)
			(layers "F.Cu" "F.Mask" "F.Paste")
			(net "GND")
		)
		(pad "C16" smd circle
			(at 0.40005 -9.99998 180)
			(size 0.3556 0.3556)
			(layers "F.Cu" "F.Mask" "F.Paste")
			(net "LSI_TN")
		)
		(pad "C17" smd circle
			(at 1.199896 -9.99998 180)
			(size 0.3556 0.3556)
			(layers "F.Cu" "F.Mask" "F.Paste")
			(net "JTAG_IOC_TCK")
		)
		(pad "C18" smd circle
			(at 1.999996 -9.99998 180)
			(size 0.3556 0.3556)
			(layers "F.Cu" "F.Mask" "F.Paste")
			(net "IOC_TDO")
		)
		(pad "C19" smd circle
			(at 2.800096 -9.99998 180)
			(size 0.3556 0.3556)
			(layers "F.Cu" "F.Mask" "F.Paste")
			(net "XM_DATA_15")
		)
		(pad "C20" smd circle
			(at 3.599942 -9.99998 180)
			(size 0.3556 0.3556)
			(layers "F.Cu" "F.Mask" "F.Paste")
			(net "XM_DATA_6")
		)
		(pad "C21" smd circle
			(at 4.400042 -9.99998 180)
			(size 0.3556 0.3556)
			(layers "F.Cu" "F.Mask" "F.Paste")
			(net "XM_DATA_8")
		)
		(pad "C22" smd circle
			(at 5.199888 -9.99998 180)
			(size 0.3556 0.3556)
			(layers "F.Cu" "F.Mask" "F.Paste")
			(net "XM_DATA_5")
		)
		(pad "C23" smd circle
			(at 5.999988 -9.99998 180)
			(size 0.3556 0.3556)
			(layers "F.Cu" "F.Mask" "F.Paste")
			(net "XM_CLE")
		)
		(pad "C24" smd circle
			(at 6.800088 -9.99998 180)
			(size 0.3556 0.3556)
			(layers "F.Cu" "F.Mask" "F.Paste")
			(net "XM_DATA_7")
		)
		(pad "C25" smd circle
			(at 7.599934 -9.99998 180)
			(size 0.3556 0.3556)
			(layers "F.Cu" "F.Mask" "F.Paste")
			(net "XM_DATA_10")
		)
		(pad "C26" smd circle
			(at 8.400034 -9.99998 180)
			(size 0.3556 0.3556)
			(layers "F.Cu" "F.Mask" "F.Paste")
			(net "XM_DATA_9")
		)
		(pad "C27" smd circle
			(at 9.19988 -9.99998 180)
			(size 0.3556 0.3556)
			(layers "F.Cu" "F.Mask" "F.Paste")
			(net "XM_ADDR_2")
		)
		(pad "C28" smd circle
			(at 9.99998 -9.99998 180)
			(size 0.4064 0.4064)
			(layers "F.Cu" "F.Mask" "F.Paste")
			(net "XM_ADDR_5")
		)
		(pad "C29" smd circle
			(at 10.80008 -9.99998 180)
			(size 0.4064 0.4064)
			(layers "F.Cu" "F.Mask" "F.Paste")
			(net "XM_ADDR_11")
		)
		(pad "C30" smd circle
			(at 11.599926 -9.99998 180)
			(size 0.4064 0.4064)
			(layers "F.Cu" "F.Mask" "F.Paste")
			(net "XM_ADDR_13")
		)
		(pad "D1" smd circle
			(at -11.599926 -9.19988 180)
			(size 0.3556 0.3556)
			(layers "F.Cu" "F.Mask" "F.Paste")
			(net "Net_1250")
		)
		(pad "D2" smd circle
			(at -10.80008 -9.19988 180)
			(size 0.3556 0.3556)
			(layers "F.Cu" "F.Mask" "F.Paste")
			(net "Net_1224")
		)
		(pad "D3" smd circle
			(at -9.99998 -9.19988 180)
			(size 0.3556 0.3556)
			(layers "F.Cu" "F.Mask" "F.Paste")
			(net "Net_1225")
		)
		(pad "D4" smd circle
			(at -9.19988 -9.19988 180)
			(size 0.3556 0.3556)
			(layers "F.Cu" "F.Mask" "F.Paste")
			(net "P1V8")
		)
		(pad "D5" smd circle
			(at -8.400034 -9.19988 180)
			(size 0.3556 0.3556)
			(layers "F.Cu" "F.Mask" "F.Paste")
			(net "GND")
		)
		(pad "D6" smd circle
			(at -7.599934 -9.19988 180)
			(size 0.3556 0.3556)
			(layers "F.Cu" "F.Mask" "F.Paste")
			(net "P1V8")
		)
		(pad "D7" smd circle
			(at -6.800088 -9.19988 180)
			(size 0.3556 0.3556)
			(layers "F.Cu" "F.Mask" "F.Paste")
			(net "GND")
		)
		(pad "D8" smd circle
			(at -5.999988 -9.19988 180)
			(size 0.3556 0.3556)
			(layers "F.Cu" "F.Mask" "F.Paste")
			(net "P1V8")
		)
		(pad "D9" smd circle
			(at -5.199888 -9.19988 180)
			(size 0.3556 0.3556)
			(layers "F.Cu" "F.Mask" "F.Paste")
			(net "GND")
		)
		(pad "D10" smd circle
			(at -4.400042 -9.19988 180)
			(size 0.3556 0.3556)
			(layers "F.Cu" "F.Mask" "F.Paste")
			(net "P1V8")
		)
		(pad "D11" smd circle
			(at -3.599942 -9.19988 180)
			(size 0.3556 0.3556)
			(layers "F.Cu" "F.Mask" "F.Paste")
			(net "GND")
		)
		(pad "D12" smd circle
			(at -2.800096 -9.19988 180)
			(size 0.3556 0.3556)
			(layers "F.Cu" "F.Mask" "F.Paste")
			(net "GND")
		)
		(pad "D13" smd circle
			(at -1.999996 -9.19988 180)
			(size 0.3556 0.3556)
			(layers "F.Cu" "F.Mask" "F.Paste")
			(net "GND")
		)
		(pad "D14" smd circle
			(at -1.199896 -9.19988 180)
			(size 0.3556 0.3556)
			(layers "F.Cu" "F.Mask" "F.Paste")
			(net "GND")
		)
		(pad "D15" smd circle
			(at -0.40005 -9.19988 180)
			(size 0.3556 0.3556)
			(layers "F.Cu" "F.Mask" "F.Paste")
			(net "GND")
		)
		(pad "D16" smd circle
			(at 0.40005 -9.19988 180)
			(size 0.3556 0.3556)
			(layers "F.Cu" "F.Mask" "F.Paste")
			(net "P1V8")
		)
		(pad "D17" smd circle
			(at 1.199896 -9.19988 180)
			(size 0.3556 0.3556)
			(layers "F.Cu" "F.Mask" "F.Paste")
			(net "GND")
		)
		(pad "D18" smd circle
			(at 1.999996 -9.19988 180)
			(size 0.3556 0.3556)
			(layers "F.Cu" "F.Mask" "F.Paste")
			(net "P1V8")
		)
		(pad "D19" smd circle
			(at 2.800096 -9.19988 180)
			(size 0.3556 0.3556)
			(layers "F.Cu" "F.Mask" "F.Paste")
			(net "GND")
		)
		(pad "D20" smd circle
			(at 3.599942 -9.19988 180)
			(size 0.3556 0.3556)
			(layers "F.Cu" "F.Mask" "F.Paste")
			(net "P1V8")
		)
		(pad "D21" smd circle
			(at 4.400042 -9.19988 180)
			(size 0.3556 0.3556)
			(layers "F.Cu" "F.Mask" "F.Paste")
			(net "GND")
		)
		(pad "D22" smd circle
			(at 5.199888 -9.19988 180)
			(size 0.3556 0.3556)
			(layers "F.Cu" "F.Mask" "F.Paste")
			(net "P1V8")
		)
		(pad "D23" smd circle
			(at 5.999988 -9.19988 180)
			(size 0.3556 0.3556)
			(layers "F.Cu" "F.Mask" "F.Paste")
			(net "GND")
		)
		(pad "D24" smd circle
			(at 6.800088 -9.19988 180)
			(size 0.3556 0.3556)
			(layers "F.Cu" "F.Mask" "F.Paste")
			(net "P1V8")
		)
		(pad "D25" smd circle
			(at 7.599934 -9.19988 180)
			(size 0.3556 0.3556)
			(layers "F.Cu" "F.Mask" "F.Paste")
			(net "GND")
		)
		(pad "D26" smd circle
			(at 8.400034 -9.19988 180)
			(size 0.3556 0.3556)
			(layers "F.Cu" "F.Mask" "F.Paste")
			(net "P1V8")
		)
		(pad "D27" smd circle
			(at 9.19988 -9.19988 180)
			(size 0.3556 0.3556)
			(layers "F.Cu" "F.Mask" "F.Paste")
			(net "GND")
		)
		(pad "D28" smd circle
			(at 9.99998 -9.19988 180)
			(size 0.3556 0.3556)
			(layers "F.Cu" "F.Mask" "F.Paste")
			(net "XM_ADDR_9")
		)
		(pad "D29" smd circle
			(at 10.80008 -9.19988 180)
			(size 0.3556 0.3556)
			(layers "F.Cu" "F.Mask" "F.Paste")
			(net "XM_ADDR_10")
		)
		(pad "D30" smd circle
			(at 11.599926 -9.19988 180)
			(size 0.3556 0.3556)
			(layers "F.Cu" "F.Mask" "F.Paste")
			(net "XM_ADDR_17")
		)
		(pad "E1" smd circle
			(at -11.599926 -8.400034 180)
			(size 0.3556 0.3556)
			(layers "F.Cu" "F.Mask" "F.Paste")
			(net "Net_1251")
		)
		(pad "E2" smd circle
			(at -10.80008 -8.400034 180)
			(size 0.3556 0.3556)
			(layers "F.Cu" "F.Mask" "F.Paste")
			(net "Net_1226")
		)
		(pad "E3" smd circle
			(at -9.99998 -8.400034 180)
			(size 0.3556 0.3556)
			(layers "F.Cu" "F.Mask" "F.Paste")
			(net "GND")
		)
		(pad "E4" smd circle
			(at -9.19988 -8.400034 180)
			(size 0.3556 0.3556)
			(layers "F.Cu" "F.Mask" "F.Paste")
			(net "GND")
		)
		(pad "E5" smd circle
			(at -8.400034 -8.400034 180)
			(size 0.3556 0.3556)
			(layers "F.Cu" "F.Mask" "F.Paste")
			(net "P1V8")
		)
		(pad "E6" smd circle
			(at -7.599934 -8.400034 180)
			(size 0.3556 0.3556)
			(layers "F.Cu" "F.Mask" "F.Paste")
			(net "GND")
		)
		(pad "E7" smd circle
			(at -6.800088 -8.400034 180)
			(size 0.3556 0.3556)
			(layers "F.Cu" "F.Mask" "F.Paste")
			(net "P1V8")
		)
		(pad "E8" smd circle
			(at -5.999988 -8.400034 180)
			(size 0.3556 0.3556)
			(layers "F.Cu" "F.Mask" "F.Paste")
			(net "GND")
		)
		(pad "E9" smd circle
			(at -5.199888 -8.400034 180)
			(size 0.3556 0.3556)
			(layers "F.Cu" "F.Mask" "F.Paste")
			(net "P1V8")
		)
		(pad "E10" smd circle
			(at -4.400042 -8.400034 180)
			(size 0.3556 0.3556)
			(layers "F.Cu" "F.Mask" "F.Paste")
			(net "GND")
		)
		(pad "E11" smd circle
			(at -3.599942 -8.400034 180)
			(size 0.3556 0.3556)
			(layers "F.Cu" "F.Mask" "F.Paste")
			(net "GND")
		)
		(pad "E12" smd circle
			(at -2.800096 -8.400034 180)
			(size 0.3556 0.3556)
			(layers "F.Cu" "F.Mask" "F.Paste")
			(net "GND")
		)
		(pad "E13" smd circle
			(at -1.999996 -8.400034 180)
			(size 0.3556 0.3556)
			(layers "F.Cu" "F.Mask" "F.Paste")
			(net "GND")
		)
		(pad "E14" smd circle
			(at -1.199896 -8.400034 180)
			(size 0.3556 0.3556)
			(layers "F.Cu" "F.Mask" "F.Paste")
			(net "GND")
		)
		(pad "E15" smd circle
			(at -0.40005 -8.400034 180)
			(size 0.3556 0.3556)
			(layers "F.Cu" "F.Mask" "F.Paste")
			(net "P1V8")
		)
		(pad "E16" smd circle
			(at 0.40005 -8.400034 180)
			(size 0.3556 0.3556)
			(layers "F.Cu" "F.Mask" "F.Paste")
			(net "GND")
		)
		(pad "E17" smd circle
			(at 1.199896 -8.400034 180)
			(size 0.3556 0.3556)
			(layers "F.Cu" "F.Mask" "F.Paste")
			(net "P1V8")
		)
		(pad "E18" smd circle
			(at 1.999996 -8.400034 180)
			(size 0.3556 0.3556)
			(layers "F.Cu" "F.Mask" "F.Paste")
			(net "GND")
		)
		(pad "E19" smd circle
			(at 2.800096 -8.400034 180)
			(size 0.3556 0.3556)
			(layers "F.Cu" "F.Mask" "F.Paste")
			(net "P1V8")
		)
		(pad "E20" smd circle
			(at 3.599942 -8.400034 180)
			(size 0.3556 0.3556)
			(layers "F.Cu" "F.Mask" "F.Paste")
			(net "GND")
		)
		(pad "E21" smd circle
			(at 4.400042 -8.400034 180)
			(size 0.3556 0.3556)
			(layers "F.Cu" "F.Mask" "F.Paste")
			(net "P1V8")
		)
		(pad "E22" smd circle
			(at 5.199888 -8.400034 180)
			(size 0.3556 0.3556)
			(layers "F.Cu" "F.Mask" "F.Paste")
			(net "GND")
		)
		(pad "E23" smd circle
			(at 5.999988 -8.400034 180)
			(size 0.3556 0.3556)
			(layers "F.Cu" "F.Mask" "F.Paste")
			(net "P1V8")
		)
		(pad "E24" smd circle
			(at 6.800088 -8.400034 180)
			(size 0.3556 0.3556)
			(layers "F.Cu" "F.Mask" "F.Paste")
			(net "GND")
		)
		(pad "E25" smd circle
			(at 7.599934 -8.400034 180)
			(size 0.3556 0.3556)
			(layers "F.Cu" "F.Mask" "F.Paste")
			(net "P1V8")
		)
		(pad "E26" smd circle
			(at 8.400034 -8.400034 180)
			(size 0.3556 0.3556)
			(layers "F.Cu" "F.Mask" "F.Paste")
			(net "GND")
		)
		(pad "E27" smd circle
			(at 9.19988 -8.400034 180)
			(size 0.3556 0.3556)
			(layers "F.Cu" "F.Mask" "F.Paste")
			(net "P1V8")
		)
		(pad "E28" smd circle
			(at 9.99998 -8.400034 180)
			(size 0.3556 0.3556)
			(layers "F.Cu" "F.Mask" "F.Paste")
			(net "XM_ADDR_12")
		)
		(pad "E29" smd circle
			(at 10.80008 -8.400034 180)
			(size 0.3556 0.3556)
			(layers "F.Cu" "F.Mask" "F.Paste")
			(net "XM_DATA_14")
		)
		(pad "E30" smd circle
			(at 11.599926 -8.400034 180)
			(size 0.3556 0.3556)
			(layers "F.Cu" "F.Mask" "F.Paste")
			(net "XM_ADDR_14")
		)
		(pad "F1" smd circle
			(at -11.599926 -7.599934 180)
			(size 0.3556 0.3556)
			(layers "F.Cu" "F.Mask" "F.Paste")
			(net "Net_1252")
		)
		(pad "F2" smd circle
			(at -10.80008 -7.599934 180)
			(size 0.3556 0.3556)
			(layers "F.Cu" "F.Mask" "F.Paste")
			(net "Net_1227")
		)
		(pad "F3" smd circle
			(at -9.99998 -7.599934 180)
			(size 0.3556 0.3556)
			(layers "F.Cu" "F.Mask" "F.Paste")
			(net "Net_1228")
		)
		(pad "F4" smd circle
			(at -9.19988 -7.599934 180)
			(size 0.3556 0.3556)
			(layers "F.Cu" "F.Mask" "F.Paste")
			(net "P1V8")
		)
		(pad "F5" smd circle
			(at -8.400034 -7.599934 180)
			(size 0.3556 0.3556)
			(layers "F.Cu" "F.Mask" "F.Paste")
			(net "GND")
		)
		(pad "F6" smd circle
			(at -7.599934 -7.599934 180)
			(size 0.3556 0.3556)
			(layers "F.Cu" "F.Mask" "F.Paste")
			(net "Net_1229")
		)
		(pad "F7" smd circle
			(at -6.800088 -7.599934 180)
			(size 0.3556 0.3556)
			(layers "F.Cu" "F.Mask" "F.Paste")
			(net "Net_1230")
		)
		(pad "F8" smd circle
			(at -5.999988 -7.599934 180)
			(size 0.3556 0.3556)
			(layers "F.Cu" "F.Mask" "F.Paste")
			(net "Net_1231")
		)
		(pad "F9" smd circle
			(at -5.199888 -7.599934 180)
			(size 0.3556 0.3556)
			(layers "F.Cu" "F.Mask" "F.Paste")
			(net "Net_1232")
		)
		(pad "F10" smd circle
			(at -4.400042 -7.599934 180)
			(size 0.3556 0.3556)
			(layers "F.Cu" "F.Mask" "F.Paste")
			(net "Net_1233")
		)
		(pad "F11" smd circle
			(at -3.599942 -7.599934 180)
			(size 0.3556 0.3556)
			(layers "F.Cu" "F.Mask" "F.Paste")
			(net "GND")
		)
		(pad "F12" smd circle
			(at -2.800096 -7.599934 180)
			(size 0.3556 0.3556)
			(layers "F.Cu" "F.Mask" "F.Paste")
			(net "GND")
		)
		(pad "F13" smd circle
			(at -1.999996 -7.599934 180)
			(size 0.3556 0.3556)
			(layers "F.Cu" "F.Mask" "F.Paste")
			(net "GND")
		)
		(pad "F14" smd circle
			(at -1.199896 -7.599934 180)
			(size 0.3556 0.3556)
			(layers "F.Cu" "F.Mask" "F.Paste")
			(net "GND")
		)
		(pad "F15" smd circle
			(at -0.40005 -7.599934 180)
			(size 0.3556 0.3556)
			(layers "F.Cu" "F.Mask" "F.Paste")
			(net "GND")
		)
		(pad "F16" smd circle
			(at 0.40005 -7.599934 180)
			(size 0.3556 0.3556)
			(layers "F.Cu" "F.Mask" "F.Paste")
			(net "GND")
		)
		(pad "F17" smd circle
			(at 1.199896 -7.599934 180)
			(size 0.3556 0.3556)
			(layers "F.Cu" "F.Mask" "F.Paste")
			(net "GND")
		)
		(pad "F18" smd circle
			(at 1.999996 -7.599934 180)
			(size 0.3556 0.3556)
			(layers "F.Cu" "F.Mask" "F.Paste")
			(net "GND")
		)
		(pad "F19" smd circle
			(at 2.800096 -7.599934 180)
			(size 0.3556 0.3556)
			(layers "F.Cu" "F.Mask" "F.Paste")
			(net "GND")
		)
		(pad "F20" smd circle
			(at 3.599942 -7.599934 180)
			(size 0.3556 0.3556)
			(layers "F.Cu" "F.Mask" "F.Paste")
			(net "GND")
		)
		(pad "F21" smd circle
			(at 4.400042 -7.599934 180)
			(size 0.3556 0.3556)
			(layers "F.Cu" "F.Mask" "F.Paste")
			(net "GND")
		)
		(pad "F22" smd circle
			(at 5.199888 -7.599934 180)
			(size 0.3556 0.3556)
			(layers "F.Cu" "F.Mask" "F.Paste")
			(net "GND")
		)
		(pad "F23" smd circle
			(at 5.999988 -7.599934 180)
			(size 0.3556 0.3556)
			(layers "F.Cu" "F.Mask" "F.Paste")
			(net "GND")
		)
		(pad "F24" smd circle
			(at 6.800088 -7.599934 180)
			(size 0.3556 0.3556)
			(layers "F.Cu" "F.Mask" "F.Paste")
			(net "GND")
		)
		(pad "F25" smd circle
			(at 7.599934 -7.599934 180)
			(size 0.3556 0.3556)
			(layers "F.Cu" "F.Mask" "F.Paste")
			(net "GND")
		)
		(pad "F26" smd circle
			(at 8.400034 -7.599934 180)
			(size 0.3556 0.3556)
			(layers "F.Cu" "F.Mask" "F.Paste")
			(net "P1V8")
		)
		(pad "F27" smd circle
			(at 9.19988 -7.599934 180)
			(size 0.3556 0.3556)
			(layers "F.Cu" "F.Mask" "F.Paste")
			(net "GND")
		)
		(pad "F28" smd circle
			(at 9.99998 -7.599934 180)
			(size 0.3556 0.3556)
			(layers "F.Cu" "F.Mask" "F.Paste")
			(net "XM_ADDR_19")
		)
		(pad "F29" smd circle
			(at 10.80008 -7.599934 180)
			(size 0.3556 0.3556)
			(layers "F.Cu" "F.Mask" "F.Paste")
			(net "XM_ADDR_16")
		)
		(pad "F30" smd circle
			(at 11.599926 -7.599934 180)
			(size 0.3556 0.3556)
			(layers "F.Cu" "F.Mask" "F.Paste")
			(net "XM_ADDR_20")
		)
		(pad "G1" smd circle
			(at -11.599926 -6.800088 180)
			(size 0.3556 0.3556)
			(layers "F.Cu" "F.Mask" "F.Paste")
			(net "Net_1253")
		)
		(pad "G2" smd circle
			(at -10.80008 -6.800088 180)
			(size 0.3556 0.3556)
			(layers "F.Cu" "F.Mask" "F.Paste")
			(net "Net_1234")
		)
		(pad "G3" smd circle
			(at -9.99998 -6.800088 180)
			(size 0.3556 0.3556)
			(layers "F.Cu" "F.Mask" "F.Paste")
			(net "Net_1235")
		)
		(pad "G4" smd circle
			(at -9.19988 -6.800088 180)
			(size 0.3556 0.3556)
			(layers "F.Cu" "F.Mask" "F.Paste")
			(net "GND")
		)
		(pad "G5" smd circle
			(at -8.400034 -6.800088 180)
			(size 0.3556 0.3556)
			(layers "F.Cu" "F.Mask" "F.Paste")
			(net "P1V8")
		)
		(pad "G6" smd circle
			(at -7.599934 -6.800088 180)
			(size 0.3556 0.3556)
			(layers "F.Cu" "F.Mask" "F.Paste")
			(net "Net_1236")
		)
		(pad "G7" smd circle
			(at -6.800088 -6.800088 180)
			(size 0.3556 0.3556)
			(layers "F.Cu" "F.Mask" "F.Paste")
			(net "GND")
		)
		(pad "G8" smd circle
			(at -5.999988 -6.800088 180)
			(size 0.3556 0.3556)
			(layers "F.Cu" "F.Mask" "F.Paste")
			(net "GND")
		)
		(pad "G9" smd circle
			(at -5.199888 -6.800088 180)
			(size 0.3556 0.3556)
			(layers "F.Cu" "F.Mask" "F.Paste")
			(net "GND")
		)
		(pad "G10" smd circle
			(at -4.400042 -6.800088 180)
			(size 0.3556 0.3556)
			(layers "F.Cu" "F.Mask" "F.Paste")
			(net "GND")
		)
		(pad "G11" smd circle
			(at -3.599942 -6.800088 180)
			(size 0.3556 0.3556)
			(layers "F.Cu" "F.Mask" "F.Paste")
			(net "GND")
		)
		(pad "G12" smd circle
			(at -2.800096 -6.800088 180)
			(size 0.3556 0.3556)
			(layers "F.Cu" "F.Mask" "F.Paste")
			(net "GND")
		)
		(pad "G13" smd circle
			(at -1.999996 -6.800088 180)
			(size 0.3556 0.3556)
			(layers "F.Cu" "F.Mask" "F.Paste")
			(net "GND")
		)
		(pad "G14" smd circle
			(at -1.199896 -6.800088 180)
			(size 0.3556 0.3556)
			(layers "F.Cu" "F.Mask" "F.Paste")
			(net "GND")
		)
		(pad "G15" smd circle
			(at -0.40005 -6.800088 180)
			(size 0.3556 0.3556)
			(layers "F.Cu" "F.Mask" "F.Paste")
			(net "GND")
		)
		(pad "G16" smd circle
			(at 0.40005 -6.800088 180)
			(size 0.3556 0.3556)
			(layers "F.Cu" "F.Mask" "F.Paste")
			(net "GND")
		)
		(pad "G17" smd circle
			(at 1.199896 -6.800088 180)
			(size 0.3556 0.3556)
			(layers "F.Cu" "F.Mask" "F.Paste")
			(net "GND")
		)
		(pad "G18" smd circle
			(at 1.999996 -6.800088 180)
			(size 0.3556 0.3556)
			(layers "F.Cu" "F.Mask" "F.Paste")
			(net "GND")
		)
		(pad "G19" smd circle
			(at 2.800096 -6.800088 180)
			(size 0.3556 0.3556)
			(layers "F.Cu" "F.Mask" "F.Paste")
			(net "GND")
		)
		(pad "G20" smd circle
			(at 3.599942 -6.800088 180)
			(size 0.3556 0.3556)
			(layers "F.Cu" "F.Mask" "F.Paste")
			(net "GND")
		)
		(pad "G21" smd circle
			(at 4.400042 -6.800088 180)
			(size 0.3556 0.3556)
			(layers "F.Cu" "F.Mask" "F.Paste")
			(net "GND")
		)
		(pad "G22" smd circle
			(at 5.199888 -6.800088 180)
			(size 0.3556 0.3556)
			(layers "F.Cu" "F.Mask" "F.Paste")
			(net "GND")
		)
		(pad "G23" smd circle
			(at 5.999988 -6.800088 180)
			(size 0.3556 0.3556)
			(layers "F.Cu" "F.Mask" "F.Paste")
			(net "GND")
		)
		(pad "G24" smd circle
			(at 6.800088 -6.800088 180)
			(size 0.3556 0.3556)
			(layers "F.Cu" "F.Mask" "F.Paste")
			(net "GND")
		)
		(pad "G25" smd circle
			(at 7.599934 -6.800088 180)
			(size 0.3556 0.3556)
			(layers "F.Cu" "F.Mask" "F.Paste")
			(net "GND")
		)
		(pad "G26" smd circle
			(at 8.400034 -6.800088 180)
			(size 0.3556 0.3556)
			(layers "F.Cu" "F.Mask" "F.Paste")
			(net "GND")
		)
		(pad "G27" smd circle
			(at 9.19988 -6.800088 180)
			(size 0.3556 0.3556)
			(layers "F.Cu" "F.Mask" "F.Paste")
			(net "P1V8")
		)
		(pad "G28" smd circle
			(at 9.99998 -6.800088 180)
			(size 0.3556 0.3556)
			(layers "F.Cu" "F.Mask" "F.Paste")
			(net "XM_ADDR_15")
		)
		(pad "G29" smd circle
			(at 10.80008 -6.800088 180)
			(size 0.3556 0.3556)
			(layers "F.Cu" "F.Mask" "F.Paste")
			(net "XM_ADDR_21")
		)
		(pad "G30" smd circle
			(at 11.599926 -6.800088 180)
			(size 0.3556 0.3556)
			(layers "F.Cu" "F.Mask" "F.Paste")
			(net "XM_DATA_13")
		)
		(pad "H1" smd circle
			(at -11.599926 -5.999988 180)
			(size 0.3556 0.3556)
			(layers "F.Cu" "F.Mask" "F.Paste")
			(net "GND")
		)
		(pad "H2" smd circle
			(at -10.80008 -5.999988 180)
			(size 0.3556 0.3556)
			(layers "F.Cu" "F.Mask" "F.Paste")
			(net "Net_1237")
		)
		(pad "H3" smd circle
			(at -9.99998 -5.999988 180)
			(size 0.3556 0.3556)
			(layers "F.Cu" "F.Mask" "F.Paste")
			(net "Net_1238")
		)
		(pad "H4" smd circle
			(at -9.19988 -5.999988 180)
			(size 0.3556 0.3556)
			(layers "F.Cu" "F.Mask" "F.Paste")
			(net "P1V8")
		)
		(pad "H5" smd circle
			(at -8.400034 -5.999988 180)
			(size 0.3556 0.3556)
			(layers "F.Cu" "F.Mask" "F.Paste")
			(net "GND")
		)
		(pad "H6" smd circle
			(at -7.599934 -5.999988 180)
			(size 0.3556 0.3556)
			(layers "F.Cu" "F.Mask" "F.Paste")
			(net "Net_1239")
		)
		(pad "H7" smd circle
			(at -6.800088 -5.999988 180)
			(size 0.3556 0.3556)
			(layers "F.Cu" "F.Mask" "F.Paste")
			(net "GND")
		)
		(pad "H8" smd circle
			(at -5.999988 -5.999988 180)
			(size 0.3556 0.3556)
			(layers "F.Cu" "F.Mask" "F.Paste")
			(net "GND")
		)
		(pad "H9" smd circle
			(at -5.199888 -5.999988 180)
			(size 0.3556 0.3556)
			(layers "F.Cu" "F.Mask" "F.Paste")
			(net "GND")
		)
		(pad "H10" smd circle
			(at -4.400042 -5.999988 180)
			(size 0.3556 0.3556)
			(layers "F.Cu" "F.Mask" "F.Paste")
			(net "GND")
		)
		(pad "H11" smd circle
			(at -3.599942 -5.999988 180)
			(size 0.3556 0.3556)
			(layers "F.Cu" "F.Mask" "F.Paste")
			(net "GND")
		)
		(pad "H12" smd circle
			(at -2.800096 -5.999988 180)
			(size 0.3556 0.3556)
			(layers "F.Cu" "F.Mask" "F.Paste")
			(net "GND")
		)
		(pad "H13" smd circle
			(at -1.999996 -5.999988 180)
			(size 0.3556 0.3556)
			(layers "F.Cu" "F.Mask" "F.Paste")
			(net "GND")
		)
		(pad "H14" smd circle
			(at -1.199896 -5.999988 180)
			(size 0.3556 0.3556)
			(layers "F.Cu" "F.Mask" "F.Paste")
			(net "GND")
		)
		(pad "H15" smd circle
			(at -0.40005 -5.999988 180)
			(size 0.3556 0.3556)
			(layers "F.Cu" "F.Mask" "F.Paste")
			(net "GND")
		)
		(pad "H16" smd circle
			(at 0.40005 -5.999988 180)
			(size 0.3556 0.3556)
			(layers "F.Cu" "F.Mask" "F.Paste")
			(net "GND")
		)
		(pad "H17" smd circle
			(at 1.199896 -5.999988 180)
			(size 0.3556 0.3556)
			(layers "F.Cu" "F.Mask" "F.Paste")
			(net "GND")
		)
		(pad "H18" smd circle
			(at 1.999996 -5.999988 180)
			(size 0.3556 0.3556)
			(layers "F.Cu" "F.Mask" "F.Paste")
			(net "GND")
		)
		(pad "H19" smd circle
			(at 2.800096 -5.999988 180)
			(size 0.3556 0.3556)
			(layers "F.Cu" "F.Mask" "F.Paste")
			(net "GND")
		)
		(pad "H20" smd circle
			(at 3.599942 -5.999988 180)
			(size 0.3556 0.3556)
			(layers "F.Cu" "F.Mask" "F.Paste")
			(net "GND")
		)
		(pad "H21" smd circle
			(at 4.400042 -5.999988 180)
			(size 0.3556 0.3556)
			(layers "F.Cu" "F.Mask" "F.Paste")
			(net "GND")
		)
		(pad "H22" smd circle
			(at 5.199888 -5.999988 180)
			(size 0.3556 0.3556)
			(layers "F.Cu" "F.Mask" "F.Paste")
			(net "GND")
		)
		(pad "H23" smd circle
			(at 5.999988 -5.999988 180)
			(size 0.3556 0.3556)
			(layers "F.Cu" "F.Mask" "F.Paste")
			(net "GND")
		)
		(pad "H24" smd circle
			(at 6.800088 -5.999988 180)
			(size 0.3556 0.3556)
			(layers "F.Cu" "F.Mask" "F.Paste")
			(net "GND")
		)
		(pad "H25" smd circle
			(at 7.599934 -5.999988 180)
			(size 0.3556 0.3556)
			(layers "F.Cu" "F.Mask" "F.Paste")
			(net "GND")
		)
		(pad "H26" smd circle
			(at 8.400034 -5.999988 180)
			(size 0.3556 0.3556)
			(layers "F.Cu" "F.Mask" "F.Paste")
			(net "P1V8")
		)
		(pad "H27" smd circle
			(at 9.19988 -5.999988 180)
			(size 0.3556 0.3556)
			(layers "F.Cu" "F.Mask" "F.Paste")
			(net "GND")
		)
		(pad "H28" smd circle
			(at 9.99998 -5.999988 180)
			(size 0.3556 0.3556)
			(layers "F.Cu" "F.Mask" "F.Paste")
			(net "XM_DATA_0")
		)
		(pad "H29" smd circle
			(at 10.80008 -5.999988 180)
			(size 0.3556 0.3556)
			(layers "F.Cu" "F.Mask" "F.Paste")
			(net "XM_ADDR_25")
		)
		(pad "H30" smd circle
			(at 11.599926 -5.999988 180)
			(size 0.3556 0.3556)
			(layers "F.Cu" "F.Mask" "F.Paste")
			(net "XM_ADDR_18")
		)
		(pad "J1" smd circle
			(at -11.599926 -5.199888 180)
			(size 0.3556 0.3556)
			(layers "F.Cu" "F.Mask" "F.Paste")
			(net "Net_1254")
		)
		(pad "J2" smd circle
			(at -10.80008 -5.199888 180)
			(size 0.3556 0.3556)
			(layers "F.Cu" "F.Mask" "F.Paste")
			(net "Net_1240")
		)
		(pad "J3" smd circle
			(at -9.99998 -5.199888 180)
			(size 0.3556 0.3556)
			(layers "F.Cu" "F.Mask" "F.Paste")
			(net "Net_1241")
		)
		(pad "J4" smd circle
			(at -9.19988 -5.199888 180)
			(size 0.3556 0.3556)
			(layers "F.Cu" "F.Mask" "F.Paste")
			(net "GND")
		)
		(pad "J5" smd circle
			(at -8.400034 -5.199888 180)
			(size 0.3556 0.3556)
			(layers "F.Cu" "F.Mask" "F.Paste")
			(net "P1V8")
		)
		(pad "J6" smd circle
			(at -7.599934 -5.199888 180)
			(size 0.3556 0.3556)
			(layers "F.Cu" "F.Mask" "F.Paste")
			(net "Net_1242")
		)
		(pad "J7" smd circle
			(at -6.800088 -5.199888 180)
			(size 0.3556 0.3556)
			(layers "F.Cu" "F.Mask" "F.Paste")
			(net "GND")
		)
		(pad "J8" smd circle
			(at -5.999988 -5.199888 180)
			(size 0.3556 0.3556)
			(layers "F.Cu" "F.Mask" "F.Paste")
			(net "GND")
		)
		(pad "J9" smd circle
			(at -5.199888 -5.199888 180)
			(size 0.3556 0.3556)
			(layers "F.Cu" "F.Mask" "F.Paste")
			(net "GND")
		)
		(pad "J10" smd circle
			(at -4.400042 -5.199888 180)
			(size 0.3556 0.3556)
			(layers "F.Cu" "F.Mask" "F.Paste")
			(net "GND")
		)
		(pad "J11" smd circle
			(at -3.599942 -5.199888 180)
			(size 0.3556 0.3556)
			(layers "F.Cu" "F.Mask" "F.Paste")
			(net "GND")
		)
		(pad "J12" smd circle
			(at -2.800096 -5.199888 180)
			(size 0.3556 0.3556)
			(layers "F.Cu" "F.Mask" "F.Paste")
			(net "P0V975")
		)
		(pad "J13" smd circle
			(at -1.999996 -5.199888 180)
			(size 0.3556 0.3556)
			(layers "F.Cu" "F.Mask" "F.Paste")
			(net "GND")
		)
		(pad "J14" smd circle
			(at -1.199896 -5.199888 180)
			(size 0.3556 0.3556)
			(layers "F.Cu" "F.Mask" "F.Paste")
			(net "GND")
		)
		(pad "J15" smd circle
			(at -0.40005 -5.199888 180)
			(size 0.3556 0.3556)
			(layers "F.Cu" "F.Mask" "F.Paste")
			(net "GND")
		)
		(pad "J16" smd circle
			(at 0.40005 -5.199888 180)
			(size 0.3556 0.3556)
			(layers "F.Cu" "F.Mask" "F.Paste")
			(net "GND")
		)
		(pad "J17" smd circle
			(at 1.199896 -5.199888 180)
			(size 0.3556 0.3556)
			(layers "F.Cu" "F.Mask" "F.Paste")
			(net "GND")
		)
		(pad "J18" smd circle
			(at 1.999996 -5.199888 180)
			(size 0.3556 0.3556)
			(layers "F.Cu" "F.Mask" "F.Paste")
			(net "GND")
		)
		(pad "J19" smd circle
			(at 2.800096 -5.199888 180)
			(size 0.3556 0.3556)
			(layers "F.Cu" "F.Mask" "F.Paste")
			(net "GND")
		)
		(pad "J20" smd circle
			(at 3.599942 -5.199888 180)
			(size 0.3556 0.3556)
			(layers "F.Cu" "F.Mask" "F.Paste")
			(net "GND")
		)
		(pad "J21" smd circle
			(at 4.400042 -5.199888 180)
			(size 0.3556 0.3556)
			(layers "F.Cu" "F.Mask" "F.Paste")
			(net "GND")
		)
		(pad "J22" smd circle
			(at 5.199888 -5.199888 180)
			(size 0.3556 0.3556)
			(layers "F.Cu" "F.Mask" "F.Paste")
			(net "GND")
		)
		(pad "J23" smd circle
			(at 5.999988 -5.199888 180)
			(size 0.3556 0.3556)
			(layers "F.Cu" "F.Mask" "F.Paste")
			(net "GND")
		)
		(pad "J24" smd circle
			(at 6.800088 -5.199888 180)
			(size 0.3556 0.3556)
			(layers "F.Cu" "F.Mask" "F.Paste")
			(net "GND")
		)
		(pad "J25" smd circle
			(at 7.599934 -5.199888 180)
			(size 0.3556 0.3556)
			(layers "F.Cu" "F.Mask" "F.Paste")
			(net "GND")
		)
		(pad "J26" smd circle
			(at 8.400034 -5.199888 180)
			(size 0.3556 0.3556)
			(layers "F.Cu" "F.Mask" "F.Paste")
			(net "GND")
		)
		(pad "J27" smd circle
			(at 9.19988 -5.199888 180)
			(size 0.3556 0.3556)
			(layers "F.Cu" "F.Mask" "F.Paste")
			(net "P1V8")
		)
		(pad "J28" smd circle
			(at 9.99998 -5.199888 180)
			(size 0.3556 0.3556)
			(layers "F.Cu" "F.Mask" "F.Paste")
			(net "XM_DATA_12")
		)
		(pad "J29" smd circle
			(at 10.80008 -5.199888 180)
			(size 0.3556 0.3556)
			(layers "F.Cu" "F.Mask" "F.Paste")
			(net "XM_ADDR_22")
		)
		(pad "J30" smd circle
			(at 11.599926 -5.199888 180)
			(size 0.3556 0.3556)
			(layers "F.Cu" "F.Mask" "F.Paste")
			(net "XM_ADDR_24")
		)
		(pad "K1" smd circle
			(at -11.599926 -4.400042 180)
			(size 0.3556 0.3556)
			(layers "F.Cu" "F.Mask" "F.Paste")
			(net "SIO_LOAD_1")
		)
		(pad "K2" smd circle
			(at -10.80008 -4.400042 180)
			(size 0.3556 0.3556)
			(layers "F.Cu" "F.Mask" "F.Paste")
			(net "SIO_DOUT_0")
		)
		(pad "K3" smd circle
			(at -9.99998 -4.400042 180)
			(size 0.3556 0.3556)
			(layers "F.Cu" "F.Mask" "F.Paste")
			(net "GND")
		)
		(pad "K4" smd circle
			(at -9.19988 -4.400042 180)
			(size 0.3556 0.3556)
			(layers "F.Cu" "F.Mask" "F.Paste")
			(net "P1V8")
		)
		(pad "K5" smd circle
			(at -8.400034 -4.400042 180)
			(size 0.3556 0.3556)
			(layers "F.Cu" "F.Mask" "F.Paste")
			(net "GND")
		)
		(pad "K6" smd circle
			(at -7.599934 -4.400042 180)
			(size 0.3556 0.3556)
			(layers "F.Cu" "F.Mask" "F.Paste")
			(net "Net_1243")
		)
		(pad "K7" smd circle
			(at -6.800088 -4.400042 180)
			(size 0.3556 0.3556)
			(layers "F.Cu" "F.Mask" "F.Paste")
			(net "GND")
		)
		(pad "K8" smd circle
			(at -5.999988 -4.400042 180)
			(size 0.3556 0.3556)
			(layers "F.Cu" "F.Mask" "F.Paste")
			(net "GND")
		)
		(pad "K9" smd circle
			(at -5.199888 -4.400042 180)
			(size 0.3556 0.3556)
			(layers "F.Cu" "F.Mask" "F.Paste")
			(net "GND")
		)
		(pad "K10" smd circle
			(at -4.400042 -4.400042 180)
			(size 0.3556 0.3556)
			(layers "F.Cu" "F.Mask" "F.Paste")
			(net "GND")
		)
		(pad "K11" smd circle
			(at -3.599942 -4.400042 180)
			(size 0.3556 0.3556)
			(layers "F.Cu" "F.Mask" "F.Paste")
			(net "GND")
		)
		(pad "K12" smd circle
			(at -2.800096 -4.400042 180)
			(size 0.3556 0.3556)
			(layers "F.Cu" "F.Mask" "F.Paste")
			(net "GND")
		)
		(pad "K13" smd circle
			(at -1.999996 -4.400042 180)
			(size 0.3556 0.3556)
			(layers "F.Cu" "F.Mask" "F.Paste")
			(net "P0V975")
		)
		(pad "K14" smd circle
			(at -1.199896 -4.400042 180)
			(size 0.3556 0.3556)
			(layers "F.Cu" "F.Mask" "F.Paste")
			(net "GND")
		)
		(pad "K15" smd circle
			(at -0.40005 -4.400042 180)
			(size 0.3556 0.3556)
			(layers "F.Cu" "F.Mask" "F.Paste")
			(net "GND")
		)
		(pad "K16" smd circle
			(at 0.40005 -4.400042 180)
			(size 0.3556 0.3556)
			(layers "F.Cu" "F.Mask" "F.Paste")
			(net "GND")
		)
		(pad "K17" smd circle
			(at 1.199896 -4.400042 180)
			(size 0.3556 0.3556)
			(layers "F.Cu" "F.Mask" "F.Paste")
			(net "GND")
		)
		(pad "K18" smd circle
			(at 1.999996 -4.400042 180)
			(size 0.3556 0.3556)
			(layers "F.Cu" "F.Mask" "F.Paste")
			(net "GND")
		)
		(pad "K19" smd circle
			(at 2.800096 -4.400042 180)
			(size 0.3556 0.3556)
			(layers "F.Cu" "F.Mask" "F.Paste")
			(net "GND")
		)
		(pad "K20" smd circle
			(at 3.599942 -4.400042 180)
			(size 0.3556 0.3556)
			(layers "F.Cu" "F.Mask" "F.Paste")
			(net "GND")
		)
		(pad "K21" smd circle
			(at 4.400042 -4.400042 180)
			(size 0.3556 0.3556)
			(layers "F.Cu" "F.Mask" "F.Paste")
			(net "P0V975")
		)
		(pad "K22" smd circle
			(at 5.199888 -4.400042 180)
			(size 0.3556 0.3556)
			(layers "F.Cu" "F.Mask" "F.Paste")
			(net "GND")
		)
		(pad "K23" smd circle
			(at 5.999988 -4.400042 180)
			(size 0.3556 0.3556)
			(layers "F.Cu" "F.Mask" "F.Paste")
			(net "GND")
		)
		(pad "K24" smd circle
			(at 6.800088 -4.400042 180)
			(size 0.3556 0.3556)
			(layers "F.Cu" "F.Mask" "F.Paste")
			(net "GND")
		)
		(pad "K25" smd circle
			(at 7.599934 -4.400042 180)
			(size 0.3556 0.3556)
			(layers "F.Cu" "F.Mask" "F.Paste")
			(net "GND")
		)
		(pad "K26" smd circle
			(at 8.400034 -4.400042 180)
			(size 0.3556 0.3556)
			(layers "F.Cu" "F.Mask" "F.Paste")
			(net "P1V8")
		)
		(pad "K27" smd circle
			(at 9.19988 -4.400042 180)
			(size 0.3556 0.3556)
			(layers "F.Cu" "F.Mask" "F.Paste")
			(net "GND")
		)
		(pad "K28" smd circle
			(at 9.99998 -4.400042 180)
			(size 0.3556 0.3556)
			(layers "F.Cu" "F.Mask" "F.Paste")
			(net "XM_DATA_2")
		)
		(pad "K29" smd circle
			(at 10.80008 -4.400042 180)
			(size 0.3556 0.3556)
			(layers "F.Cu" "F.Mask" "F.Paste")
			(net "XM_ADDR_23")
		)
		(pad "K30" smd circle
			(at 11.599926 -4.400042 180)
			(size 0.3556 0.3556)
			(layers "F.Cu" "F.Mask" "F.Paste")
			(net "XM_DATA_1")
		)
		(pad "L1" smd circle
			(at -11.599926 -3.599942 180)
			(size 0.3556 0.3556)
			(layers "F.Cu" "F.Mask" "F.Paste")
			(net "SIO_CLK_1")
		)
		(pad "L2" smd circle
			(at -10.80008 -3.599942 180)
			(size 0.3556 0.3556)
			(layers "F.Cu" "F.Mask" "F.Paste")
			(net "SIO_DIN_1")
		)
		(pad "L3" smd circle
			(at -9.99998 -3.599942 180)
			(size 0.3556 0.3556)
			(layers "F.Cu" "F.Mask" "F.Paste")
			(net "Net_1244")
		)
		(pad "L4" smd circle
			(at -9.19988 -3.599942 180)
			(size 0.3556 0.3556)
			(layers "F.Cu" "F.Mask" "F.Paste")
			(net "GND")
		)
		(pad "L5" smd circle
			(at -8.400034 -3.599942 180)
			(size 0.3556 0.3556)
			(layers "F.Cu" "F.Mask" "F.Paste")
			(net "P1V8")
		)
		(pad "L6" smd circle
			(at -7.599934 -3.599942 180)
			(size 0.3556 0.3556)
			(layers "F.Cu" "F.Mask" "F.Paste")
			(net "ICE1_TDI")
		)
		(pad "L7" smd circle
			(at -6.800088 -3.599942 180)
			(size 0.3556 0.3556)
			(layers "F.Cu" "F.Mask" "F.Paste")
			(net "GND")
		)
		(pad "L8" smd circle
			(at -5.999988 -3.599942 180)
			(size 0.3556 0.3556)
			(layers "F.Cu" "F.Mask" "F.Paste")
			(net "GND")
		)
		(pad "L9" smd circle
			(at -5.199888 -3.599942 180)
			(size 0.3556 0.3556)
			(layers "F.Cu" "F.Mask" "F.Paste")
			(net "GND")
		)
		(pad "L10" smd circle
			(at -4.400042 -3.599942 180)
			(size 0.3556 0.3556)
			(layers "F.Cu" "F.Mask" "F.Paste")
			(net "GND")
		)
		(pad "L11" smd circle
			(at -3.599942 -3.599942 180)
			(size 0.3556 0.3556)
			(layers "F.Cu" "F.Mask" "F.Paste")
			(net "GND")
		)
		(pad "L12" smd circle
			(at -2.800096 -3.599942 180)
			(size 0.3556 0.3556)
			(layers "F.Cu" "F.Mask" "F.Paste")
			(net "GND")
		)
		(pad "L13" smd circle
			(at -1.999996 -3.599942 180)
			(size 0.3556 0.3556)
			(layers "F.Cu" "F.Mask" "F.Paste")
			(net "GND")
		)
		(pad "L14" smd circle
			(at -1.199896 -3.599942 180)
			(size 0.3556 0.3556)
			(layers "F.Cu" "F.Mask" "F.Paste")
			(net "P0V975")
		)
		(pad "L15" smd circle
			(at -0.40005 -3.599942 180)
			(size 0.3556 0.3556)
			(layers "F.Cu" "F.Mask" "F.Paste")
			(net "GND")
		)
		(pad "L16" smd circle
			(at 0.40005 -3.599942 180)
			(size 0.3556 0.3556)
			(layers "F.Cu" "F.Mask" "F.Paste")
			(net "P0V975")
		)
		(pad "L17" smd circle
			(at 1.199896 -3.599942 180)
			(size 0.3556 0.3556)
			(layers "F.Cu" "F.Mask" "F.Paste")
			(net "GND")
		)
		(pad "L18" smd circle
			(at 1.999996 -3.599942 180)
			(size 0.3556 0.3556)
			(layers "F.Cu" "F.Mask" "F.Paste")
			(net "P0V975")
		)
		(pad "L19" smd circle
			(at 2.800096 -3.599942 180)
			(size 0.3556 0.3556)
			(layers "F.Cu" "F.Mask" "F.Paste")
			(net "GND")
		)
		(pad "L20" smd circle
			(at 3.599942 -3.599942 180)
			(size 0.3556 0.3556)
			(layers "F.Cu" "F.Mask" "F.Paste")
			(net "P0V975")
		)
		(pad "L21" smd circle
			(at 4.400042 -3.599942 180)
			(size 0.3556 0.3556)
			(layers "F.Cu" "F.Mask" "F.Paste")
			(net "GND")
		)
		(pad "L22" smd circle
			(at 5.199888 -3.599942 180)
			(size 0.3556 0.3556)
			(layers "F.Cu" "F.Mask" "F.Paste")
			(net "VDDIO_15")
		)
		(pad "L23" smd circle
			(at 5.999988 -3.599942 180)
			(size 0.3556 0.3556)
			(layers "F.Cu" "F.Mask" "F.Paste")
			(net "GND")
		)
		(pad "L24" smd circle
			(at 6.800088 -3.599942 180)
			(size 0.3556 0.3556)
			(layers "F.Cu" "F.Mask" "F.Paste")
			(net "GND")
		)
		(pad "L25" smd circle
			(at 7.599934 -3.599942 180)
			(size 0.3556 0.3556)
			(layers "F.Cu" "F.Mask" "F.Paste")
			(net "GND")
		)
		(pad "L26" smd circle
			(at 8.400034 -3.599942 180)
			(size 0.3556 0.3556)
			(layers "F.Cu" "F.Mask" "F.Paste")
			(net "GND")
		)
		(pad "L27" smd circle
			(at 9.19988 -3.599942 180)
			(size 0.3556 0.3556)
			(layers "F.Cu" "F.Mask" "F.Paste")
			(net "P1V8")
		)
		(pad "L28" smd circle
			(at 9.99998 -3.599942 180)
			(size 0.3556 0.3556)
			(layers "F.Cu" "F.Mask" "F.Paste")
			(net "GND")
		)
		(pad "L29" smd circle
			(at 10.80008 -3.599942 180)
			(size 0.3556 0.3556)
			(layers "F.Cu" "F.Mask" "F.Paste")
			(net "XM_DATA_4")
		)
		(pad "L30" smd circle
			(at 11.599926 -3.599942 180)
			(size 0.3556 0.3556)
			(layers "F.Cu" "F.Mask" "F.Paste")
			(net "XM_DATA_3")
		)
		(pad "M1" smd circle
			(at -11.599926 -2.800096 180)
			(size 0.3556 0.3556)
			(layers "F.Cu" "F.Mask" "F.Paste")
			(net "SIO_CLK_0")
		)
		(pad "M2" smd circle
			(at -10.80008 -2.800096 180)
			(size 0.3556 0.3556)
			(layers "F.Cu" "F.Mask" "F.Paste")
			(net "SIO_DOUT_1")
		)
		(pad "M3" smd circle
			(at -9.99998 -2.800096 180)
			(size 0.3556 0.3556)
			(layers "F.Cu" "F.Mask" "F.Paste")
			(net "SIO_LOAD_0")
		)
		(pad "M4" smd circle
			(at -9.19988 -2.800096 180)
			(size 0.3556 0.3556)
			(layers "F.Cu" "F.Mask" "F.Paste")
			(net "P1V8")
		)
		(pad "M5" smd circle
			(at -8.400034 -2.800096 180)
			(size 0.3556 0.3556)
			(layers "F.Cu" "F.Mask" "F.Paste")
			(net "GND")
		)
		(pad "M6" smd circle
			(at -7.599934 -2.800096 180)
			(size 0.3556 0.3556)
			(layers "F.Cu" "F.Mask" "F.Paste")
			(net "ICE_SEL")
		)
		(pad "M7" smd circle
			(at -6.800088 -2.800096 180)
			(size 0.3556 0.3556)
			(layers "F.Cu" "F.Mask" "F.Paste")
			(net "GND")
		)
		(pad "M8" smd circle
			(at -5.999988 -2.800096 180)
			(size 0.3556 0.3556)
			(layers "F.Cu" "F.Mask" "F.Paste")
			(net "GND")
		)
		(pad "M9" smd circle
			(at -5.199888 -2.800096 180)
			(size 0.3556 0.3556)
			(layers "F.Cu" "F.Mask" "F.Paste")
			(net "P1V8")
		)
		(pad "M10" smd circle
			(at -4.400042 -2.800096 180)
			(size 0.3556 0.3556)
			(layers "F.Cu" "F.Mask" "F.Paste")
			(net "GND")
		)
		(pad "M11" smd circle
			(at -3.599942 -2.800096 180)
			(size 0.3556 0.3556)
			(layers "F.Cu" "F.Mask" "F.Paste")
			(net "P0V975")
		)
		(pad "M12" smd circle
			(at -2.800096 -2.800096 180)
			(size 0.3556 0.3556)
			(layers "F.Cu" "F.Mask" "F.Paste")
			(net "GND")
		)
		(pad "M13" smd circle
			(at -1.999996 -2.800096 180)
			(size 0.3556 0.3556)
			(layers "F.Cu" "F.Mask" "F.Paste")
			(net "P0V975")
		)
		(pad "M14" smd circle
			(at -1.199896 -2.800096 180)
			(size 0.3556 0.3556)
			(layers "F.Cu" "F.Mask" "F.Paste")
			(net "GND")
		)
		(pad "M15" smd circle
			(at -0.40005 -2.800096 180)
			(size 0.3556 0.3556)
			(layers "F.Cu" "F.Mask" "F.Paste")
			(net "P0V975")
		)
		(pad "M16" smd circle
			(at 0.40005 -2.800096 180)
			(size 0.3556 0.3556)
			(layers "F.Cu" "F.Mask" "F.Paste")
			(net "GND")
		)
		(pad "M17" smd circle
			(at 1.199896 -2.800096 180)
			(size 0.3556 0.3556)
			(layers "F.Cu" "F.Mask" "F.Paste")
			(net "P0V975")
		)
		(pad "M18" smd circle
			(at 1.999996 -2.800096 180)
			(size 0.3556 0.3556)
			(layers "F.Cu" "F.Mask" "F.Paste")
			(net "GND")
		)
		(pad "M19" smd circle
			(at 2.800096 -2.800096 180)
			(size 0.3556 0.3556)
			(layers "F.Cu" "F.Mask" "F.Paste")
			(net "P0V975")
		)
		(pad "M20" smd circle
			(at 3.599942 -2.800096 180)
			(size 0.3556 0.3556)
			(layers "F.Cu" "F.Mask" "F.Paste")
			(net "GND")
		)
		(pad "M21" smd circle
			(at 4.400042 -2.800096 180)
			(size 0.3556 0.3556)
			(layers "F.Cu" "F.Mask" "F.Paste")
			(net "P0V975")
		)
		(pad "M22" smd circle
			(at 5.199888 -2.800096 180)
			(size 0.3556 0.3556)
			(layers "F.Cu" "F.Mask" "F.Paste")
			(net "GND")
		)
		(pad "M23" smd circle
			(at 5.999988 -2.800096 180)
			(size 0.3556 0.3556)
			(layers "F.Cu" "F.Mask" "F.Paste")
			(net "GND")
		)
		(pad "M24" smd circle
			(at 6.800088 -2.800096 180)
			(size 0.3556 0.3556)
			(layers "F.Cu" "F.Mask" "F.Paste")
			(net "GND")
		)
		(pad "M25" smd circle
			(at 7.599934 -2.800096 180)
			(size 0.3556 0.3556)
			(layers "F.Cu" "F.Mask" "F.Paste")
			(net "GND")
		)
		(pad "M26" smd circle
			(at 8.400034 -2.800096 180)
			(size 0.3556 0.3556)
			(layers "F.Cu" "F.Mask" "F.Paste")
			(net "GND")
		)
		(pad "M27" smd circle
			(at 9.19988 -2.800096 180)
			(size 0.3556 0.3556)
			(layers "F.Cu" "F.Mask" "F.Paste")
			(net "GND")
		)
		(pad "M28" smd circle
			(at 9.99998 -2.800096 180)
			(size 0.3556 0.3556)
			(layers "F.Cu" "F.Mask" "F.Paste")
			(net "GND")
		)
		(pad "M29" smd circle
			(at 10.80008 -2.800096 180)
			(size 0.3556 0.3556)
			(layers "F.Cu" "F.Mask" "F.Paste")
			(net "GND")
		)
		(pad "M30" smd circle
			(at 11.599926 -2.800096 180)
			(size 0.3556 0.3556)
			(layers "F.Cu" "F.Mask" "F.Paste")
			(net "GND")
		)
		(pad "N1" smd circle
			(at -11.599926 -1.999996 180)
			(size 0.3556 0.3556)
			(layers "F.Cu" "F.Mask" "F.Paste")
			(net "GND")
		)
		(pad "N2" smd circle
			(at -10.80008 -1.999996 180)
			(size 0.3556 0.3556)
			(layers "F.Cu" "F.Mask" "F.Paste")
			(net "GND")
		)
		(pad "N3" smd circle
			(at -9.99998 -1.999996 180)
			(size 0.3556 0.3556)
			(layers "F.Cu" "F.Mask" "F.Paste")
			(net "P1V8")
		)
		(pad "N4" smd circle
			(at -9.19988 -1.999996 180)
			(size 0.3556 0.3556)
			(layers "F.Cu" "F.Mask" "F.Paste")
			(net "GND")
		)
		(pad "N5" smd circle
			(at -8.400034 -1.999996 180)
			(size 0.3556 0.3556)
			(layers "F.Cu" "F.Mask" "F.Paste")
			(net "Net_1245")
		)
		(pad "N6" smd circle
			(at -7.599934 -1.999996 180)
			(size 0.3556 0.3556)
			(layers "F.Cu" "F.Mask" "F.Paste")
			(net "Net_1246")
		)
		(pad "N7" smd circle
			(at -6.800088 -1.999996 180)
			(size 0.3556 0.3556)
			(layers "F.Cu" "F.Mask" "F.Paste")
			(net "GND")
		)
		(pad "N8" smd circle
			(at -5.999988 -1.999996 180)
			(size 0.3556 0.3556)
			(layers "F.Cu" "F.Mask" "F.Paste")
			(net "GND")
		)
		(pad "N9" smd circle
			(at -5.199888 -1.999996 180)
			(size 0.3556 0.3556)
			(layers "F.Cu" "F.Mask" "F.Paste")
			(net "GND")
		)
		(pad "N10" smd circle
			(at -4.400042 -1.999996 180)
			(size 0.3556 0.3556)
			(layers "F.Cu" "F.Mask" "F.Paste")
			(net "GND")
		)
		(pad "N11" smd circle
			(at -3.599942 -1.999996 180)
			(size 0.3556 0.3556)
			(layers "F.Cu" "F.Mask" "F.Paste")
			(net "GND")
		)
		(pad "N12" smd circle
			(at -2.800096 -1.999996 180)
			(size 0.3556 0.3556)
			(layers "F.Cu" "F.Mask" "F.Paste")
			(net "P0V975")
		)
		(pad "N13" smd circle
			(at -1.999996 -1.999996 180)
			(size 0.3556 0.3556)
			(layers "F.Cu" "F.Mask" "F.Paste")
			(net "GND")
		)
		(pad "N14" smd circle
			(at -1.199896 -1.999996 180)
			(size 0.3556 0.3556)
			(layers "F.Cu" "F.Mask" "F.Paste")
			(net "P0V975")
		)
		(pad "N15" smd circle
			(at -0.40005 -1.999996 180)
			(size 0.3556 0.3556)
			(layers "F.Cu" "F.Mask" "F.Paste")
			(net "GND")
		)
		(pad "N16" smd circle
			(at 0.40005 -1.999996 180)
			(size 0.3556 0.3556)
			(layers "F.Cu" "F.Mask" "F.Paste")
			(net "P0V975")
		)
		(pad "N17" smd circle
			(at 1.199896 -1.999996 180)
			(size 0.3556 0.3556)
			(layers "F.Cu" "F.Mask" "F.Paste")
			(net "GND")
		)
		(pad "N18" smd circle
			(at 1.999996 -1.999996 180)
			(size 0.3556 0.3556)
			(layers "F.Cu" "F.Mask" "F.Paste")
			(net "P0V975")
		)
		(pad "N19" smd circle
			(at 2.800096 -1.999996 180)
			(size 0.3556 0.3556)
			(layers "F.Cu" "F.Mask" "F.Paste")
			(net "GND")
		)
		(pad "N20" smd circle
			(at 3.599942 -1.999996 180)
			(size 0.3556 0.3556)
			(layers "F.Cu" "F.Mask" "F.Paste")
			(net "P0V975")
		)
		(pad "N21" smd circle
			(at 4.400042 -1.999996 180)
			(size 0.3556 0.3556)
			(layers "F.Cu" "F.Mask" "F.Paste")
			(net "GND")
		)
		(pad "N22" smd circle
			(at 5.199888 -1.999996 180)
			(size 0.3556 0.3556)
			(layers "F.Cu" "F.Mask" "F.Paste")
			(net "GND")
		)
		(pad "N23" smd circle
			(at 5.999988 -1.999996 180)
			(size 0.3556 0.3556)
			(layers "F.Cu" "F.Mask" "F.Paste")
			(net "GND")
		)
		(pad "N24" smd circle
			(at 6.800088 -1.999996 180)
			(size 0.3556 0.3556)
			(layers "F.Cu" "F.Mask" "F.Paste")
			(net "GND")
		)
		(pad "N25" smd circle
			(at 7.599934 -1.999996 180)
			(size 0.3556 0.3556)
			(layers "F.Cu" "F.Mask" "F.Paste")
			(net "GND")
		)
		(pad "N26" smd circle
			(at 8.400034 -1.999996 180)
			(size 0.3556 0.3556)
			(layers "F.Cu" "F.Mask" "F.Paste")
			(net "GND")
		)
		(pad "N27" smd circle
			(at 9.19988 -1.999996 180)
			(size 0.3556 0.3556)
			(layers "F.Cu" "F.Mask" "F.Paste")
			(net "P1V8")
		)
		(pad "N28" smd circle
			(at 9.99998 -1.999996 180)
			(size 0.3556 0.3556)
			(layers "F.Cu" "F.Mask" "F.Paste")
			(net "IOC_GPIO_32")
		)
		(pad "N29" smd circle
			(at 10.80008 -1.999996 180)
			(size 0.3556 0.3556)
			(layers "F.Cu" "F.Mask" "F.Paste")
			(net "MEM_CLK_SEL")
		)
		(pad "N30" smd circle
			(at 11.599926 -1.999996 180)
			(size 0.3556 0.3556)
			(layers "F.Cu" "F.Mask" "F.Paste")
			(net "SBL_SDA")
		)
		(pad "P1" smd circle
			(at -11.599926 -1.199896 180)
			(size 0.3556 0.3556)
			(layers "F.Cu" "F.Mask" "F.Paste")
			(net "IOC_REF_CLK_P")
		)
		(pad "P2" smd circle
			(at -10.80008 -1.199896 180)
			(size 0.3556 0.3556)
			(layers "F.Cu" "F.Mask" "F.Paste")
			(net "IOC_REF_CLK_N")
		)
		(pad "P3" smd circle
			(at -9.99998 -1.199896 180)
			(size 0.3556 0.3556)
			(layers "F.Cu" "F.Mask" "F.Paste")
			(net "GND")
		)
		(pad "P4" smd circle
			(at -9.19988 -1.199896 180)
			(size 0.3556 0.3556)
			(layers "F.Cu" "F.Mask" "F.Paste")
			(net "P1V8")
		)
		(pad "P5" smd circle
			(at -8.400034 -1.199896 180)
			(size 0.3556 0.3556)
			(layers "F.Cu" "F.Mask" "F.Paste")
			(net "Net_1247")
		)
		(pad "P6" smd circle
			(at -7.599934 -1.199896 180)
			(size 0.3556 0.3556)
			(layers "F.Cu" "F.Mask" "F.Paste")
			(net "Net_1248")
		)
		(pad "P7" smd circle
			(at -6.800088 -1.199896 180)
			(size 0.3556 0.3556)
			(layers "F.Cu" "F.Mask" "F.Paste")
			(net "GND")
		)
		(pad "P8" smd circle
			(at -5.999988 -1.199896 180)
			(size 0.3556 0.3556)
			(layers "F.Cu" "F.Mask" "F.Paste")
			(net "GND")
		)
		(pad "P9" smd circle
			(at -5.199888 -1.199896 180)
			(size 0.3556 0.3556)
			(layers "F.Cu" "F.Mask" "F.Paste")
			(net "GND")
		)
		(pad "P10" smd circle
			(at -4.400042 -1.199896 180)
			(size 0.3556 0.3556)
			(layers "F.Cu" "F.Mask" "F.Paste")
			(net "GND")
		)
		(pad "P11" smd circle
			(at -3.599942 -1.199896 180)
			(size 0.3556 0.3556)
			(layers "F.Cu" "F.Mask" "F.Paste")
			(net "GND")
		)
		(pad "P12" smd circle
			(at -2.800096 -1.199896 180)
			(size 0.3556 0.3556)
			(layers "F.Cu" "F.Mask" "F.Paste")
			(net "GND")
		)
		(pad "P13" smd circle
			(at -1.999996 -1.199896 180)
			(size 0.3556 0.3556)
			(layers "F.Cu" "F.Mask" "F.Paste")
			(net "P0V975")
		)
		(pad "P14" smd circle
			(at -1.199896 -1.199896 180)
			(size 0.3556 0.3556)
			(layers "F.Cu" "F.Mask" "F.Paste")
			(net "GND")
		)
		(pad "P15" smd circle
			(at -0.40005 -1.199896 180)
			(size 0.3556 0.3556)
			(layers "F.Cu" "F.Mask" "F.Paste")
			(net "P0V975")
		)
		(pad "P16" smd circle
			(at 0.40005 -1.199896 180)
			(size 0.3556 0.3556)
			(layers "F.Cu" "F.Mask" "F.Paste")
			(net "GND")
		)
		(pad "P17" smd circle
			(at 1.199896 -1.199896 180)
			(size 0.3556 0.3556)
			(layers "F.Cu" "F.Mask" "F.Paste")
			(net "P0V975")
		)
		(pad "P18" smd circle
			(at 1.999996 -1.199896 180)
			(size 0.3556 0.3556)
			(layers "F.Cu" "F.Mask" "F.Paste")
			(net "GND")
		)
		(pad "P19" smd circle
			(at 2.800096 -1.199896 180)
			(size 0.3556 0.3556)
			(layers "F.Cu" "F.Mask" "F.Paste")
			(net "P0V975")
		)
		(pad "P20" smd circle
			(at 3.599942 -1.199896 180)
			(size 0.3556 0.3556)
			(layers "F.Cu" "F.Mask" "F.Paste")
			(net "GND")
		)
		(pad "P21" smd circle
			(at 4.400042 -1.199896 180)
			(size 0.3556 0.3556)
			(layers "F.Cu" "F.Mask" "F.Paste")
			(net "P0V975")
		)
		(pad "P22" smd circle
			(at 5.199888 -1.199896 180)
			(size 0.3556 0.3556)
			(layers "F.Cu" "F.Mask" "F.Paste")
			(net "GND")
		)
		(pad "P23" smd circle
			(at 5.999988 -1.199896 180)
			(size 0.3556 0.3556)
			(layers "F.Cu" "F.Mask" "F.Paste")
			(net "GND")
		)
		(pad "P24" smd circle
			(at 6.800088 -1.199896 180)
			(size 0.3556 0.3556)
			(layers "F.Cu" "F.Mask" "F.Paste")
			(net "GND")
		)
		(pad "P25" smd circle
			(at 7.599934 -1.199896 180)
			(size 0.3556 0.3556)
			(layers "F.Cu" "F.Mask" "F.Paste")
			(net "GND")
		)
		(pad "P26" smd circle
			(at 8.400034 -1.199896 180)
			(size 0.3556 0.3556)
			(layers "F.Cu" "F.Mask" "F.Paste")
			(net "P1V8")
		)
		(pad "P27" smd circle
			(at 9.19988 -1.199896 180)
			(size 0.3556 0.3556)
			(layers "F.Cu" "F.Mask" "F.Paste")
			(net "GND")
		)
		(pad "P28" smd circle
			(at 9.99998 -1.199896 180)
			(size 0.3556 0.3556)
			(layers "F.Cu" "F.Mask" "F.Paste")
			(net "IOC_SCL_3")
		)
		(pad "P29" smd circle
			(at 10.80008 -1.199896 180)
			(size 0.3556 0.3556)
			(layers "F.Cu" "F.Mask" "F.Paste")
			(net "IOC_CLK_SEL0")
		)
		(pad "P30" smd circle
			(at 11.599926 -1.199896 180)
			(size 0.3556 0.3556)
			(layers "F.Cu" "F.Mask" "F.Paste")
			(net "IOC_SCL_1")
		)
		(pad "R1" smd circle
			(at -11.599926 -0.40005 180)
			(size 0.3556 0.3556)
			(layers "F.Cu" "F.Mask" "F.Paste")
			(net "GND")
		)
		(pad "R2" smd circle
			(at -10.80008 -0.40005 180)
			(size 0.3556 0.3556)
			(layers "F.Cu" "F.Mask" "F.Paste")
			(net "GND")
		)
		(pad "R3" smd circle
			(at -9.99998 -0.40005 180)
			(size 0.3556 0.3556)
			(layers "F.Cu" "F.Mask" "F.Paste")
			(net "GND")
		)
		(pad "R4" smd circle
			(at -9.19988 -0.40005 180)
			(size 0.3556 0.3556)
			(layers "F.Cu" "F.Mask" "F.Paste")
			(net "GND")
		)
		(pad "R5" smd circle
			(at -8.400034 -0.40005 180)
			(size 0.3556 0.3556)
			(layers "F.Cu" "F.Mask" "F.Paste")
			(net "IOC_SIO_BLINK")
		)
		(pad "R6" smd circle
			(at -7.599934 -0.40005 180)
			(size 0.3556 0.3556)
			(layers "F.Cu" "F.Mask" "F.Paste")
			(net "POWERLOSS#")
		)
		(pad "R7" smd circle
			(at -6.800088 -0.40005 180)
			(size 0.3556 0.3556)
			(layers "F.Cu" "F.Mask" "F.Paste")
			(net "GND")
		)
		(pad "R8" smd circle
			(at -5.999988 -0.40005 180)
			(size 0.3556 0.3556)
			(layers "F.Cu" "F.Mask" "F.Paste")
			(net "GND")
		)
		(pad "R9" smd circle
			(at -5.199888 -0.40005 180)
			(size 0.3556 0.3556)
			(layers "F.Cu" "F.Mask" "F.Paste")
			(net "GND")
		)
		(pad "R10" smd circle
			(at -4.400042 -0.40005 180)
			(size 0.3556 0.3556)
			(layers "F.Cu" "F.Mask" "F.Paste")
			(net "GND")
		)
		(pad "R11" smd circle
			(at -3.599942 -0.40005 180)
			(size 0.3556 0.3556)
			(layers "F.Cu" "F.Mask" "F.Paste")
			(net "GND")
		)
		(pad "R12" smd circle
			(at -2.800096 -0.40005 180)
			(size 0.3556 0.3556)
			(layers "F.Cu" "F.Mask" "F.Paste")
			(net "P0V975")
		)
		(pad "R13" smd circle
			(at -1.999996 -0.40005 180)
			(size 0.3556 0.3556)
			(layers "F.Cu" "F.Mask" "F.Paste")
			(net "GND")
		)
		(pad "R14" smd circle
			(at -1.199896 -0.40005 180)
			(size 0.3556 0.3556)
			(layers "F.Cu" "F.Mask" "F.Paste")
			(net "P0V975")
		)
		(pad "R15" smd circle
			(at -0.40005 -0.40005 180)
			(size 0.3556 0.3556)
			(layers "F.Cu" "F.Mask" "F.Paste")
			(net "GND")
		)
		(pad "R16" smd circle
			(at 0.40005 -0.40005 180)
			(size 0.3556 0.3556)
			(layers "F.Cu" "F.Mask" "F.Paste")
			(net "P0V975")
		)
		(pad "R17" smd circle
			(at 1.199896 -0.40005 180)
			(size 0.3556 0.3556)
			(layers "F.Cu" "F.Mask" "F.Paste")
			(net "GND")
		)
		(pad "R18" smd circle
			(at 1.999996 -0.40005 180)
			(size 0.3556 0.3556)
			(layers "F.Cu" "F.Mask" "F.Paste")
			(net "P0V975")
		)
		(pad "R19" smd circle
			(at 2.800096 -0.40005 180)
			(size 0.3556 0.3556)
			(layers "F.Cu" "F.Mask" "F.Paste")
			(net "GND")
		)
		(pad "R20" smd circle
			(at 3.599942 -0.40005 180)
			(size 0.3556 0.3556)
			(layers "F.Cu" "F.Mask" "F.Paste")
			(net "P0V975")
		)
		(pad "R21" smd circle
			(at 4.400042 -0.40005 180)
			(size 0.3556 0.3556)
			(layers "F.Cu" "F.Mask" "F.Paste")
			(net "GND")
		)
		(pad "R22" smd circle
			(at 5.199888 -0.40005 180)
			(size 0.3556 0.3556)
			(layers "F.Cu" "F.Mask" "F.Paste")
			(net "GND")
		)
		(pad "R23" smd circle
			(at 5.999988 -0.40005 180)
			(size 0.3556 0.3556)
			(layers "F.Cu" "F.Mask" "F.Paste")
			(net "GND")
		)
		(pad "R24" smd circle
			(at 6.800088 -0.40005 180)
			(size 0.3556 0.3556)
			(layers "F.Cu" "F.Mask" "F.Paste")
			(net "GND")
		)
		(pad "R25" smd circle
			(at 7.599934 -0.40005 180)
			(size 0.3556 0.3556)
			(layers "F.Cu" "F.Mask" "F.Paste")
			(net "GND")
		)
		(pad "R26" smd circle
			(at 8.400034 -0.40005 180)
			(size 0.3556 0.3556)
			(layers "F.Cu" "F.Mask" "F.Paste")
			(net "GND")
		)
		(pad "R27" smd circle
			(at 9.19988 -0.40005 180)
			(size 0.3556 0.3556)
			(layers "F.Cu" "F.Mask" "F.Paste")
			(net "P1V8")
		)
		(pad "R28" smd circle
			(at 9.99998 -0.40005 180)
			(size 0.3556 0.3556)
			(layers "F.Cu" "F.Mask" "F.Paste")
			(net "IOC_SDA_4")
		)
		(pad "R29" smd circle
			(at 10.80008 -0.40005 180)
			(size 0.3556 0.3556)
			(layers "F.Cu" "F.Mask" "F.Paste")
			(net "IOC_SDA_0")
		)
		(pad "R30" smd circle
			(at 11.599926 -0.40005 180)
			(size 0.3556 0.3556)
			(layers "F.Cu" "F.Mask" "F.Paste")
			(net "SYS_CORE_TRI#")
		)
		(pad "T1" smd circle
			(at -11.599926 0.40005 180)
			(size 0.3556 0.3556)
			(layers "F.Cu" "F.Mask" "F.Paste")
			(net "RTRIM")
		)
		(pad "T2" smd circle
			(at -10.80008 0.40005 180)
			(size 0.3556 0.3556)
			(layers "F.Cu" "F.Mask" "F.Paste")
			(net "RTRIM#")
		)
		(pad "T3" smd circle
			(at -9.99998 0.40005 180)
			(size 0.3556 0.3556)
			(layers "F.Cu" "F.Mask" "F.Paste")
			(net "GND")
		)
		(pad "T4" smd circle
			(at -9.19988 0.40005 180)
			(size 0.3556 0.3556)
			(layers "F.Cu" "F.Mask" "F.Paste")
			(net "OSC_REF_CLK")
		)
		(pad "T5" smd circle
			(at -8.400034 0.40005 180)
			(size 0.3556 0.3556)
			(layers "F.Cu" "F.Mask" "F.Paste")
			(net "GND")
		)
		(pad "T6" smd circle
			(at -7.599934 0.40005 180)
			(size 0.3556 0.3556)
			(layers "F.Cu" "F.Mask" "F.Paste")
			(net "SIO_DIN_0")
		)
		(pad "T7" smd circle
			(at -6.800088 0.40005 180)
			(size 0.3556 0.3556)
			(layers "F.Cu" "F.Mask" "F.Paste")
			(net "GND")
		)
		(pad "T8" smd circle
			(at -5.999988 0.40005 180)
			(size 0.3556 0.3556)
			(layers "F.Cu" "F.Mask" "F.Paste")
			(net "GND")
		)
		(pad "T9" smd circle
			(at -5.199888 0.40005 180)
			(size 0.3556 0.3556)
			(layers "F.Cu" "F.Mask" "F.Paste")
			(net "SYS_PLL_VDD")
		)
		(pad "T10" smd circle
			(at -4.400042 0.40005 180)
			(size 0.3556 0.3556)
			(layers "F.Cu" "F.Mask" "F.Paste")
			(net "GND")
		)
		(pad "T11" smd circle
			(at -3.599942 0.40005 180)
			(size 0.3556 0.3556)
			(layers "F.Cu" "F.Mask" "F.Paste")
			(net "GND")
		)
		(pad "T12" smd circle
			(at -2.800096 0.40005 180)
			(size 0.3556 0.3556)
			(layers "F.Cu" "F.Mask" "F.Paste")
			(net "GND")
		)
		(pad "T13" smd circle
			(at -1.999996 0.40005 180)
			(size 0.3556 0.3556)
			(layers "F.Cu" "F.Mask" "F.Paste")
			(net "P0V975")
		)
		(pad "T14" smd circle
			(at -1.199896 0.40005 180)
			(size 0.3556 0.3556)
			(layers "F.Cu" "F.Mask" "F.Paste")
			(net "GND")
		)
		(pad "T15" smd circle
			(at -0.40005 0.40005 180)
			(size 0.3556 0.3556)
			(layers "F.Cu" "F.Mask" "F.Paste")
			(net "P0V975")
		)
		(pad "T16" smd circle
			(at 0.40005 0.40005 180)
			(size 0.3556 0.3556)
			(layers "F.Cu" "F.Mask" "F.Paste")
			(net "GND")
		)
		(pad "T17" smd circle
			(at 1.199896 0.40005 180)
			(size 0.3556 0.3556)
			(layers "F.Cu" "F.Mask" "F.Paste")
			(net "P0V975")
		)
		(pad "T18" smd circle
			(at 1.999996 0.40005 180)
			(size 0.3556 0.3556)
			(layers "F.Cu" "F.Mask" "F.Paste")
			(net "GND")
		)
		(pad "T19" smd circle
			(at 2.800096 0.40005 180)
			(size 0.3556 0.3556)
			(layers "F.Cu" "F.Mask" "F.Paste")
			(net "P0V975")
		)
		(pad "T20" smd circle
			(at 3.599942 0.40005 180)
			(size 0.3556 0.3556)
			(layers "F.Cu" "F.Mask" "F.Paste")
			(net "GND")
		)
		(pad "T21" smd circle
			(at 4.400042 0.40005 180)
			(size 0.3556 0.3556)
			(layers "F.Cu" "F.Mask" "F.Paste")
			(net "P0V975")
		)
		(pad "T22" smd circle
			(at 5.199888 0.40005 180)
			(size 0.3556 0.3556)
			(layers "F.Cu" "F.Mask" "F.Paste")
			(net "GND")
		)
		(pad "T23" smd circle
			(at 5.999988 0.40005 180)
			(size 0.3556 0.3556)
			(layers "F.Cu" "F.Mask" "F.Paste")
			(net "GND")
		)
		(pad "T24" smd circle
			(at 6.800088 0.40005 180)
			(size 0.3556 0.3556)
			(layers "F.Cu" "F.Mask" "F.Paste")
			(net "GND")
		)
		(pad "T25" smd circle
			(at 7.599934 0.40005 180)
			(size 0.3556 0.3556)
			(layers "F.Cu" "F.Mask" "F.Paste")
			(net "GND")
		)
		(pad "T26" smd circle
			(at 8.400034 0.40005 180)
			(size 0.3556 0.3556)
			(layers "F.Cu" "F.Mask" "F.Paste")
			(net "P1V8")
		)
		(pad "T27" smd circle
			(at 9.19988 0.40005 180)
			(size 0.3556 0.3556)
			(layers "F.Cu" "F.Mask" "F.Paste")
			(net "GND")
		)
		(pad "T28" smd circle
			(at 9.99998 0.40005 180)
			(size 0.3556 0.3556)
			(layers "F.Cu" "F.Mask" "F.Paste")
			(net "IOC_CLK_SEL1")
		)
		(pad "T29" smd circle
			(at 10.80008 0.40005 180)
			(size 0.3556 0.3556)
			(layers "F.Cu" "F.Mask" "F.Paste")
			(net "SYS_HB_LED")
		)
		(pad "T30" smd circle
			(at 11.599926 0.40005 180)
			(size 0.3556 0.3556)
			(layers "F.Cu" "F.Mask" "F.Paste")
			(net "SBL_SCL")
		)
		(pad "U1" smd circle
			(at -11.599926 1.199896 180)
			(size 0.3556 0.3556)
			(layers "F.Cu" "F.Mask" "F.Paste")
			(net "SAS0_VDDH")
		)
		(pad "U2" smd circle
			(at -10.80008 1.199896 180)
			(size 0.3556 0.3556)
			(layers "F.Cu" "F.Mask" "F.Paste")
			(net "GND")
		)
		(pad "U3" smd circle
			(at -9.99998 1.199896 180)
			(size 0.3556 0.3556)
			(layers "F.Cu" "F.Mask" "F.Paste")
			(net "GND")
		)
		(pad "U4" smd circle
			(at -9.19988 1.199896 180)
			(size 0.3556 0.3556)
			(layers "F.Cu" "F.Mask" "F.Paste")
			(net "GND")
		)
		(pad "U5" smd circle
			(at -8.400034 1.199896 180)
			(size 0.3556 0.3556)
			(layers "F.Cu" "F.Mask" "F.Paste")
			(net "GND")
		)
		(pad "U6" smd circle
			(at -7.599934 1.199896 180)
			(size 0.3556 0.3556)
			(layers "F.Cu" "F.Mask" "F.Paste")
			(net "GND")
		)
		(pad "U7" smd circle
			(at -6.800088 1.199896 180)
			(size 0.3556 0.3556)
			(layers "F.Cu" "F.Mask" "F.Paste")
			(net "GND")
		)
		(pad "U8" smd circle
			(at -5.999988 1.199896 180)
			(size 0.3556 0.3556)
			(layers "F.Cu" "F.Mask" "F.Paste")
			(net "GND")
		)
		(pad "U9" smd circle
			(at -5.199888 1.199896 180)
			(size 0.3556 0.3556)
			(layers "F.Cu" "F.Mask" "F.Paste")
			(net "GND")
		)
		(pad "U10" smd circle
			(at -4.400042 1.199896 180)
			(size 0.3556 0.3556)
			(layers "F.Cu" "F.Mask" "F.Paste")
			(net "SHELL_PLL_VDD")
		)
		(pad "U11" smd circle
			(at -3.599942 1.199896 180)
			(size 0.3556 0.3556)
			(layers "F.Cu" "F.Mask" "F.Paste")
			(net "GND")
		)
		(pad "U12" smd circle
			(at -2.800096 1.199896 180)
			(size 0.3556 0.3556)
			(layers "F.Cu" "F.Mask" "F.Paste")
			(net "P0V975")
		)
		(pad "U13" smd circle
			(at -1.999996 1.199896 180)
			(size 0.3556 0.3556)
			(layers "F.Cu" "F.Mask" "F.Paste")
			(net "GND")
		)
		(pad "U14" smd circle
			(at -1.199896 1.199896 180)
			(size 0.3556 0.3556)
			(layers "F.Cu" "F.Mask" "F.Paste")
			(net "P0V975")
		)
		(pad "U15" smd circle
			(at -0.40005 1.199896 180)
			(size 0.3556 0.3556)
			(layers "F.Cu" "F.Mask" "F.Paste")
			(net "GND")
		)
		(pad "U16" smd circle
			(at 0.40005 1.199896 180)
			(size 0.3556 0.3556)
			(layers "F.Cu" "F.Mask" "F.Paste")
			(net "P0V975")
		)
		(pad "U17" smd circle
			(at 1.199896 1.199896 180)
			(size 0.3556 0.3556)
			(layers "F.Cu" "F.Mask" "F.Paste")
			(net "GND")
		)
		(pad "U18" smd circle
			(at 1.999996 1.199896 180)
			(size 0.3556 0.3556)
			(layers "F.Cu" "F.Mask" "F.Paste")
			(net "P0V975")
		)
		(pad "U19" smd circle
			(at 2.800096 1.199896 180)
			(size 0.3556 0.3556)
			(layers "F.Cu" "F.Mask" "F.Paste")
			(net "GND")
		)
		(pad "U20" smd circle
			(at 3.599942 1.199896 180)
			(size 0.3556 0.3556)
			(layers "F.Cu" "F.Mask" "F.Paste")
			(net "P0V975")
		)
		(pad "U21" smd circle
			(at 4.400042 1.199896 180)
			(size 0.3556 0.3556)
			(layers "F.Cu" "F.Mask" "F.Paste")
			(net "GND")
		)
		(pad "U22" smd circle
			(at 5.199888 1.199896 180)
			(size 0.3556 0.3556)
			(layers "F.Cu" "F.Mask" "F.Paste")
			(net "GND")
		)
		(pad "U23" smd circle
			(at 5.999988 1.199896 180)
			(size 0.3556 0.3556)
			(layers "F.Cu" "F.Mask" "F.Paste")
			(net "GND")
		)
		(pad "U24" smd circle
			(at 6.800088 1.199896 180)
			(size 0.3556 0.3556)
			(layers "F.Cu" "F.Mask" "F.Paste")
			(net "GND")
		)
		(pad "U25" smd circle
			(at 7.599934 1.199896 180)
			(size 0.3556 0.3556)
			(layers "F.Cu" "F.Mask" "F.Paste")
			(net "GND")
		)
		(pad "U26" smd circle
			(at 8.400034 1.199896 180)
			(size 0.3556 0.3556)
			(layers "F.Cu" "F.Mask" "F.Paste")
			(net "GND")
		)
		(pad "U27" smd circle
			(at 9.19988 1.199896 180)
			(size 0.3556 0.3556)
			(layers "F.Cu" "F.Mask" "F.Paste")
			(net "P1V8")
		)
		(pad "U28" smd circle
			(at 9.99998 1.199896 180)
			(size 0.3556 0.3556)
			(layers "F.Cu" "F.Mask" "F.Paste")
			(net "IOC_RESET#")
		)
		(pad "U29" smd circle
			(at 10.80008 1.199896 180)
			(size 0.3556 0.3556)
			(layers "F.Cu" "F.Mask" "F.Paste")
			(net "IOC_SDA_3")
		)
		(pad "U30" smd circle
			(at 11.599926 1.199896 180)
			(size 0.3556 0.3556)
			(layers "F.Cu" "F.Mask" "F.Paste")
			(net "CP_DONE")
		)
		(pad "V1" smd circle
			(at -11.599926 1.999996 180)
			(size 0.3556 0.3556)
			(layers "F.Cu" "F.Mask" "F.Paste")
			(net "PHY_IOC_TO_CON_B_3_DP_C")
		)
		(pad "V2" smd circle
			(at -10.80008 1.999996 180)
			(size 0.3556 0.3556)
			(layers "F.Cu" "F.Mask" "F.Paste")
			(net "PHY_IOC_TO_CON_B_3_DN_C")
		)
		(pad "V3" smd circle
			(at -9.99998 1.999996 180)
			(size 0.3556 0.3556)
			(layers "F.Cu" "F.Mask" "F.Paste")
			(net "GND")
		)
		(pad "V4" smd circle
			(at -9.19988 1.999996 180)
			(size 0.3556 0.3556)
			(layers "F.Cu" "F.Mask" "F.Paste")
			(net "PHY_CON_B_TO_IOC_3_DP")
		)
		(pad "V5" smd circle
			(at -8.400034 1.999996 180)
			(size 0.3556 0.3556)
			(layers "F.Cu" "F.Mask" "F.Paste")
			(net "PHY_CON_B_TO_IOC_3_DN")
		)
		(pad "V6" smd circle
			(at -7.599934 1.999996 180)
			(size 0.3556 0.3556)
			(layers "F.Cu" "F.Mask" "F.Paste")
			(net "GND")
		)
		(pad "V7" smd circle
			(at -6.800088 1.999996 180)
			(size 0.3556 0.3556)
			(layers "F.Cu" "F.Mask" "F.Paste")
			(net "SAS0_AVDD")
		)
		(pad "V8" smd circle
			(at -5.999988 1.999996 180)
			(size 0.3556 0.3556)
			(layers "F.Cu" "F.Mask" "F.Paste")
			(net "GND")
		)
		(pad "V9" smd circle
			(at -5.199888 1.999996 180)
			(size 0.3556 0.3556)
			(layers "F.Cu" "F.Mask" "F.Paste")
			(net "SAS0_AVDD")
		)
		(pad "V10" smd circle
			(at -4.400042 1.999996 180)
			(size 0.3556 0.3556)
			(layers "F.Cu" "F.Mask" "F.Paste")
			(net "GND")
		)
		(pad "V11" smd circle
			(at -3.599942 1.999996 180)
			(size 0.3556 0.3556)
			(layers "F.Cu" "F.Mask" "F.Paste")
			(net "VDDA_SAS_REF_CLK")
		)
		(pad "V12" smd circle
			(at -2.800096 1.999996 180)
			(size 0.3556 0.3556)
			(layers "F.Cu" "F.Mask" "F.Paste")
			(net "GND")
		)
		(pad "V13" smd circle
			(at -1.999996 1.999996 180)
			(size 0.3556 0.3556)
			(layers "F.Cu" "F.Mask" "F.Paste")
			(net "P0V975")
		)
		(pad "V14" smd circle
			(at -1.199896 1.999996 180)
			(size 0.3556 0.3556)
			(layers "F.Cu" "F.Mask" "F.Paste")
			(net "GND")
		)
		(pad "V15" smd circle
			(at -0.40005 1.999996 180)
			(size 0.3556 0.3556)
			(layers "F.Cu" "F.Mask" "F.Paste")
			(net "P0V975")
		)
		(pad "V16" smd circle
			(at 0.40005 1.999996 180)
			(size 0.3556 0.3556)
			(layers "F.Cu" "F.Mask" "F.Paste")
			(net "GND")
		)
		(pad "V17" smd circle
			(at 1.199896 1.999996 180)
			(size 0.3556 0.3556)
			(layers "F.Cu" "F.Mask" "F.Paste")
			(net "P0V975")
		)
		(pad "V18" smd circle
			(at 1.999996 1.999996 180)
			(size 0.3556 0.3556)
			(layers "F.Cu" "F.Mask" "F.Paste")
			(net "GND")
		)
		(pad "V19" smd circle
			(at 2.800096 1.999996 180)
			(size 0.3556 0.3556)
			(layers "F.Cu" "F.Mask" "F.Paste")
			(net "P0V975")
		)
		(pad "V20" smd circle
			(at 3.599942 1.999996 180)
			(size 0.3556 0.3556)
			(layers "F.Cu" "F.Mask" "F.Paste")
			(net "GND")
		)
		(pad "V21" smd circle
			(at 4.400042 1.999996 180)
			(size 0.3556 0.3556)
			(layers "F.Cu" "F.Mask" "F.Paste")
			(net "P0V975")
		)
		(pad "V22" smd circle
			(at 5.199888 1.999996 180)
			(size 0.3556 0.3556)
			(layers "F.Cu" "F.Mask" "F.Paste")
			(net "GND")
		)
		(pad "V23" smd circle
			(at 5.999988 1.999996 180)
			(size 0.3556 0.3556)
			(layers "F.Cu" "F.Mask" "F.Paste")
			(net "GND")
		)
		(pad "V24" smd circle
			(at 6.800088 1.999996 180)
			(size 0.3556 0.3556)
			(layers "F.Cu" "F.Mask" "F.Paste")
			(net "GND")
		)
		(pad "V25" smd circle
			(at 7.599934 1.999996 180)
			(size 0.3556 0.3556)
			(layers "F.Cu" "F.Mask" "F.Paste")
			(net "GND")
		)
		(pad "V26" smd circle
			(at 8.400034 1.999996 180)
			(size 0.3556 0.3556)
			(layers "F.Cu" "F.Mask" "F.Paste")
			(net "P1V8")
		)
		(pad "V27" smd circle
			(at 9.19988 1.999996 180)
			(size 0.3556 0.3556)
			(layers "F.Cu" "F.Mask" "F.Paste")
			(net "GND")
		)
		(pad "V28" smd circle
			(at 9.99998 1.999996 180)
			(size 0.3556 0.3556)
			(layers "F.Cu" "F.Mask" "F.Paste")
			(net "IOC_SCL_2")
		)
		(pad "V29" smd circle
			(at 10.80008 1.999996 180)
			(size 0.3556 0.3556)
			(layers "F.Cu" "F.Mask" "F.Paste")
			(net "IOC_SCL_0")
		)
		(pad "V30" smd circle
			(at 11.599926 1.999996 180)
			(size 0.3556 0.3556)
			(layers "F.Cu" "F.Mask" "F.Paste")
			(net "IOC_SDA_1")
		)
		(pad "W1" smd circle
			(at -11.599926 2.800096 180)
			(size 0.3556 0.3556)
			(layers "F.Cu" "F.Mask" "F.Paste")
			(net "PHY_IOC_TO_CON_B_2_DP_C")
		)
		(pad "W2" smd circle
			(at -10.80008 2.800096 180)
			(size 0.3556 0.3556)
			(layers "F.Cu" "F.Mask" "F.Paste")
			(net "PHY_IOC_TO_CON_B_2_DN_C")
		)
		(pad "W3" smd circle
			(at -9.99998 2.800096 180)
			(size 0.3556 0.3556)
			(layers "F.Cu" "F.Mask" "F.Paste")
			(net "GND")
		)
		(pad "W4" smd circle
			(at -9.19988 2.800096 180)
			(size 0.3556 0.3556)
			(layers "F.Cu" "F.Mask" "F.Paste")
			(net "PHY_CON_B_TO_IOC_2_DP")
		)
		(pad "W5" smd circle
			(at -8.400034 2.800096 180)
			(size 0.3556 0.3556)
			(layers "F.Cu" "F.Mask" "F.Paste")
			(net "PHY_CON_B_TO_IOC_2_DN")
		)
		(pad "W6" smd circle
			(at -7.599934 2.800096 180)
			(size 0.3556 0.3556)
			(layers "F.Cu" "F.Mask" "F.Paste")
			(net "GND")
		)
		(pad "W7" smd circle
			(at -6.800088 2.800096 180)
			(size 0.3556 0.3556)
			(layers "F.Cu" "F.Mask" "F.Paste")
			(net "GND")
		)
		(pad "W8" smd circle
			(at -5.999988 2.800096 180)
			(size 0.3556 0.3556)
			(layers "F.Cu" "F.Mask" "F.Paste")
			(net "GND")
		)
		(pad "W9" smd circle
			(at -5.199888 2.800096 180)
			(size 0.3556 0.3556)
			(layers "F.Cu" "F.Mask" "F.Paste")
			(net "GND")
		)
		(pad "W10" smd circle
			(at -4.400042 2.800096 180)
			(size 0.3556 0.3556)
			(layers "F.Cu" "F.Mask" "F.Paste")
			(net "GND")
		)
		(pad "W11" smd circle
			(at -3.599942 2.800096 180)
			(size 0.3556 0.3556)
			(layers "F.Cu" "F.Mask" "F.Paste")
			(net "GND")
		)
		(pad "W12" smd circle
			(at -2.800096 2.800096 180)
			(size 0.3556 0.3556)
			(layers "F.Cu" "F.Mask" "F.Paste")
			(net "GND")
		)
		(pad "W13" smd circle
			(at -1.999996 2.800096 180)
			(size 0.3556 0.3556)
			(layers "F.Cu" "F.Mask" "F.Paste")
			(net "GND")
		)
		(pad "W14" smd circle
			(at -1.199896 2.800096 180)
			(size 0.3556 0.3556)
			(layers "F.Cu" "F.Mask" "F.Paste")
			(net "P0V975")
		)
		(pad "W15" smd circle
			(at -0.40005 2.800096 180)
			(size 0.3556 0.3556)
			(layers "F.Cu" "F.Mask" "F.Paste")
			(net "GND")
		)
		(pad "W16" smd circle
			(at 0.40005 2.800096 180)
			(size 0.3556 0.3556)
			(layers "F.Cu" "F.Mask" "F.Paste")
			(net "P0V975")
		)
		(pad "W17" smd circle
			(at 1.199896 2.800096 180)
			(size 0.3556 0.3556)
			(layers "F.Cu" "F.Mask" "F.Paste")
			(net "GND")
		)
		(pad "W18" smd circle
			(at 1.999996 2.800096 180)
			(size 0.3556 0.3556)
			(layers "F.Cu" "F.Mask" "F.Paste")
			(net "P0V975")
		)
		(pad "W19" smd circle
			(at 2.800096 2.800096 180)
			(size 0.3556 0.3556)
			(layers "F.Cu" "F.Mask" "F.Paste")
			(net "GND")
		)
		(pad "W20" smd circle
			(at 3.599942 2.800096 180)
			(size 0.3556 0.3556)
			(layers "F.Cu" "F.Mask" "F.Paste")
			(net "P0V975")
		)
		(pad "W21" smd circle
			(at 4.400042 2.800096 180)
			(size 0.3556 0.3556)
			(layers "F.Cu" "F.Mask" "F.Paste")
			(net "GND")
		)
		(pad "W22" smd circle
			(at 5.199888 2.800096 180)
			(size 0.3556 0.3556)
			(layers "F.Cu" "F.Mask" "F.Paste")
			(net "GND")
		)
		(pad "W23" smd circle
			(at 5.999988 2.800096 180)
			(size 0.3556 0.3556)
			(layers "F.Cu" "F.Mask" "F.Paste")
			(net "GND")
		)
		(pad "W24" smd circle
			(at 6.800088 2.800096 180)
			(size 0.3556 0.3556)
			(layers "F.Cu" "F.Mask" "F.Paste")
			(net "GND")
		)
		(pad "W25" smd circle
			(at 7.599934 2.800096 180)
			(size 0.3556 0.3556)
			(layers "F.Cu" "F.Mask" "F.Paste")
			(net "GND")
		)
		(pad "W26" smd circle
			(at 8.400034 2.800096 180)
			(size 0.3556 0.3556)
			(layers "F.Cu" "F.Mask" "F.Paste")
			(net "GND")
		)
		(pad "W27" smd circle
			(at 9.19988 2.800096 180)
			(size 0.3556 0.3556)
			(layers "F.Cu" "F.Mask" "F.Paste")
			(net "P1V8")
		)
		(pad "W28" smd circle
			(at 9.99998 2.800096 180)
			(size 0.3556 0.3556)
			(layers "F.Cu" "F.Mask" "F.Paste")
			(net "IOC_EXT2_LED_B")
		)
		(pad "W29" smd circle
			(at 10.80008 2.800096 180)
			(size 0.3556 0.3556)
			(layers "F.Cu" "F.Mask" "F.Paste")
			(net "IOC_SCL_4")
		)
		(pad "W30" smd circle
			(at 11.599926 2.800096 180)
			(size 0.3556 0.3556)
			(layers "F.Cu" "F.Mask" "F.Paste")
			(net "IOC_GPIO_24")
		)
		(pad "Y1" smd circle
			(at -11.599926 3.599942 180)
			(size 0.3556 0.3556)
			(layers "F.Cu" "F.Mask" "F.Paste")
			(net "SAS0_VDDH")
		)
		(pad "Y2" smd circle
			(at -10.80008 3.599942 180)
			(size 0.3556 0.3556)
			(layers "F.Cu" "F.Mask" "F.Paste")
			(net "GND")
		)
		(pad "Y3" smd circle
			(at -9.99998 3.599942 180)
			(size 0.3556 0.3556)
			(layers "F.Cu" "F.Mask" "F.Paste")
			(net "GND")
		)
		(pad "Y4" smd circle
			(at -9.19988 3.599942 180)
			(size 0.3556 0.3556)
			(layers "F.Cu" "F.Mask" "F.Paste")
			(net "SAS0_AVDD")
		)
		(pad "Y5" smd circle
			(at -8.400034 3.599942 180)
			(size 0.3556 0.3556)
			(layers "F.Cu" "F.Mask" "F.Paste")
			(net "GND")
		)
		(pad "Y6" smd circle
			(at -7.599934 3.599942 180)
			(size 0.3556 0.3556)
			(layers "F.Cu" "F.Mask" "F.Paste")
			(net "SAS0_VDDH")
		)
		(pad "Y7" smd circle
			(at -6.800088 3.599942 180)
			(size 0.3556 0.3556)
			(layers "F.Cu" "F.Mask" "F.Paste")
			(net "SAS0_AVDD")
		)
		(pad "Y8" smd circle
			(at -5.999988 3.599942 180)
			(size 0.3556 0.3556)
			(layers "F.Cu" "F.Mask" "F.Paste")
			(net "GND")
		)
		(pad "Y9" smd circle
			(at -5.199888 3.599942 180)
			(size 0.3556 0.3556)
			(layers "F.Cu" "F.Mask" "F.Paste")
			(net "GND")
		)
		(pad "Y10" smd circle
			(at -4.400042 3.599942 180)
			(size 0.3556 0.3556)
			(layers "F.Cu" "F.Mask" "F.Paste")
			(net "GND")
		)
		(pad "Y11" smd circle
			(at -3.599942 3.599942 180)
			(size 0.3556 0.3556)
			(layers "F.Cu" "F.Mask" "F.Paste")
			(net "GND")
		)
		(pad "Y12" smd circle
			(at -2.800096 3.599942 180)
			(size 0.3556 0.3556)
			(layers "F.Cu" "F.Mask" "F.Paste")
			(net "GND")
		)
		(pad "Y13" smd circle
			(at -1.999996 3.599942 180)
			(size 0.3556 0.3556)
			(layers "F.Cu" "F.Mask" "F.Paste")
			(net "GND")
		)
		(pad "Y14" smd circle
			(at -1.199896 3.599942 180)
			(size 0.3556 0.3556)
			(layers "F.Cu" "F.Mask" "F.Paste")
			(net "GND")
		)
		(pad "Y15" smd circle
			(at -0.40005 3.599942 180)
			(size 0.3556 0.3556)
			(layers "F.Cu" "F.Mask" "F.Paste")
			(net "GND")
		)
		(pad "Y16" smd circle
			(at 0.40005 3.599942 180)
			(size 0.3556 0.3556)
			(layers "F.Cu" "F.Mask" "F.Paste")
			(net "GND")
		)
		(pad "Y17" smd circle
			(at 1.199896 3.599942 180)
			(size 0.3556 0.3556)
			(layers "F.Cu" "F.Mask" "F.Paste")
			(net "P0V975")
		)
		(pad "Y18" smd circle
			(at 1.999996 3.599942 180)
			(size 0.3556 0.3556)
			(layers "F.Cu" "F.Mask" "F.Paste")
			(net "GND")
		)
		(pad "Y19" smd circle
			(at 2.800096 3.599942 180)
			(size 0.3556 0.3556)
			(layers "F.Cu" "F.Mask" "F.Paste")
			(net "P0V975")
		)
		(pad "Y20" smd circle
			(at 3.599942 3.599942 180)
			(size 0.3556 0.3556)
			(layers "F.Cu" "F.Mask" "F.Paste")
			(net "GND")
		)
		(pad "Y21" smd circle
			(at 4.400042 3.599942 180)
			(size 0.3556 0.3556)
			(layers "F.Cu" "F.Mask" "F.Paste")
			(net "P0V975")
		)
		(pad "Y22" smd circle
			(at 5.199888 3.599942 180)
			(size 0.3556 0.3556)
			(layers "F.Cu" "F.Mask" "F.Paste")
			(net "GND")
		)
		(pad "Y23" smd circle
			(at 5.999988 3.599942 180)
			(size 0.3556 0.3556)
			(layers "F.Cu" "F.Mask" "F.Paste")
			(net "GND")
		)
		(pad "Y24" smd circle
			(at 6.800088 3.599942 180)
			(size 0.3556 0.3556)
			(layers "F.Cu" "F.Mask" "F.Paste")
			(net "GND")
		)
		(pad "Y25" smd circle
			(at 7.599934 3.599942 180)
			(size 0.3556 0.3556)
			(layers "F.Cu" "F.Mask" "F.Paste")
			(net "GND")
		)
		(pad "Y26" smd circle
			(at 8.400034 3.599942 180)
			(size 0.3556 0.3556)
			(layers "F.Cu" "F.Mask" "F.Paste")
			(net "P1V8")
		)
		(pad "Y27" smd circle
			(at 9.19988 3.599942 180)
			(size 0.3556 0.3556)
			(layers "F.Cu" "F.Mask" "F.Paste")
			(net "GND")
		)
		(pad "Y28" smd circle
			(at 9.99998 3.599942 180)
			(size 0.3556 0.3556)
			(layers "F.Cu" "F.Mask" "F.Paste")
			(net "IOC_SDA_2")
		)
		(pad "Y29" smd circle
			(at 10.80008 3.599942 180)
			(size 0.3556 0.3556)
			(layers "F.Cu" "F.Mask" "F.Paste")
			(net "SPARE4")
		)
		(pad "Y30" smd circle
			(at 11.599926 3.599942 180)
			(size 0.3556 0.3556)
			(layers "F.Cu" "F.Mask" "F.Paste")
			(net "IOC_GPIO_15")
		)
	)
	(footprint ""
		(layer "F.Cu")
		(at 19.3294 -175.768)
		(property "Reference" "R533"
			(at 0 0 0)
			(layer "F.SilkS")
			(hide yes)
			(effects
				(font
					(size 1.27 1.27)
				)
			)
		)
		(property "Value" "0R2J-2-GP"
			(at 0.064008 -3.993896 0)
			(unlocked yes)
			(layer "F.Fab")
			(hide yes)
			(effects
				(font
					(size 1.016 1.016)
					(thickness 0.1524)
				)
			)
		)
		(property "Device Type" "R402H16"
			(at 0.064008 -5.517896 0)
			(unlocked yes)
			(layer "F.Fab")
			(hide yes)
			(effects
				(font
					(size 1.016 1.016)
					(thickness 0.1524)
				)
			)
		)
		(duplicate_pad_numbers_are_jumpers no)
		(fp_line
			(start -0.508 -0.9398)
			(end -0.508 0.9398)
			(stroke
				(width 0.1524)
				(type default)
			)
			(layer "F.SilkS")
		)
		(fp_line
			(start 0.508 -0.9398)
			(end -0.508 -0.9398)
			(stroke
				(width 0.1524)
				(type default)
			)
			(layer "F.SilkS")
		)
		(fp_rect
			(start -0.508 0.9398)
			(end 0.508 -0.9398)
			(stroke
				(width 0)
				(type default)
			)
			(fill no)
			(layer "F.CrtYd")
		)
		(fp_rect
			(start -0.508 0.9398)
			(end 0.508 -0.9398)
			(stroke
				(width 0)
				(type default)
			)
			(fill no)
			(layer "F.Fab")
		)
		(pad "1" smd custom
			(at 0 -0.4445)
			(size 0.1397 0.1397)
			(layers "F.Cu" "F.Mask" "F.Paste")
			(net "P5V_STBY")
			(options
				(clearance outline)
				(anchor circle)
			)
			(primitives
				(gr_poly
					(pts
						(arc
							(start -0.1778 -0.2794)
							(mid -0.249642 -0.249642)
							(end -0.2794 -0.1778)
						)
						(arc
							(start -0.2794 0.1778)
							(mid -0.249642 0.249642)
							(end -0.1778 0.2794)
						)
						(arc
							(start 0.1778 0.2794)
							(mid 0.249642 0.249642)
							(end 0.2794 0.1778)
						)
						(arc
							(start 0.2794 -0.1778)
							(mid 0.249642 -0.249642)
							(end 0.1778 -0.2794)
						)
					)
					(width 0)
					(fill yes)
				)
			)
		)
		(pad "2" smd custom
			(at 0 0.4445)
			(size 0.1397 0.1397)
			(layers "F.Cu" "F.Mask" "F.Paste")
			(net "TPS74801_P1V2_STBY_BIAS")
			(options
				(clearance outline)
				(anchor circle)
			)
			(primitives
				(gr_poly
					(pts
						(arc
							(start -0.1778 -0.2794)
							(mid -0.249642 -0.249642)
							(end -0.2794 -0.1778)
						)
						(arc
							(start -0.2794 0.1778)
							(mid -0.249642 0.249642)
							(end -0.1778 0.2794)
						)
						(arc
							(start 0.1778 0.2794)
							(mid 0.249642 0.249642)
							(end 0.2794 0.1778)
						)
						(arc
							(start 0.2794 -0.1778)
							(mid 0.249642 -0.249642)
							(end 0.1778 -0.2794)
						)
					)
					(width 0)
					(fill yes)
				)
			)
		)
	)
	(footprint ""
		(layer "F.Cu")
		(at 180.7718 -88.138 180)
		(property "Reference" "R654"
			(at 0 0 180)
			(layer "F.SilkS")
			(hide yes)
			(effects
				(font
					(size 1.27 1.27)
				)
			)
		)
		(property "Value" "10KR2F-2-GP"
			(at 0.064008 -3.993896 180)
			(unlocked yes)
			(layer "F.Fab")
			(hide yes)
			(effects
				(font
					(size 1.016 1.016)
					(thickness 0.1524)
				)
			)
		)
		(property "Device Type" "R402H16"
			(at 0.064008 -5.517896 180)
			(unlocked yes)
			(layer "F.Fab")
			(hide yes)
			(effects
				(font
					(size 1.016 1.016)
					(thickness 0.1524)
				)
			)
		)
		(duplicate_pad_numbers_are_jumpers no)
		(fp_line
			(start 0.508 -0.9398)
			(end -0.508 -0.9398)
			(stroke
				(width 0.1524)
				(type default)
			)
			(layer "F.SilkS")
		)
		(fp_line
			(start -0.508 -0.9398)
			(end -0.508 0.9398)
			(stroke
				(width 0.1524)
				(type default)
			)
			(layer "F.SilkS")
		)
		(fp_rect
			(start -0.508 0.9398)
			(end 0.508 -0.9398)
			(stroke
				(width 0)
				(type default)
			)
			(fill no)
			(layer "F.CrtYd")
		)
		(fp_rect
			(start -0.508 0.9398)
			(end 0.508 -0.9398)
			(stroke
				(width 0)
				(type default)
			)
			(fill no)
			(layer "F.Fab")
		)
		(pad "1" smd custom
			(at 0 -0.4445 180)
			(size 0.1397 0.1397)
			(layers "F.Cu" "F.Mask" "F.Paste")
			(net "SYS_DBMODE2")
			(options
				(clearance outline)
				(anchor circle)
			)
			(primitives
				(gr_poly
					(pts
						(arc
							(start -0.1778 -0.2794)
							(mid -0.249642 -0.249642)
							(end -0.2794 -0.1778)
						)
						(arc
							(start -0.2794 0.1778)
							(mid -0.249642 0.249642)
							(end -0.1778 0.2794)
						)
						(arc
							(start 0.1778 0.2794)
							(mid 0.249642 0.249642)
							(end 0.2794 0.1778)
						)
						(arc
							(start 0.2794 -0.1778)
							(mid 0.249642 -0.249642)
							(end 0.1778 -0.2794)
						)
					)
					(width 0)
					(fill yes)
				)
			)
		)
		(pad "2" smd custom
			(at 0 0.4445 180)
			(size 0.1397 0.1397)
			(layers "F.Cu" "F.Mask" "F.Paste")
			(net "GND")
			(options
				(clearance outline)
				(anchor circle)
			)
			(primitives
				(gr_poly
					(pts
						(arc
							(start -0.1778 -0.2794)
							(mid -0.249642 -0.249642)
							(end -0.2794 -0.1778)
						)
						(arc
							(start -0.2794 0.1778)
							(mid -0.249642 0.249642)
							(end -0.1778 0.2794)
						)
						(arc
							(start 0.1778 0.2794)
							(mid 0.249642 0.249642)
							(end 0.2794 0.1778)
						)
						(arc
							(start 0.2794 -0.1778)
							(mid 0.249642 -0.249642)
							(end 0.1778 -0.2794)
						)
					)
					(width 0)
					(fill yes)
				)
			)
		)
	)
	(footprint ""
		(layer "F.Cu")
		(at 98.3996 -170.6372 -90)
		(property "Reference" "R724"
			(at 0 0 270)
			(layer "F.SilkS")
			(hide yes)
			(effects
				(font
					(size 1.27 1.27)
				)
			)
		)
		(property "Value" "0R2J-2-GP"
			(at 0.064008 -3.993896 270)
			(unlocked yes)
			(layer "F.Fab")
			(hide yes)
			(effects
				(font
					(size 1.016 1.016)
					(thickness 0.1524)
				)
			)
		)
		(property "Device Type" "R402H16"
			(at 0.064008 -5.517896 270)
			(unlocked yes)
			(layer "F.Fab")
			(hide yes)
			(effects
				(font
					(size 1.016 1.016)
					(thickness 0.1524)
				)
			)
		)
		(duplicate_pad_numbers_are_jumpers no)
		(fp_line
			(start -0.508 -0.9398)
			(end -0.508 0.9398)
			(stroke
				(width 0.1524)
				(type default)
			)
			(layer "F.SilkS")
		)
		(fp_line
			(start 0.508 -0.9398)
			(end -0.508 -0.9398)
			(stroke
				(width 0.1524)
				(type default)
			)
			(layer "F.SilkS")
		)
		(fp_rect
			(start -0.508 0.9398)
			(end 0.508 -0.9398)
			(stroke
				(width 0)
				(type default)
			)
			(fill no)
			(layer "F.CrtYd")
		)
		(fp_rect
			(start -0.508 0.9398)
			(end 0.508 -0.9398)
			(stroke
				(width 0)
				(type default)
			)
			(fill no)
			(layer "F.Fab")
		)
		(pad "1" smd custom
			(at 0 -0.4445 270)
			(size 0.1397 0.1397)
			(layers "F.Cu" "F.Mask" "F.Paste")
			(net "DPB_MISC_ALERT_OUT")
			(options
				(clearance outline)
				(anchor circle)
			)
			(primitives
				(gr_poly
					(pts
						(arc
							(start -0.1778 -0.2794)
							(mid -0.249642 -0.249642)
							(end -0.2794 -0.1778)
						)
						(arc
							(start -0.2794 0.1778)
							(mid -0.249642 0.249642)
							(end -0.1778 0.2794)
						)
						(arc
							(start 0.1778 0.2794)
							(mid 0.249642 0.249642)
							(end 0.2794 0.1778)
						)
						(arc
							(start 0.2794 -0.1778)
							(mid 0.249642 -0.249642)
							(end 0.1778 -0.2794)
						)
					)
					(width 0)
					(fill yes)
				)
			)
		)
		(pad "2" smd custom
			(at 0 0.4445 270)
			(size 0.1397 0.1397)
			(layers "F.Cu" "F.Mask" "F.Paste")
			(net "DPB_MISC_ALERT_OUT_R")
			(options
				(clearance outline)
				(anchor circle)
			)
			(primitives
				(gr_poly
					(pts
						(arc
							(start -0.1778 -0.2794)
							(mid -0.249642 -0.249642)
							(end -0.2794 -0.1778)
						)
						(arc
							(start -0.2794 0.1778)
							(mid -0.249642 0.249642)
							(end -0.1778 0.2794)
						)
						(arc
							(start 0.1778 0.2794)
							(mid 0.249642 0.249642)
							(end 0.2794 0.1778)
						)
						(arc
							(start 0.2794 -0.1778)
							(mid 0.249642 -0.249642)
							(end 0.1778 -0.2794)
						)
					)
					(width 0)
					(fill yes)
				)
			)
		)
	)
	(footprint ""
		(layer "F.Cu")
		(at 155.499816 -109.99978)
		(property "Reference" ""
			(at 0 0 0)
			(layer "F.SilkS")
			(hide yes)
			(effects
				(font
					(size 1.27 1.27)
				)
			)
		)
		(property "Value" "*"
			(at -6.38175 0.19685 0)
			(unlocked yes)
			(layer "F.Fab")
			(hide yes)
			(effects
				(font
					(size 1.016 1.016)
					(thickness 0.1524)
				)
			)
		)
		(duplicate_pad_numbers_are_jumpers no)
		(fp_poly
			(pts
				(arc
					(start 5.0673 0)
					(mid -5.0673 0)
					(end 5.0673 0)
				)
			)
			(stroke
				(width 0)
				(type default)
			)
			(fill no)
			(layer "B.CrtYd")
		)
		(fp_poly
			(pts
				(arc
					(start 5.0673 0)
					(mid -5.0673 0)
					(end 5.0673 0)
				)
			)
			(stroke
				(width 0)
				(type default)
			)
			(fill no)
			(layer "F.CrtYd")
		)
		(fp_poly
			(pts
				(arc
					(start 5.0673 0)
					(mid -5.0673 0)
					(end 5.0673 0)
				)
			)
			(stroke
				(width 0)
				(type default)
			)
			(fill no)
			(layer "B.Fab")
		)
		(fp_poly
			(pts
				(arc
					(start 5.0673 0)
					(mid -5.0673 0)
					(end 5.0673 0)
				)
			)
			(stroke
				(width 0)
				(type default)
			)
			(fill no)
			(layer "F.Fab")
		)
		(pad "1" thru_hole circle
			(at 0 0)
			(size 9.525 9.525)
			(drill 3.5052)
			(layers "*.Cu" "*.Mask")
			(remove_unused_layers no)
			(net "Net_11")
			(clearance -2.5019)
			(thermal_gap 0.3048)
			(padstack
				(mode front_inner_back)
				(layer "Inner"
					(shape circle)
					(size 3.9116 3.9116)
					(clearance 0.3048)
				)
				(layer "B.Cu"
					(shape circle)
					(size 9.525 9.525)
					(clearance -2.5019)
				)
			)
		)
	)
	(footprint ""
		(layer "F.Cu")
		(at 83.479386 -136.616186)
		(property "Reference" "C40"
			(at 0 0 0)
			(layer "F.SilkS")
			(hide yes)
			(effects
				(font
					(size 1.27 1.27)
				)
			)
		)
		(property "Value" "SCD1U16V2KX-3GP"
			(at 1.1811 -2.7051 0)
			(unlocked yes)
			(layer "F.Fab")
			(hide yes)
			(effects
				(font
					(size 1.016 1.016)
					(thickness 0.1524)
				)
			)
		)
		(property "Device Type" "C402H22"
			(at 1.1811 -4.2291 0)
			(unlocked yes)
			(layer "F.Fab")
			(hide yes)
			(effects
				(font
					(size 1.016 1.016)
					(thickness 0.1524)
				)
			)
		)
		(duplicate_pad_numbers_are_jumpers no)
		(fp_rect
			(start -0.4318 0.9525)
			(end 0.4318 -0.9525)
			(stroke
				(width 0)
				(type default)
			)
			(fill no)
			(layer "F.CrtYd")
		)
		(fp_rect
			(start -0.4318 0.9525)
			(end 0.4318 -0.9525)
			(stroke
				(width 0)
				(type default)
			)
			(fill no)
			(layer "F.Fab")
		)
		(pad "1" smd custom
			(at 0 -0.4445)
			(size 0.1524 0.1524)
			(layers "F.Cu" "F.Mask" "F.Paste")
			(net "D_FLIP_CLR#")
			(options
				(clearance outline)
				(anchor circle)
			)
			(primitives
				(gr_poly
					(pts
						(arc
							(start 0.3048 -0.2032)
							(mid 0.275042 -0.275042)
							(end 0.2032 -0.3048)
						)
						(arc
							(start -0.2032 -0.3048)
							(mid -0.275042 -0.275042)
							(end -0.3048 -0.2032)
						)
						(arc
							(start -0.3048 0.2032)
							(mid -0.275042 0.275042)
							(end -0.2032 0.3048)
						)
						(arc
							(start 0.2032 0.3048)
							(mid 0.275042 0.275042)
							(end 0.3048 0.2032)
						)
					)
					(width 0)
					(fill yes)
				)
			)
		)
		(pad "2" smd custom
			(at 0 0.4445)
			(size 0.1524 0.1524)
			(layers "F.Cu" "F.Mask" "F.Paste")
			(net "GND")
			(options
				(clearance outline)
				(anchor circle)
			)
			(primitives
				(gr_poly
					(pts
						(arc
							(start 0.3048 -0.2032)
							(mid 0.275042 -0.275042)
							(end 0.2032 -0.3048)
						)
						(arc
							(start -0.2032 -0.3048)
							(mid -0.275042 -0.275042)
							(end -0.3048 -0.2032)
						)
						(arc
							(start -0.3048 0.2032)
							(mid -0.275042 0.275042)
							(end -0.2032 0.3048)
						)
						(arc
							(start 0.2032 0.3048)
							(mid 0.275042 0.275042)
							(end 0.3048 0.2032)
						)
					)
					(width 0)
					(fill yes)
				)
			)
		)
	)
	(footprint ""
		(layer "F.Cu")
		(at 178.40706 -124.60224 180)
		(property "Reference" "R727"
			(at 0 0 180)
			(layer "F.SilkS")
			(hide yes)
			(effects
				(font
					(size 1.27 1.27)
				)
			)
		)
		(property "Value" "0R2J-2-GP"
			(at 0.064008 -3.993896 180)
			(unlocked yes)
			(layer "F.Fab")
			(hide yes)
			(effects
				(font
					(size 1.016 1.016)
					(thickness 0.1524)
				)
			)
		)
		(property "Device Type" "R402H16"
			(at 0.064008 -5.517896 180)
			(unlocked yes)
			(layer "F.Fab")
			(hide yes)
			(effects
				(font
					(size 1.016 1.016)
					(thickness 0.1524)
				)
			)
		)
		(duplicate_pad_numbers_are_jumpers no)
		(fp_line
			(start 0.508 -0.9398)
			(end -0.508 -0.9398)
			(stroke
				(width 0.1524)
				(type default)
			)
			(layer "F.SilkS")
		)
		(fp_line
			(start -0.508 -0.9398)
			(end -0.508 0.9398)
			(stroke
				(width 0.1524)
				(type default)
			)
			(layer "F.SilkS")
		)
		(fp_rect
			(start -0.508 0.9398)
			(end 0.508 -0.9398)
			(stroke
				(width 0)
				(type default)
			)
			(fill no)
			(layer "F.CrtYd")
		)
		(fp_rect
			(start -0.508 0.9398)
			(end 0.508 -0.9398)
			(stroke
				(width 0)
				(type default)
			)
			(fill no)
			(layer "F.Fab")
		)
		(pad "1" smd custom
			(at 0 -0.4445 180)
			(size 0.1397 0.1397)
			(layers "F.Cu" "F.Mask" "F.Paste")
			(net "P1V8_EN")
			(options
				(clearance outline)
				(anchor circle)
			)
			(primitives
				(gr_poly
					(pts
						(arc
							(start -0.1778 -0.2794)
							(mid -0.249642 -0.249642)
							(end -0.2794 -0.1778)
						)
						(arc
							(start -0.2794 0.1778)
							(mid -0.249642 0.249642)
							(end -0.1778 0.2794)
						)
						(arc
							(start 0.1778 0.2794)
							(mid 0.249642 0.249642)
							(end 0.2794 0.1778)
						)
						(arc
							(start 0.2794 -0.1778)
							(mid 0.249642 -0.249642)
							(end 0.1778 -0.2794)
						)
					)
					(width 0)
					(fill yes)
				)
			)
		)
		(pad "2" smd custom
			(at 0 0.4445 180)
			(size 0.1397 0.1397)
			(layers "F.Cu" "F.Mask" "F.Paste")
			(net "P3V3_PG")
			(options
				(clearance outline)
				(anchor circle)
			)
			(primitives
				(gr_poly
					(pts
						(arc
							(start -0.1778 -0.2794)
							(mid -0.249642 -0.249642)
							(end -0.2794 -0.1778)
						)
						(arc
							(start -0.2794 0.1778)
							(mid -0.249642 0.249642)
							(end -0.1778 0.2794)
						)
						(arc
							(start 0.1778 0.2794)
							(mid 0.249642 0.249642)
							(end 0.2794 0.1778)
						)
						(arc
							(start 0.2794 -0.1778)
							(mid 0.249642 -0.249642)
							(end 0.1778 -0.2794)
						)
					)
					(width 0)
					(fill yes)
				)
			)
		)
	)
	(footprint ""
		(layer "F.Cu")
		(at 74.5236 -143.6624 90)
		(property "Reference" "R131"
			(at 0 0 90)
			(layer "F.SilkS")
			(hide yes)
			(effects
				(font
					(size 1.27 1.27)
				)
			)
		)
		(property "Value" "0R2J-2-GP"
			(at 0.064008 -3.993896 90)
			(unlocked yes)
			(layer "F.Fab")
			(hide yes)
			(effects
				(font
					(size 1.016 1.016)
					(thickness 0.1524)
				)
			)
		)
		(property "Device Type" "R402H16"
			(at 0.064008 -5.517896 90)
			(unlocked yes)
			(layer "F.Fab")
			(hide yes)
			(effects
				(font
					(size 1.016 1.016)
					(thickness 0.1524)
				)
			)
		)
		(duplicate_pad_numbers_are_jumpers no)
		(fp_line
			(start 0.508 -0.9398)
			(end -0.508 -0.9398)
			(stroke
				(width 0.1524)
				(type default)
			)
			(layer "F.SilkS")
		)
		(fp_line
			(start -0.508 -0.9398)
			(end -0.508 0.9398)
			(stroke
				(width 0.1524)
				(type default)
			)
			(layer "F.SilkS")
		)
		(fp_rect
			(start -0.508 0.9398)
			(end 0.508 -0.9398)
			(stroke
				(width 0)
				(type default)
			)
			(fill no)
			(layer "F.CrtYd")
		)
		(fp_rect
			(start -0.508 0.9398)
			(end 0.508 -0.9398)
			(stroke
				(width 0)
				(type default)
			)
			(fill no)
			(layer "F.Fab")
		)
		(pad "1" smd custom
			(at 0 -0.4445 90)
			(size 0.1397 0.1397)
			(layers "F.Cu" "F.Mask" "F.Paste")
			(net "I2C_SCC_SCL")
			(options
				(clearance outline)
				(anchor circle)
			)
			(primitives
				(gr_poly
					(pts
						(arc
							(start -0.1778 -0.2794)
							(mid -0.249642 -0.249642)
							(end -0.2794 -0.1778)
						)
						(arc
							(start -0.2794 0.1778)
							(mid -0.249642 0.249642)
							(end -0.1778 0.2794)
						)
						(arc
							(start 0.1778 0.2794)
							(mid 0.249642 0.249642)
							(end 0.2794 0.1778)
						)
						(arc
							(start 0.2794 -0.1778)
							(mid 0.249642 -0.249642)
							(end 0.1778 -0.2794)
						)
					)
					(width 0)
					(fill yes)
				)
			)
		)
		(pad "2" smd custom
			(at 0 0.4445 90)
			(size 0.1397 0.1397)
			(layers "F.Cu" "F.Mask" "F.Paste")
			(net "I2C_SCC_SCL_R")
			(options
				(clearance outline)
				(anchor circle)
			)
			(primitives
				(gr_poly
					(pts
						(arc
							(start -0.1778 -0.2794)
							(mid -0.249642 -0.249642)
							(end -0.2794 -0.1778)
						)
						(arc
							(start -0.2794 0.1778)
							(mid -0.249642 0.249642)
							(end -0.1778 0.2794)
						)
						(arc
							(start 0.1778 0.2794)
							(mid 0.249642 0.249642)
							(end 0.2794 0.1778)
						)
						(arc
							(start 0.2794 -0.1778)
							(mid 0.249642 -0.249642)
							(end 0.1778 -0.2794)
						)
					)
					(width 0)
					(fill yes)
				)
			)
		)
	)
	(footprint ""
		(layer "F.Cu")
		(at 23.2918 -183.5658 90)
		(property "Reference" "L8"
			(at 0 0 90)
			(layer "F.SilkS")
			(hide yes)
			(effects
				(font
					(size 1.27 1.27)
				)
			)
		)
		(property "Value" "BLM21PG220SN1DGP"
			(at 0.0254 -5.6896 90)
			(unlocked yes)
			(layer "F.Fab")
			(hide yes)
			(effects
				(font
					(size 1.016 1.016)
					(thickness 0.1524)
				)
			)
		)
		(property "Device Type" "L20125H42"
			(at 0.0254 -7.5946 90)
			(unlocked yes)
			(layer "F.Fab")
			(hide yes)
			(effects
				(font
					(size 1.016 1.016)
					(thickness 0.1524)
				)
			)
		)
		(duplicate_pad_numbers_are_jumpers no)
		(fp_line
			(start 0.9144 -1.7018)
			(end -0.9144 -1.7018)
			(stroke
				(width 0.1524)
				(type default)
			)
			(layer "F.SilkS")
		)
		(fp_line
			(start -0.9144 -1.7018)
			(end -0.9144 1.7018)
			(stroke
				(width 0.1524)
				(type default)
			)
			(layer "F.SilkS")
		)
		(fp_line
			(start 0.9144 1.7018)
			(end 0.9144 -1.7018)
			(stroke
				(width 0.1524)
				(type default)
			)
			(layer "F.SilkS")
		)
		(fp_line
			(start -0.9144 1.7018)
			(end 0.9144 1.7018)
			(stroke
				(width 0.1524)
				(type default)
			)
			(layer "F.SilkS")
		)
		(fp_rect
			(start -1.0033 1.778)
			(end 1.0033 -1.778)
			(stroke
				(width 0)
				(type default)
			)
			(fill no)
			(layer "F.CrtYd")
		)
		(fp_poly
			(pts
				(xy -1.0033 -1.778) (xy 1.0033 -1.778) (xy 1.0033 1.778) (xy -1.0033 1.778)
			)
			(stroke
				(width 0)
				(type default)
			)
			(fill no)
			(layer "F.Fab")
		)
		(pad "1" smd rect
			(at 0 -0.9652 90)
			(size 1.397 1.143)
			(layers "F.Cu" "F.Mask" "F.Paste")
			(net "P12V_STBY")
		)
		(pad "2" smd rect
			(at 0 0.9652 90)
			(size 1.397 1.143)
			(layers "F.Cu" "F.Mask" "F.Paste")
			(net "P12V_STBY_VIN_PU2")
		)
	)
	(footprint ""
		(layer "F.Cu")
		(at 60.452 -158.623)
		(property "Reference" "R397"
			(at 0 0 0)
			(layer "F.SilkS")
			(hide yes)
			(effects
				(font
					(size 1.27 1.27)
				)
			)
		)
		(property "Value" "4K7R2F-GP"
			(at 0.064008 -3.993896 0)
			(unlocked yes)
			(layer "F.Fab")
			(hide yes)
			(effects
				(font
					(size 1.016 1.016)
					(thickness 0.1524)
				)
			)
		)
		(property "Device Type" "R402H16"
			(at 0.064008 -5.517896 0)
			(unlocked yes)
			(layer "F.Fab")
			(hide yes)
			(effects
				(font
					(size 1.016 1.016)
					(thickness 0.1524)
				)
			)
		)
		(duplicate_pad_numbers_are_jumpers no)
		(fp_line
			(start -0.508 -0.9398)
			(end -0.508 0.9398)
			(stroke
				(width 0.1524)
				(type default)
			)
			(layer "F.SilkS")
		)
		(fp_line
			(start 0.508 -0.9398)
			(end -0.508 -0.9398)
			(stroke
				(width 0.1524)
				(type default)
			)
			(layer "F.SilkS")
		)
		(fp_rect
			(start -0.508 0.9398)
			(end 0.508 -0.9398)
			(stroke
				(width 0)
				(type default)
			)
			(fill no)
			(layer "F.CrtYd")
		)
		(fp_rect
			(start -0.508 0.9398)
			(end 0.508 -0.9398)
			(stroke
				(width 0)
				(type default)
			)
			(fill no)
			(layer "F.Fab")
		)
		(pad "1" smd custom
			(at 0 -0.4445)
			(size 0.1397 0.1397)
			(layers "F.Cu" "F.Mask" "F.Paste")
			(net "GND")
			(options
				(clearance outline)
				(anchor circle)
			)
			(primitives
				(gr_poly
					(pts
						(arc
							(start -0.1778 -0.2794)
							(mid -0.249642 -0.249642)
							(end -0.2794 -0.1778)
						)
						(arc
							(start -0.2794 0.1778)
							(mid -0.249642 0.249642)
							(end -0.1778 0.2794)
						)
						(arc
							(start 0.1778 0.2794)
							(mid 0.249642 0.249642)
							(end 0.2794 0.1778)
						)
						(arc
							(start 0.2794 -0.1778)
							(mid 0.249642 -0.249642)
							(end 0.1778 -0.2794)
						)
					)
					(width 0)
					(fill yes)
				)
			)
		)
		(pad "2" smd custom
			(at 0 0.4445)
			(size 0.1397 0.1397)
			(layers "F.Cu" "F.Mask" "F.Paste")
			(net "MAC2_TXD1")
			(options
				(clearance outline)
				(anchor circle)
			)
			(primitives
				(gr_poly
					(pts
						(arc
							(start -0.1778 -0.2794)
							(mid -0.249642 -0.249642)
							(end -0.2794 -0.1778)
						)
						(arc
							(start -0.2794 0.1778)
							(mid -0.249642 0.249642)
							(end -0.1778 0.2794)
						)
						(arc
							(start 0.1778 0.2794)
							(mid 0.249642 0.249642)
							(end 0.2794 0.1778)
						)
						(arc
							(start 0.2794 -0.1778)
							(mid 0.249642 -0.249642)
							(end 0.1778 -0.2794)
						)
					)
					(width 0)
					(fill yes)
				)
			)
		)
	)
	(footprint ""
		(layer "F.Cu")
		(at 66.04 -163.322 -90)
		(property "Reference" "R76"
			(at 0 0 270)
			(layer "F.SilkS")
			(hide yes)
			(effects
				(font
					(size 1.27 1.27)
				)
			)
		)
		(property "Value" "47KR2F-GP"
			(at 0.064008 -3.993896 270)
			(unlocked yes)
			(layer "F.Fab")
			(hide yes)
			(effects
				(font
					(size 1.016 1.016)
					(thickness 0.1524)
				)
			)
		)
		(property "Device Type" "R402H16"
			(at 0.064008 -5.517896 270)
			(unlocked yes)
			(layer "F.Fab")
			(hide yes)
			(effects
				(font
					(size 1.016 1.016)
					(thickness 0.1524)
				)
			)
		)
		(duplicate_pad_numbers_are_jumpers no)
		(fp_line
			(start -0.508 -0.9398)
			(end -0.508 0.9398)
			(stroke
				(width 0.1524)
				(type default)
			)
			(layer "F.SilkS")
		)
		(fp_line
			(start 0.508 -0.9398)
			(end -0.508 -0.9398)
			(stroke
				(width 0.1524)
				(type default)
			)
			(layer "F.SilkS")
		)
		(fp_rect
			(start -0.508 0.9398)
			(end 0.508 -0.9398)
			(stroke
				(width 0)
				(type default)
			)
			(fill no)
			(layer "F.CrtYd")
		)
		(fp_rect
			(start -0.508 0.9398)
			(end 0.508 -0.9398)
			(stroke
				(width 0)
				(type default)
			)
			(fill no)
			(layer "F.Fab")
		)
		(pad "1" smd custom
			(at 0 -0.4445 270)
			(size 0.1397 0.1397)
			(layers "F.Cu" "F.Mask" "F.Paste")
			(net "FM_TPM_PRSNT_RST_N")
			(options
				(clearance outline)
				(anchor circle)
			)
			(primitives
				(gr_poly
					(pts
						(arc
							(start -0.1778 -0.2794)
							(mid -0.249642 -0.249642)
							(end -0.2794 -0.1778)
						)
						(arc
							(start -0.2794 0.1778)
							(mid -0.249642 0.249642)
							(end -0.1778 0.2794)
						)
						(arc
							(start 0.1778 0.2794)
							(mid 0.249642 0.249642)
							(end 0.2794 0.1778)
						)
						(arc
							(start 0.2794 -0.1778)
							(mid 0.249642 -0.249642)
							(end 0.1778 -0.2794)
						)
					)
					(width 0)
					(fill yes)
				)
			)
		)
		(pad "2" smd custom
			(at 0 0.4445 270)
			(size 0.1397 0.1397)
			(layers "F.Cu" "F.Mask" "F.Paste")
			(net "FM_TPM_PRSNT_RST_N_R")
			(options
				(clearance outline)
				(anchor circle)
			)
			(primitives
				(gr_poly
					(pts
						(arc
							(start -0.1778 -0.2794)
							(mid -0.249642 -0.249642)
							(end -0.2794 -0.1778)
						)
						(arc
							(start -0.2794 0.1778)
							(mid -0.249642 0.249642)
							(end -0.1778 0.2794)
						)
						(arc
							(start 0.1778 0.2794)
							(mid 0.249642 0.249642)
							(end 0.2794 0.1778)
						)
						(arc
							(start 0.2794 -0.1778)
							(mid 0.249642 -0.249642)
							(end 0.1778 -0.2794)
						)
					)
					(width 0)
					(fill yes)
				)
			)
		)
	)
	(footprint ""
		(layer "F.Cu")
		(at 94.488 -17.8816)
		(property "Reference" "D19"
			(at 0 0 0)
			(layer "F.SilkS")
			(hide yes)
			(effects
				(font
					(size 1.27 1.27)
				)
			)
		)
		(property "Value" "PESD5V0F1BL-GP"
			(at 1.8923 -1.5621 0)
			(unlocked yes)
			(layer "F.Fab")
			(hide yes)
			(effects
				(font
					(size 1.016 1.016)
					(thickness 0.1524)
				)
			)
		)
		(property "Device Type" "SOD882-10D6-1H20"
			(at 1.8923 -3.0861 0)
			(unlocked yes)
			(layer "F.Fab")
			(hide yes)
			(effects
				(font
					(size 1.016 1.016)
					(thickness 0.1524)
				)
			)
		)
		(duplicate_pad_numbers_are_jumpers no)
		(fp_line
			(start -0.3048 -0.9271)
			(end 0.3048 -0.9271)
			(stroke
				(width 0.254)
				(type default)
			)
			(layer "F.SilkS")
		)
		(fp_rect
			(start -0.2921 0.4953)
			(end 0.2921 -0.4953)
			(stroke
				(width 0)
				(type default)
			)
			(fill no)
			(layer "F.CrtYd")
		)
		(fp_poly
			(pts
				(xy -0.4318 0.8001) (xy -0.4318 -0.266192) (xy -0.2921 -0.266192) (xy -0.2921 0.4953) (xy 0.2921 0.4953)
				(xy 0.2921 -0.4953) (xy -0.2921 -0.4953) (xy -0.2921 -0.2667) (xy -0.4318 -0.2667) (xy -0.4318 -0.8001)
				(xy 0.4318 -0.8001) (xy 0.4318 0.8001)
			)
			(stroke
				(width 0)
				(type default)
			)
			(fill no)
			(layer "F.CrtYd")
		)
		(fp_rect
			(start -0.4318 0.8001)
			(end 0.4318 -0.8001)
			(stroke
				(width 0)
				(type default)
			)
			(fill no)
			(layer "F.Fab")
		)
		(pad "1" smd custom
			(at 0 -0.4445)
			(size 0.1143 0.1143)
			(layers "F.Cu" "F.Mask" "F.Paste")
			(net "GND")
			(options
				(clearance outline)
				(anchor circle)
			)
			(primitives
				(gr_poly
					(pts
						(arc
							(start -0.2032 0.2286)
							(mid -0.275042 0.198842)
							(end -0.3048 0.127)
						)
						(arc
							(start -0.3048 -0.127)
							(mid -0.275042 -0.198842)
							(end -0.2032 -0.2286)
						)
						(arc
							(start 0.2032 -0.2286)
							(mid 0.275042 -0.198842)
							(end 0.3048 -0.127)
						)
						(arc
							(start 0.3048 0.127)
							(mid 0.275042 0.198842)
							(end 0.2032 0.2286)
						)
					)
					(width 0)
					(fill yes)
				)
			)
		)
		(pad "2" smd custom
			(at 0 0.4445)
			(size 0.1143 0.1143)
			(layers "F.Cu" "F.Mask" "F.Paste")
			(net "USB_P1_F_DN1")
			(options
				(clearance outline)
				(anchor circle)
			)
			(primitives
				(gr_poly
					(pts
						(arc
							(start 0.2032 -0.2286)
							(mid 0.275042 -0.198842)
							(end 0.3048 -0.127)
						)
						(arc
							(start 0.3048 0.127)
							(mid 0.275042 0.198842)
							(end 0.2032 0.2286)
						)
						(arc
							(start -0.2032 0.2286)
							(mid -0.275042 0.198842)
							(end -0.3048 0.127)
						)
						(arc
							(start -0.3048 -0.127)
							(mid -0.275042 -0.198842)
							(end -0.2032 -0.2286)
						)
					)
					(width 0)
					(fill yes)
				)
			)
		)
	)
	(footprint ""
		(layer "F.Cu")
		(at 205.2828 -111.5568 180)
		(property "Reference" "C509"
			(at 0 0 180)
			(layer "F.SilkS")
			(hide yes)
			(effects
				(font
					(size 1.27 1.27)
				)
			)
		)
		(property "Value" "SE470UF2VDM-GP"
			(at 0 -9.6012 180)
			(unlocked yes)
			(layer "F.Fab")
			(hide yes)
			(effects
				(font
					(size 1.016 1.016)
					(thickness 0.1524)
				)
			)
		)
		(property "Device Type" "CT7343H83"
			(at 0 -11.1252 180)
			(unlocked yes)
			(layer "F.Fab")
			(hide yes)
			(effects
				(font
					(size 1.016 1.016)
					(thickness 0.1524)
				)
			)
		)
		(duplicate_pad_numbers_are_jumpers no)
		(fp_line
			(start 2.286 4.8768)
			(end -2.286 4.8768)
			(stroke
				(width 0.1524)
				(type default)
			)
			(layer "F.SilkS")
		)
		(fp_line
			(start 2.286 2.032)
			(end 2.286 4.8768)
			(stroke
				(width 0.1524)
				(type default)
			)
			(layer "F.SilkS")
		)
		(fp_line
			(start 2.286 -2.032)
			(end 2.286 -4.8768)
			(stroke
				(width 0.1524)
				(type default)
			)
			(layer "F.SilkS")
		)
		(fp_line
			(start 2.286 -4.8768)
			(end -2.286 -4.8768)
			(stroke
				(width 0.1524)
				(type default)
			)
			(layer "F.SilkS")
		)
		(fp_line
			(start 2.1082 -4.699)
			(end -2.1082 -4.699)
			(stroke
				(width 0.508)
				(type default)
			)
			(layer "F.SilkS")
		)
		(fp_line
			(start -2.286 4.8768)
			(end -2.286 2.032)
			(stroke
				(width 0.1524)
				(type default)
			)
			(layer "F.SilkS")
		)
		(fp_line
			(start -2.286 -4.8768)
			(end -2.286 -2.032)
			(stroke
				(width 0.1524)
				(type default)
			)
			(layer "F.SilkS")
		)
		(fp_rect
			(start -2.1463 3.6449)
			(end 2.1463 -3.6449)
			(stroke
				(width 0)
				(type default)
			)
			(fill no)
			(layer "F.CrtYd")
		)
		(fp_poly
			(pts
				(xy -2.54 4.953) (xy -2.54 4.2926) (xy -3.81 4.2926) (xy -3.81 -4.2926) (xy -2.54 -4.2926) (xy -2.54 -4.953)
				(xy 2.54 -4.953) (xy 2.54 -4.2926) (xy 3.81 -4.2926) (xy 3.81 -1.6256) (xy 2.1463 -1.6256) (xy 2.1463 -3.6449)
				(xy -2.1463 -3.6449) (xy -2.1463 3.6449) (xy 2.1463 3.6449) (xy 2.1463 -1.6129) (xy 3.81 -1.6129)
				(xy 3.81 4.2926) (xy 2.54 4.2926) (xy 2.54 4.953)
			)
			(stroke
				(width 0)
				(type default)
			)
			(fill no)
			(layer "F.CrtYd")
		)
		(fp_rect
			(start 2.54 4.2926)
			(end 3.81 -4.2926)
			(stroke
				(width 0)
				(type default)
			)
			(fill no)
			(layer "F.Fab")
		)
		(fp_rect
			(start -2.54 4.953)
			(end 2.54 -4.953)
			(stroke
				(width 0)
				(type default)
			)
			(fill no)
			(layer "F.Fab")
		)
		(fp_rect
			(start -3.81 4.2926)
			(end -2.54 -4.2926)
			(stroke
				(width 0)
				(type default)
			)
			(fill no)
			(layer "F.Fab")
		)
		(pad "1" smd rect
			(at 0 -3.1496 180)
			(size 2.413 2.286)
			(layers "F.Cu" "F.Mask" "F.Paste")
			(net "P0V975")
		)
		(pad "2" smd rect
			(at 0 3.1496 180)
			(size 2.413 2.286)
			(layers "F.Cu" "F.Mask" "F.Paste")
			(net "GND")
		)
		(zone
			(layer "F.Cu")
			(hatch none 0.5)
			(connect_pads
				(clearance 0)
			)
			(min_thickness 0.25)
			(keepout
				(tracks allowed)
				(vias not_allowed)
				(pads allowed)
				(copperpour not_allowed)
				(footprints allowed)
			)
			(placement
				(enabled no)
				(sheetname "")
			)
			(fill
				(thermal_gap 0.5)
				(thermal_bridge_width 0.5)
				(island_removal_mode 0)
			)
			(polygon
				(pts
					(xy 203.7715 -109.8677) (xy 203.7715 -106.9594) (xy 206.7941 -106.9594) (xy 206.7941 -109.855)
					(xy 206.7941 -110.1852) (xy 203.7715 -110.1852)
				)
			)
		)
		(zone
			(layer "F.Cu")
			(hatch none 0.5)
			(connect_pads
				(clearance 0)
			)
			(min_thickness 0.25)
			(keepout
				(tracks allowed)
				(vias not_allowed)
				(pads allowed)
				(copperpour not_allowed)
				(footprints allowed)
			)
			(placement
				(enabled no)
				(sheetname "")
			)
			(fill
				(thermal_gap 0.5)
				(thermal_bridge_width 0.5)
				(island_removal_mode 0)
			)
			(polygon
				(pts
					(xy 206.7941 -116.1542) (xy 203.7715 -116.1542) (xy 203.7715 -113.2586) (xy 203.7715 -112.9284)
					(xy 206.7941 -112.9284) (xy 206.7941 -113.2586)
				)
			)
		)
	)
	(footprint ""
		(layer "F.Cu")
		(at 66.044826 -168.201086 90)
		(property "Reference" "R80"
			(at 0 0 90)
			(layer "F.SilkS")
			(hide yes)
			(effects
				(font
					(size 1.27 1.27)
				)
			)
		)
		(property "Value" "100KR2F-L1-GP"
			(at 0.064008 -3.993896 90)
			(unlocked yes)
			(layer "F.Fab")
			(hide yes)
			(effects
				(font
					(size 1.016 1.016)
					(thickness 0.1524)
				)
			)
		)
		(property "Device Type" "R402H16"
			(at 0.064008 -5.517896 90)
			(unlocked yes)
			(layer "F.Fab")
			(hide yes)
			(effects
				(font
					(size 1.016 1.016)
					(thickness 0.1524)
				)
			)
		)
		(duplicate_pad_numbers_are_jumpers no)
		(fp_line
			(start 0.508 -0.9398)
			(end -0.508 -0.9398)
			(stroke
				(width 0.1524)
				(type default)
			)
			(layer "F.SilkS")
		)
		(fp_line
			(start -0.508 -0.9398)
			(end -0.508 0.9398)
			(stroke
				(width 0.1524)
				(type default)
			)
			(layer "F.SilkS")
		)
		(fp_rect
			(start -0.508 0.9398)
			(end 0.508 -0.9398)
			(stroke
				(width 0)
				(type default)
			)
			(fill no)
			(layer "F.CrtYd")
		)
		(fp_rect
			(start -0.508 0.9398)
			(end 0.508 -0.9398)
			(stroke
				(width 0)
				(type default)
			)
			(fill no)
			(layer "F.Fab")
		)
		(pad "1" smd custom
			(at 0 -0.4445 90)
			(size 0.1397 0.1397)
			(layers "F.Cu" "F.Mask" "F.Paste")
			(net "Q4_G")
			(options
				(clearance outline)
				(anchor circle)
			)
			(primitives
				(gr_poly
					(pts
						(arc
							(start -0.1778 -0.2794)
							(mid -0.249642 -0.249642)
							(end -0.2794 -0.1778)
						)
						(arc
							(start -0.2794 0.1778)
							(mid -0.249642 0.249642)
							(end -0.1778 0.2794)
						)
						(arc
							(start 0.1778 0.2794)
							(mid 0.249642 0.249642)
							(end 0.2794 0.1778)
						)
						(arc
							(start 0.2794 -0.1778)
							(mid 0.249642 -0.249642)
							(end 0.1778 -0.2794)
						)
					)
					(width 0)
					(fill yes)
				)
			)
		)
		(pad "2" smd custom
			(at 0 0.4445 90)
			(size 0.1397 0.1397)
			(layers "F.Cu" "F.Mask" "F.Paste")
			(net "GND")
			(options
				(clearance outline)
				(anchor circle)
			)
			(primitives
				(gr_poly
					(pts
						(arc
							(start -0.1778 -0.2794)
							(mid -0.249642 -0.249642)
							(end -0.2794 -0.1778)
						)
						(arc
							(start -0.2794 0.1778)
							(mid -0.249642 0.249642)
							(end -0.1778 0.2794)
						)
						(arc
							(start 0.1778 0.2794)
							(mid 0.249642 0.249642)
							(end 0.2794 0.1778)
						)
						(arc
							(start 0.2794 -0.1778)
							(mid 0.249642 -0.249642)
							(end 0.1778 -0.2794)
						)
					)
					(width 0)
					(fill yes)
				)
			)
		)
	)
	(footprint ""
		(layer "F.Cu")
		(at 172.5168 -144.1196 -90)
		(property "Reference" "C154"
			(at 0 0 270)
			(layer "F.SilkS")
			(hide yes)
			(effects
				(font
					(size 1.27 1.27)
				)
			)
		)
		(property "Value" "SC10U16V5KX-7-GP-U"
			(at -0.0762 -6.1214 270)
			(unlocked yes)
			(layer "F.Fab")
			(hide yes)
			(effects
				(font
					(size 1.016 1.016)
					(thickness 0.1524)
				)
			)
		)
		(property "Device Type" "C805H58"
			(at -0.0762 -8.1534 270)
			(unlocked yes)
			(layer "F.Fab")
			(hide yes)
			(effects
				(font
					(size 1.016 1.016)
					(thickness 0.1524)
				)
			)
		)
		(duplicate_pad_numbers_are_jumpers no)
		(fp_line
			(start 0.635 0)
			(end -0.635 0)
			(stroke
				(width 0.508)
				(type default)
			)
			(layer "F.SilkS")
		)
		(fp_rect
			(start -0.9652 1.778)
			(end 0.9652 -1.778)
			(stroke
				(width 0)
				(type default)
			)
			(fill no)
			(layer "F.CrtYd")
		)
		(fp_poly
			(pts
				(xy -0.9652 -1.778) (xy 0.9652 -1.778) (xy 0.9652 1.778) (xy -0.9652 1.778)
			)
			(stroke
				(width 0)
				(type default)
			)
			(fill no)
			(layer "F.Fab")
		)
		(pad "1" smd rect
			(at 0 -0.9652 270)
			(size 1.397 1.143)
			(layers "F.Cu" "F.Mask" "F.Paste")
			(net "P12V_STBY_VIN_PU1")
		)
		(pad "2" smd rect
			(at 0 0.9652 270)
			(size 1.397 1.143)
			(layers "F.Cu" "F.Mask" "F.Paste")
			(net "GND")
		)
	)
	(footprint ""
		(layer "F.Cu")
		(at 51.45024 -158.944564 180)
		(property "Reference" "R297"
			(at 0 0 180)
			(layer "F.SilkS")
			(hide yes)
			(effects
				(font
					(size 1.27 1.27)
				)
			)
		)
		(property "Value" "0R2J-2-GP"
			(at 0.064008 -3.993896 180)
			(unlocked yes)
			(layer "F.Fab")
			(hide yes)
			(effects
				(font
					(size 1.016 1.016)
					(thickness 0.1524)
				)
			)
		)
		(property "Device Type" "R402H16"
			(at 0.064008 -5.517896 180)
			(unlocked yes)
			(layer "F.Fab")
			(hide yes)
			(effects
				(font
					(size 1.016 1.016)
					(thickness 0.1524)
				)
			)
		)
		(duplicate_pad_numbers_are_jumpers no)
		(fp_line
			(start 0.508 -0.9398)
			(end -0.508 -0.9398)
			(stroke
				(width 0.1524)
				(type default)
			)
			(layer "F.SilkS")
		)
		(fp_line
			(start -0.508 -0.9398)
			(end -0.508 0.9398)
			(stroke
				(width 0.1524)
				(type default)
			)
			(layer "F.SilkS")
		)
		(fp_rect
			(start -0.508 0.9398)
			(end 0.508 -0.9398)
			(stroke
				(width 0)
				(type default)
			)
			(fill no)
			(layer "F.CrtYd")
		)
		(fp_rect
			(start -0.508 0.9398)
			(end 0.508 -0.9398)
			(stroke
				(width 0)
				(type default)
			)
			(fill no)
			(layer "F.Fab")
		)
		(pad "1" smd custom
			(at 0 -0.4445 180)
			(size 0.1397 0.1397)
			(layers "F.Cu" "F.Mask" "F.Paste")
			(net "UART_BMC_R_TX")
			(options
				(clearance outline)
				(anchor circle)
			)
			(primitives
				(gr_poly
					(pts
						(arc
							(start -0.1778 -0.2794)
							(mid -0.249642 -0.249642)
							(end -0.2794 -0.1778)
						)
						(arc
							(start -0.2794 0.1778)
							(mid -0.249642 0.249642)
							(end -0.1778 0.2794)
						)
						(arc
							(start 0.1778 0.2794)
							(mid 0.249642 0.249642)
							(end 0.2794 0.1778)
						)
						(arc
							(start 0.2794 -0.1778)
							(mid 0.249642 -0.249642)
							(end 0.1778 -0.2794)
						)
					)
					(width 0)
					(fill yes)
				)
			)
		)
		(pad "2" smd custom
			(at 0 0.4445 180)
			(size 0.1397 0.1397)
			(layers "F.Cu" "F.Mask" "F.Paste")
			(net "UART_BMC_TX")
			(options
				(clearance outline)
				(anchor circle)
			)
			(primitives
				(gr_poly
					(pts
						(arc
							(start -0.1778 -0.2794)
							(mid -0.249642 -0.249642)
							(end -0.2794 -0.1778)
						)
						(arc
							(start -0.2794 0.1778)
							(mid -0.249642 0.249642)
							(end -0.1778 0.2794)
						)
						(arc
							(start 0.1778 0.2794)
							(mid 0.249642 0.249642)
							(end 0.2794 0.1778)
						)
						(arc
							(start 0.2794 -0.1778)
							(mid 0.249642 -0.249642)
							(end 0.1778 -0.2794)
						)
					)
					(width 0)
					(fill yes)
				)
			)
		)
	)
	(footprint ""
		(layer "F.Cu")
		(at 179.3748 -141.8082 -90)
		(property "Reference" "C161"
			(at 0 0 270)
			(layer "F.SilkS")
			(hide yes)
			(effects
				(font
					(size 1.27 1.27)
				)
			)
		)
		(property "Value" "SC1U16V3KX-5GP"
			(at 0 -2.8194 270)
			(unlocked yes)
			(layer "F.Fab")
			(hide yes)
			(effects
				(font
					(size 1.016 1.016)
					(thickness 0.1524)
				)
			)
		)
		(property "Device Type" "C603H36"
			(at 0 -4.3434 270)
			(unlocked yes)
			(layer "F.Fab")
			(hide yes)
			(effects
				(font
					(size 1.016 1.016)
					(thickness 0.1524)
				)
			)
		)
		(duplicate_pad_numbers_are_jumpers no)
		(fp_line
			(start 0.508 0)
			(end -0.508 0)
			(stroke
				(width 0.2032)
				(type default)
			)
			(layer "F.SilkS")
		)
		(fp_rect
			(start -0.5842 1.3335)
			(end 0.5842 -1.3335)
			(stroke
				(width 0)
				(type default)
			)
			(fill no)
			(layer "F.CrtYd")
		)
		(fp_rect
			(start -0.5842 1.3335)
			(end 0.5842 -1.3335)
			(stroke
				(width 0)
				(type default)
			)
			(fill no)
			(layer "F.Fab")
		)
		(pad "1" smd custom
			(at 0 -0.762 270)
			(size 0.2159 0.2159)
			(layers "F.Cu" "F.Mask" "F.Paste")
			(net "GND")
			(options
				(clearance outline)
				(anchor circle)
			)
			(primitives
				(gr_poly
					(pts
						(arc
							(start -0.3302 -0.4318)
							(mid -0.402042 -0.402042)
							(end -0.4318 -0.3302)
						)
						(arc
							(start -0.4318 0.3302)
							(mid -0.402042 0.402042)
							(end -0.3302 0.4318)
						)
						(arc
							(start 0.3302 0.4318)
							(mid 0.402042 0.402042)
							(end 0.4318 0.3302)
						)
						(arc
							(start 0.4318 -0.3302)
							(mid 0.402042 -0.402042)
							(end 0.3302 -0.4318)
						)
					)
					(width 0)
					(fill yes)
				)
			)
		)
		(pad "2" smd custom
			(at 0 0.762 270)
			(size 0.2159 0.2159)
			(layers "F.Cu" "F.Mask" "F.Paste")
			(net "P5V_STBY_VREG")
			(options
				(clearance outline)
				(anchor circle)
			)
			(primitives
				(gr_poly
					(pts
						(arc
							(start -0.3302 -0.4318)
							(mid -0.402042 -0.402042)
							(end -0.4318 -0.3302)
						)
						(arc
							(start -0.4318 0.3302)
							(mid -0.402042 0.402042)
							(end -0.3302 0.4318)
						)
						(arc
							(start 0.3302 0.4318)
							(mid 0.402042 0.402042)
							(end 0.4318 0.3302)
						)
						(arc
							(start 0.4318 -0.3302)
							(mid 0.402042 -0.402042)
							(end 0.3302 -0.4318)
						)
					)
					(width 0)
					(fill yes)
				)
			)
		)
	)
	(footprint ""
		(layer "F.Cu")
		(at 19.144742 -129.077466 180)
		(property "Reference" "R215"
			(at 0 0 180)
			(layer "F.SilkS")
			(hide yes)
			(effects
				(font
					(size 1.27 1.27)
				)
			)
		)
		(property "Value" "120R2F-GP"
			(at 0.064008 -3.993896 180)
			(unlocked yes)
			(layer "F.Fab")
			(hide yes)
			(effects
				(font
					(size 1.016 1.016)
					(thickness 0.1524)
				)
			)
		)
		(property "Device Type" "R402H16"
			(at 0.064008 -5.517896 180)
			(unlocked yes)
			(layer "F.Fab")
			(hide yes)
			(effects
				(font
					(size 1.016 1.016)
					(thickness 0.1524)
				)
			)
		)
		(duplicate_pad_numbers_are_jumpers no)
		(fp_line
			(start 0.508 -0.9398)
			(end -0.508 -0.9398)
			(stroke
				(width 0.1524)
				(type default)
			)
			(layer "F.SilkS")
		)
		(fp_line
			(start -0.508 -0.9398)
			(end -0.508 0.9398)
			(stroke
				(width 0.1524)
				(type default)
			)
			(layer "F.SilkS")
		)
		(fp_rect
			(start -0.508 0.9398)
			(end 0.508 -0.9398)
			(stroke
				(width 0)
				(type default)
			)
			(fill no)
			(layer "F.CrtYd")
		)
		(fp_rect
			(start -0.508 0.9398)
			(end 0.508 -0.9398)
			(stroke
				(width 0)
				(type default)
			)
			(fill no)
			(layer "F.Fab")
		)
		(pad "1" smd custom
			(at 0 -0.4445 180)
			(size 0.1397 0.1397)
			(layers "F.Cu" "F.Mask" "F.Paste")
			(net "GND")
			(options
				(clearance outline)
				(anchor circle)
			)
			(primitives
				(gr_poly
					(pts
						(arc
							(start -0.1778 -0.2794)
							(mid -0.249642 -0.249642)
							(end -0.2794 -0.1778)
						)
						(arc
							(start -0.2794 0.1778)
							(mid -0.249642 0.249642)
							(end -0.1778 0.2794)
						)
						(arc
							(start 0.1778 0.2794)
							(mid 0.249642 0.249642)
							(end 0.2794 0.1778)
						)
						(arc
							(start 0.2794 -0.1778)
							(mid 0.249642 -0.249642)
							(end 0.1778 -0.2794)
						)
					)
					(width 0)
					(fill yes)
				)
			)
		)
		(pad "2" smd custom
			(at 0 0.4445 180)
			(size 0.1397 0.1397)
			(layers "F.Cu" "F.Mask" "F.Paste")
			(net "MEMCSN")
			(options
				(clearance outline)
				(anchor circle)
			)
			(primitives
				(gr_poly
					(pts
						(arc
							(start -0.1778 -0.2794)
							(mid -0.249642 -0.249642)
							(end -0.2794 -0.1778)
						)
						(arc
							(start -0.2794 0.1778)
							(mid -0.249642 0.249642)
							(end -0.1778 0.2794)
						)
						(arc
							(start 0.1778 0.2794)
							(mid 0.249642 0.249642)
							(end 0.2794 0.1778)
						)
						(arc
							(start 0.2794 -0.1778)
							(mid 0.249642 -0.249642)
							(end 0.1778 -0.2794)
						)
					)
					(width 0)
					(fill yes)
				)
			)
		)
	)
	(footprint ""
		(layer "F.Cu")
		(at 115.2652 -14.9098 180)
		(property "Reference" "C128"
			(at 0 0 180)
			(layer "F.SilkS")
			(hide yes)
			(effects
				(font
					(size 1.27 1.27)
				)
			)
		)
		(property "Value" "SC1U25V3KX-GP"
			(at 0 -2.8194 180)
			(unlocked yes)
			(layer "F.Fab")
			(hide yes)
			(effects
				(font
					(size 1.016 1.016)
					(thickness 0.1524)
				)
			)
		)
		(property "Device Type" "C603H36"
			(at 0 -4.3434 180)
			(unlocked yes)
			(layer "F.Fab")
			(hide yes)
			(effects
				(font
					(size 1.016 1.016)
					(thickness 0.1524)
				)
			)
		)
		(duplicate_pad_numbers_are_jumpers no)
		(fp_line
			(start 0.508 0)
			(end -0.508 0)
			(stroke
				(width 0.2032)
				(type default)
			)
			(layer "F.SilkS")
		)
		(fp_rect
			(start -0.5842 1.3335)
			(end 0.5842 -1.3335)
			(stroke
				(width 0)
				(type default)
			)
			(fill no)
			(layer "F.CrtYd")
		)
		(fp_rect
			(start -0.5842 1.3335)
			(end 0.5842 -1.3335)
			(stroke
				(width 0)
				(type default)
			)
			(fill no)
			(layer "F.Fab")
		)
		(pad "1" smd custom
			(at 0 -0.762 180)
			(size 0.2159 0.2159)
			(layers "F.Cu" "F.Mask" "F.Paste")
			(net "MB0_VCC")
			(options
				(clearance outline)
				(anchor circle)
			)
			(primitives
				(gr_poly
					(pts
						(arc
							(start -0.3302 -0.4318)
							(mid -0.402042 -0.402042)
							(end -0.4318 -0.3302)
						)
						(arc
							(start -0.4318 0.3302)
							(mid -0.402042 0.402042)
							(end -0.3302 0.4318)
						)
						(arc
							(start 0.3302 0.4318)
							(mid 0.402042 0.402042)
							(end 0.4318 0.3302)
						)
						(arc
							(start 0.4318 -0.3302)
							(mid 0.402042 -0.402042)
							(end 0.3302 -0.4318)
						)
					)
					(width 0)
					(fill yes)
				)
			)
		)
		(pad "2" smd custom
			(at 0 0.762 180)
			(size 0.2159 0.2159)
			(layers "F.Cu" "F.Mask" "F.Paste")
			(net "AGND_CURRENT_MON")
			(options
				(clearance outline)
				(anchor circle)
			)
			(primitives
				(gr_poly
					(pts
						(arc
							(start -0.3302 -0.4318)
							(mid -0.402042 -0.402042)
							(end -0.4318 -0.3302)
						)
						(arc
							(start -0.4318 0.3302)
							(mid -0.402042 0.402042)
							(end -0.3302 0.4318)
						)
						(arc
							(start 0.3302 0.4318)
							(mid 0.402042 0.402042)
							(end 0.4318 0.3302)
						)
						(arc
							(start 0.4318 -0.3302)
							(mid 0.402042 -0.402042)
							(end 0.3302 -0.4318)
						)
					)
					(width 0)
					(fill yes)
				)
			)
		)
	)
	(footprint ""
		(layer "F.Cu")
		(at 41.744646 -177.06721)
		(property "Reference" "R485"
			(at 0 0 0)
			(layer "F.SilkS")
			(hide yes)
			(effects
				(font
					(size 1.27 1.27)
				)
			)
		)
		(property "Value" "0R2J-2-GP"
			(at 0.064008 -3.993896 0)
			(unlocked yes)
			(layer "F.Fab")
			(hide yes)
			(effects
				(font
					(size 1.016 1.016)
					(thickness 0.1524)
				)
			)
		)
		(property "Device Type" "R402H16"
			(at 0.064008 -5.517896 0)
			(unlocked yes)
			(layer "F.Fab")
			(hide yes)
			(effects
				(font
					(size 1.016 1.016)
					(thickness 0.1524)
				)
			)
		)
		(duplicate_pad_numbers_are_jumpers no)
		(fp_line
			(start -0.508 -0.9398)
			(end -0.508 0.9398)
			(stroke
				(width 0.1524)
				(type default)
			)
			(layer "F.SilkS")
		)
		(fp_line
			(start 0.508 -0.9398)
			(end -0.508 -0.9398)
			(stroke
				(width 0.1524)
				(type default)
			)
			(layer "F.SilkS")
		)
		(fp_rect
			(start -0.508 0.9398)
			(end 0.508 -0.9398)
			(stroke
				(width 0)
				(type default)
			)
			(fill no)
			(layer "F.CrtYd")
		)
		(fp_rect
			(start -0.508 0.9398)
			(end 0.508 -0.9398)
			(stroke
				(width 0)
				(type default)
			)
			(fill no)
			(layer "F.Fab")
		)
		(pad "1" smd custom
			(at 0 -0.4445)
			(size 0.1397 0.1397)
			(layers "F.Cu" "F.Mask" "F.Paste")
			(net "P3V3_STBY_EN")
			(options
				(clearance outline)
				(anchor circle)
			)
			(primitives
				(gr_poly
					(pts
						(arc
							(start -0.1778 -0.2794)
							(mid -0.249642 -0.249642)
							(end -0.2794 -0.1778)
						)
						(arc
							(start -0.2794 0.1778)
							(mid -0.249642 0.249642)
							(end -0.1778 0.2794)
						)
						(arc
							(start 0.1778 0.2794)
							(mid 0.249642 0.249642)
							(end 0.2794 0.1778)
						)
						(arc
							(start 0.2794 -0.1778)
							(mid 0.249642 -0.249642)
							(end 0.1778 -0.2794)
						)
					)
					(width 0)
					(fill yes)
				)
			)
		)
		(pad "2" smd custom
			(at 0 0.4445)
			(size 0.1397 0.1397)
			(layers "F.Cu" "F.Mask" "F.Paste")
			(net "PWRGD_P5V_STBY")
			(options
				(clearance outline)
				(anchor circle)
			)
			(primitives
				(gr_poly
					(pts
						(arc
							(start -0.1778 -0.2794)
							(mid -0.249642 -0.249642)
							(end -0.2794 -0.1778)
						)
						(arc
							(start -0.2794 0.1778)
							(mid -0.249642 0.249642)
							(end -0.1778 0.2794)
						)
						(arc
							(start 0.1778 0.2794)
							(mid 0.249642 0.249642)
							(end 0.2794 0.1778)
						)
						(arc
							(start 0.2794 -0.1778)
							(mid 0.249642 -0.249642)
							(end 0.1778 -0.2794)
						)
					)
					(width 0)
					(fill yes)
				)
			)
		)
	)
	(footprint ""
		(layer "F.Cu")
		(at 92.623894 -164.807646 180)
		(property "Reference" "X1"
			(at 0 0 180)
			(layer "F.SilkS")
			(hide yes)
			(effects
				(font
					(size 1.27 1.27)
				)
			)
		)
		(property "Value" "XTAL-24MHZ-87-GP"
			(at -0.0889 -3.0988 180)
			(unlocked yes)
			(layer "F.Fab")
			(hide yes)
			(effects
				(font
					(size 1.016 1.016)
					(thickness 0.1524)
				)
			)
		)
		(property "Device Type" "OSC-3225-4P-4H30"
			(at -0.0889 -4.6228 180)
			(unlocked yes)
			(layer "F.Fab")
			(hide yes)
			(effects
				(font
					(size 1.016 1.016)
					(thickness 0.1524)
				)
			)
		)
		(duplicate_pad_numbers_are_jumpers no)
		(fp_line
			(start 2.1209 1.5494)
			(end 2.1209 -1.5494)
			(stroke
				(width 0.1524)
				(type default)
			)
			(layer "F.SilkS")
		)
		(fp_line
			(start 2.1209 -1.5494)
			(end -2.1209 -1.5494)
			(stroke
				(width 0.1524)
				(type default)
			)
			(layer "F.SilkS")
		)
		(fp_line
			(start -1.143 1.651)
			(end -2.2098 1.651)
			(stroke
				(width 0.3302)
				(type default)
			)
			(layer "F.SilkS")
		)
		(fp_line
			(start -2.1209 1.5494)
			(end 2.1209 1.5494)
			(stroke
				(width 0.1524)
				(type default)
			)
			(layer "F.SilkS")
		)
		(fp_line
			(start -2.1209 -1.5494)
			(end -2.1209 1.5494)
			(stroke
				(width 0.1524)
				(type default)
			)
			(layer "F.SilkS")
		)
		(fp_line
			(start -2.2098 1.651)
			(end -2.2098 0.6604)
			(stroke
				(width 0.3302)
				(type default)
			)
			(layer "F.SilkS")
		)
		(fp_poly
			(pts
				(xy -2.6289 1.1938) (xy -2.6289 0.3302) (xy -2.1971 0.762)
			)
			(stroke
				(width 0)
				(type default)
			)
			(fill yes)
			(layer "F.SilkS")
		)
		(fp_rect
			(start -1.6002 1.2446)
			(end 1.6002 -1.2446)
			(stroke
				(width 0)
				(type default)
			)
			(fill no)
			(layer "F.CrtYd")
		)
		(fp_poly
			(pts
				(xy -2.3749 1.8034) (xy -2.3749 -1.8034) (xy 2.3749 -1.8034) (xy 2.3749 1.8034) (xy 0.00254 1.8034)
				(xy 0.00254 1.2446) (xy 1.6002 1.2446) (xy 1.6002 -1.2446) (xy -1.6002 -1.2446) (xy -1.6002 1.2446)
				(xy -0.00254 1.2446) (xy -0.00254 1.8034)
			)
			(stroke
				(width 0)
				(type default)
			)
			(fill no)
			(layer "F.CrtYd")
		)
		(fp_rect
			(start -2.3749 1.8034)
			(end 2.3749 -1.8034)
			(stroke
				(width 0)
				(type default)
			)
			(fill no)
			(layer "F.Fab")
		)
		(pad "1" smd rect
			(at -1.171448 0.756412 180)
			(size 1.397 1.0668)
			(layers "F.Cu" "F.Mask" "F.Paste")
			(net "USB_HUB_XTAL_OUT")
		)
		(pad "2" smd rect
			(at 1.171448 0.756412 180)
			(size 1.397 1.0668)
			(layers "F.Cu" "F.Mask" "F.Paste")
			(net "GND")
		)
		(pad "3" smd rect
			(at 1.171448 -0.756412 180)
			(size 1.397 1.0668)
			(layers "F.Cu" "F.Mask" "F.Paste")
			(net "USB_HUB_XTAL_IN")
		)
		(pad "4" smd rect
			(at -1.171448 -0.756412 180)
			(size 1.397 1.0668)
			(layers "F.Cu" "F.Mask" "F.Paste")
			(net "GND")
		)
		(zone
			(layer "F.Cu")
			(hatch none 0.5)
			(connect_pads
				(clearance 0)
			)
			(min_thickness 0.25)
			(keepout
				(tracks not_allowed)
				(vias allowed)
				(pads allowed)
				(copperpour not_allowed)
				(footprints allowed)
			)
			(placement
				(enabled no)
				(sheetname "")
			)
			(fill
				(thermal_gap 0.5)
				(thermal_bridge_width 0.5)
				(island_removal_mode 0)
			)
			(polygon
				(pts
					(xy 92.674694 -164.858446) (xy 92.573094 -164.858446) (xy 92.573094 -164.756846) (xy 92.674694 -164.756846)
				)
			)
		)
		(zone
			(layer "F.Cu")
			(hatch none 0.5)
			(connect_pads
				(clearance 0)
			)
			(min_thickness 0.25)
			(keepout
				(tracks allowed)
				(vias not_allowed)
				(pads allowed)
				(copperpour not_allowed)
				(footprints allowed)
			)
			(placement
				(enabled no)
				(sheetname "")
			)
			(fill
				(thermal_gap 0.5)
				(thermal_bridge_width 0.5)
				(island_removal_mode 0)
			)
			(polygon
				(pts
					(xy 93.096842 -163.517834) (xy 92.150946 -163.517834) (xy 92.150946 -164.584634) (xy 90.753946 -164.584634)
					(xy 90.753946 -165.030658) (xy 92.150946 -165.030658) (xy 92.150946 -166.097458) (xy 93.096842 -166.097458)
					(xy 93.096842 -165.030658) (xy 94.493842 -165.030658) (xy 94.493842 -164.584634) (xy 93.096842 -164.584634)
				)
			)
		)
	)
	(footprint ""
		(layer "F.Cu")
		(at 21.2725 -167.247316 180)
		(property "Reference" "C223"
			(at 0 0 180)
			(layer "F.SilkS")
			(hide yes)
			(effects
				(font
					(size 1.27 1.27)
				)
			)
		)
		(property "Value" "SC10U6D3V5KX-4GP"
			(at -0.0762 -6.1214 180)
			(unlocked yes)
			(layer "F.Fab")
			(hide yes)
			(effects
				(font
					(size 1.016 1.016)
					(thickness 0.1524)
				)
			)
		)
		(property "Device Type" "C805H58"
			(at -0.0762 -8.1534 180)
			(unlocked yes)
			(layer "F.Fab")
			(hide yes)
			(effects
				(font
					(size 1.016 1.016)
					(thickness 0.1524)
				)
			)
		)
		(duplicate_pad_numbers_are_jumpers no)
		(fp_line
			(start 0.635 0)
			(end -0.635 0)
			(stroke
				(width 0.508)
				(type default)
			)
			(layer "F.SilkS")
		)
		(fp_rect
			(start -0.9652 1.778)
			(end 0.9652 -1.778)
			(stroke
				(width 0)
				(type default)
			)
			(fill no)
			(layer "F.CrtYd")
		)
		(fp_poly
			(pts
				(xy -0.9652 -1.778) (xy 0.9652 -1.778) (xy 0.9652 1.778) (xy -0.9652 1.778)
			)
			(stroke
				(width 0)
				(type default)
			)
			(fill no)
			(layer "F.Fab")
		)
		(pad "1" smd rect
			(at 0 -0.9652 180)
			(size 1.397 1.143)
			(layers "F.Cu" "F.Mask" "F.Paste")
			(net "TPS74801_P1V2_STBY_OUT")
		)
		(pad "2" smd rect
			(at 0 0.9652 180)
			(size 1.397 1.143)
			(layers "F.Cu" "F.Mask" "F.Paste")
			(net "GND")
		)
	)
	(footprint ""
		(layer "F.Cu")
		(at 169.799 -180.2892 90)
		(property "Reference" "G1"
			(at 0 0 90)
			(layer "F.SilkS")
			(hide yes)
			(effects
				(font
					(size 1.27 1.27)
				)
			)
		)
		(property "Value" "GAP-CLOSE-PWR-4-GP"
			(at -2.4638 -0.5461 90)
			(unlocked yes)
			(layer "F.Fab")
			(hide yes)
			(effects
				(font
					(size 1.016 1.016)
					(thickness 0.1524)
				)
			)
		)
		(property "Device Type" "GAP-CLOSE-PWR-4"
			(at -2.4638 -2.0701 90)
			(unlocked yes)
			(layer "F.Fab")
			(hide yes)
			(effects
				(font
					(size 1.016 1.016)
					(thickness 0.1524)
				)
			)
		)
		(duplicate_pad_numbers_are_jumpers no)
		(fp_rect
			(start -0.2794 0.254)
			(end 0.2794 -0.254)
			(stroke
				(width 0)
				(type default)
			)
			(fill no)
			(layer "F.CrtYd")
		)
		(fp_rect
			(start -0.2794 0.254)
			(end 0.2794 -0.254)
			(stroke
				(width 0)
				(type default)
			)
			(fill no)
			(layer "F.Fab")
		)
		(pad "1" smd rect
			(at -0.0635 0 90)
			(size 0.1778 0.254)
			(layers "F.Cu" "F.Mask" "F.Paste")
			(net "P5V_STBY")
		)
		(pad "2" smd rect
			(at 0.0635 0 90)
			(size 0.1778 0.254)
			(layers "F.Cu" "F.Mask" "F.Paste")
			(net "P5V_CC")
		)
	)
	(footprint ""
		(layer "F.Cu")
		(at 176.917858 -116.587524 180)
		(property "Reference" "R568"
			(at 0 0 180)
			(layer "F.SilkS")
			(hide yes)
			(effects
				(font
					(size 1.27 1.27)
				)
			)
		)
		(property "Value" "10KR2F-2-GP"
			(at 0.064008 -3.993896 180)
			(unlocked yes)
			(layer "F.Fab")
			(hide yes)
			(effects
				(font
					(size 1.016 1.016)
					(thickness 0.1524)
				)
			)
		)
		(property "Device Type" "R402H16"
			(at 0.064008 -5.517896 180)
			(unlocked yes)
			(layer "F.Fab")
			(hide yes)
			(effects
				(font
					(size 1.016 1.016)
					(thickness 0.1524)
				)
			)
		)
		(duplicate_pad_numbers_are_jumpers no)
		(fp_line
			(start 0.508 -0.9398)
			(end -0.508 -0.9398)
			(stroke
				(width 0.1524)
				(type default)
			)
			(layer "F.SilkS")
		)
		(fp_line
			(start -0.508 -0.9398)
			(end -0.508 0.9398)
			(stroke
				(width 0.1524)
				(type default)
			)
			(layer "F.SilkS")
		)
		(fp_rect
			(start -0.508 0.9398)
			(end 0.508 -0.9398)
			(stroke
				(width 0)
				(type default)
			)
			(fill no)
			(layer "F.CrtYd")
		)
		(fp_rect
			(start -0.508 0.9398)
			(end 0.508 -0.9398)
			(stroke
				(width 0)
				(type default)
			)
			(fill no)
			(layer "F.Fab")
		)
		(pad "1" smd custom
			(at 0 -0.4445 180)
			(size 0.1397 0.1397)
			(layers "F.Cu" "F.Mask" "F.Paste")
			(net "P1V8")
			(options
				(clearance outline)
				(anchor circle)
			)
			(primitives
				(gr_poly
					(pts
						(arc
							(start -0.1778 -0.2794)
							(mid -0.249642 -0.249642)
							(end -0.2794 -0.1778)
						)
						(arc
							(start -0.2794 0.1778)
							(mid -0.249642 0.249642)
							(end -0.1778 0.2794)
						)
						(arc
							(start 0.1778 0.2794)
							(mid 0.249642 0.249642)
							(end 0.2794 0.1778)
						)
						(arc
							(start 0.2794 -0.1778)
							(mid 0.249642 -0.249642)
							(end 0.1778 -0.2794)
						)
					)
					(width 0)
					(fill yes)
				)
			)
		)
		(pad "2" smd custom
			(at 0 0.4445 180)
			(size 0.1397 0.1397)
			(layers "F.Cu" "F.Mask" "F.Paste")
			(net "PWRGD_P0V975")
			(options
				(clearance outline)
				(anchor circle)
			)
			(primitives
				(gr_poly
					(pts
						(arc
							(start -0.1778 -0.2794)
							(mid -0.249642 -0.249642)
							(end -0.2794 -0.1778)
						)
						(arc
							(start -0.2794 0.1778)
							(mid -0.249642 0.249642)
							(end -0.1778 0.2794)
						)
						(arc
							(start 0.1778 0.2794)
							(mid 0.249642 0.249642)
							(end 0.2794 0.1778)
						)
						(arc
							(start 0.2794 -0.1778)
							(mid 0.249642 -0.249642)
							(end 0.1778 -0.2794)
						)
					)
					(width 0)
					(fill yes)
				)
			)
		)
	)
	(footprint ""
		(layer "F.Cu")
		(at 68.5038 -116.3828 -90)
		(property "Reference" "R268"
			(at 0 0 270)
			(layer "F.SilkS")
			(hide yes)
			(effects
				(font
					(size 1.27 1.27)
				)
			)
		)
		(property "Value" "2K2R2J-2-GP"
			(at 0.064008 -3.993896 270)
			(unlocked yes)
			(layer "F.Fab")
			(hide yes)
			(effects
				(font
					(size 1.016 1.016)
					(thickness 0.1524)
				)
			)
		)
		(property "Device Type" "R402H16"
			(at 0.064008 -5.517896 270)
			(unlocked yes)
			(layer "F.Fab")
			(hide yes)
			(effects
				(font
					(size 1.016 1.016)
					(thickness 0.1524)
				)
			)
		)
		(duplicate_pad_numbers_are_jumpers no)
		(fp_line
			(start -0.508 -0.9398)
			(end -0.508 0.9398)
			(stroke
				(width 0.1524)
				(type default)
			)
			(layer "F.SilkS")
		)
		(fp_line
			(start 0.508 -0.9398)
			(end -0.508 -0.9398)
			(stroke
				(width 0.1524)
				(type default)
			)
			(layer "F.SilkS")
		)
		(fp_rect
			(start -0.508 0.9398)
			(end 0.508 -0.9398)
			(stroke
				(width 0)
				(type default)
			)
			(fill no)
			(layer "F.CrtYd")
		)
		(fp_rect
			(start -0.508 0.9398)
			(end 0.508 -0.9398)
			(stroke
				(width 0)
				(type default)
			)
			(fill no)
			(layer "F.Fab")
		)
		(pad "1" smd custom
			(at 0 -0.4445 270)
			(size 0.1397 0.1397)
			(layers "F.Cu" "F.Mask" "F.Paste")
			(net "P3V3_STBY")
			(options
				(clearance outline)
				(anchor circle)
			)
			(primitives
				(gr_poly
					(pts
						(arc
							(start -0.1778 -0.2794)
							(mid -0.249642 -0.249642)
							(end -0.2794 -0.1778)
						)
						(arc
							(start -0.2794 0.1778)
							(mid -0.249642 0.249642)
							(end -0.1778 0.2794)
						)
						(arc
							(start 0.1778 0.2794)
							(mid 0.249642 0.249642)
							(end 0.2794 0.1778)
						)
						(arc
							(start 0.2794 -0.1778)
							(mid 0.249642 -0.249642)
							(end 0.1778 -0.2794)
						)
					)
					(width 0)
					(fill yes)
				)
			)
		)
		(pad "2" smd custom
			(at 0 0.4445 270)
			(size 0.1397 0.1397)
			(layers "F.Cu" "F.Mask" "F.Paste")
			(net "PU_IBMC_BT_HOLD_N")
			(options
				(clearance outline)
				(anchor circle)
			)
			(primitives
				(gr_poly
					(pts
						(arc
							(start -0.1778 -0.2794)
							(mid -0.249642 -0.249642)
							(end -0.2794 -0.1778)
						)
						(arc
							(start -0.2794 0.1778)
							(mid -0.249642 0.249642)
							(end -0.1778 0.2794)
						)
						(arc
							(start 0.1778 0.2794)
							(mid 0.249642 0.249642)
							(end 0.2794 0.1778)
						)
						(arc
							(start 0.2794 -0.1778)
							(mid 0.249642 -0.249642)
							(end 0.1778 -0.2794)
						)
					)
					(width 0)
					(fill yes)
				)
			)
		)
	)
	(footprint ""
		(layer "F.Cu")
		(at 145.999962 -6.199886)
		(property "Reference" "LED3"
			(at 0 0 0)
			(layer "F.SilkS")
			(hide yes)
			(effects
				(font
					(size 1.27 1.27)
				)
			)
		)
		(property "Value" "LED-BY-14-GP"
			(at -4.7752 -2.1844 0)
			(unlocked yes)
			(layer "F.Fab")
			(hide yes)
			(effects
				(font
					(size 1.016 1.016)
					(thickness 0.1524)
				)
			)
		)
		(property "Device Type" "LED-100-3PH206"
			(at -4.7752 -3.7084 0)
			(unlocked yes)
			(layer "F.Fab")
			(hide yes)
			(effects
				(font
					(size 1.016 1.016)
					(thickness 0.1524)
				)
			)
		)
		(duplicate_pad_numbers_are_jumpers no)
		(fp_line
			(start -3.7592 -1.524)
			(end 3.7592 -1.524)
			(stroke
				(width 0.1524)
				(type default)
			)
			(layer "F.SilkS")
		)
		(fp_line
			(start -3.7592 8.0264)
			(end -3.7592 -1.524)
			(stroke
				(width 0.1524)
				(type default)
			)
			(layer "F.SilkS")
		)
		(fp_line
			(start -1.75387 1.04394)
			(end -1.75387 3.63474)
			(stroke
				(width 0.1524)
				(type default)
			)
			(layer "F.SilkS")
		)
		(fp_line
			(start -1.75387 2.33934)
			(end -3.45567 2.33934)
			(stroke
				(width 0.1524)
				(type default)
			)
			(layer "F.SilkS")
		)
		(fp_line
			(start -1.75387 3.63474)
			(end -0.45847 2.33934)
			(stroke
				(width 0.1524)
				(type default)
			)
			(layer "F.SilkS")
		)
		(fp_line
			(start -0.45847 2.33934)
			(end -1.75387 1.04394)
			(stroke
				(width 0.1524)
				(type default)
			)
			(layer "F.SilkS")
		)
		(fp_line
			(start -0.45847 2.33934)
			(end 0.58293 2.33934)
			(stroke
				(width 0.1524)
				(type default)
			)
			(layer "F.SilkS")
		)
		(fp_line
			(start -0.45847 3.05054)
			(end -0.45847 1.42494)
			(stroke
				(width 0.1524)
				(type default)
			)
			(layer "F.SilkS")
		)
		(fp_line
			(start 0.58293 2.33934)
			(end 1.87833 1.04394)
			(stroke
				(width 0.1524)
				(type default)
			)
			(layer "F.SilkS")
		)
		(fp_line
			(start 0.58293 3.05054)
			(end 0.58293 1.42494)
			(stroke
				(width 0.1524)
				(type default)
			)
			(layer "F.SilkS")
		)
		(fp_line
			(start 1.87833 1.04394)
			(end 1.87833 3.63474)
			(stroke
				(width 0.1524)
				(type default)
			)
			(layer "F.SilkS")
		)
		(fp_line
			(start 1.87833 2.33934)
			(end 2.81813 2.33934)
			(stroke
				(width 0.1524)
				(type default)
			)
			(layer "F.SilkS")
		)
		(fp_line
			(start 1.87833 3.63474)
			(end 0.58293 2.33934)
			(stroke
				(width 0.1524)
				(type default)
			)
			(layer "F.SilkS")
		)
		(fp_line
			(start 3.7592 -1.524)
			(end 3.7592 8.0264)
			(stroke
				(width 0.1524)
				(type default)
			)
			(layer "F.SilkS")
		)
		(fp_line
			(start 3.7592 8.0264)
			(end -3.7592 8.0264)
			(stroke
				(width 0.1524)
				(type default)
			)
			(layer "F.SilkS")
		)
		(fp_circle
			(center -2.54 0)
			(end -1.5494 0)
			(stroke
				(width 0.3048)
				(type default)
			)
			(fill no)
			(layer "F.SilkS")
		)
		(fp_circle
			(center 0 0)
			(end 0.9906 0)
			(stroke
				(width 0.3048)
				(type default)
			)
			(fill no)
			(layer "F.SilkS")
		)
		(fp_circle
			(center 2.54 0)
			(end 3.5306 0)
			(stroke
				(width 0.3048)
				(type default)
			)
			(fill no)
			(layer "F.SilkS")
		)
		(fp_rect
			(start -3.5052 7.7724)
			(end 3.5052 -1.27)
			(stroke
				(width 0)
				(type default)
			)
			(fill no)
			(layer "F.CrtYd")
		)
		(fp_poly
			(pts
				(xy -4.0132 8.2804) (xy -4.0132 -1.778) (xy -3.5052 -1.778) (xy -3.5052 7.7724) (xy 3.5052 7.7724)
				(xy 3.5052 -1.27) (xy -3.50012 -1.27) (xy -3.50012 -1.778) (xy 4.0132 -1.778) (xy 4.0132 8.2804)
			)
			(stroke
				(width 0)
				(type default)
			)
			(fill no)
			(layer "F.CrtYd")
		)
		(fp_rect
			(start -4.0132 8.2804)
			(end 4.0132 -1.778)
			(stroke
				(width 0)
				(type default)
			)
			(fill no)
			(layer "F.Fab")
		)
		(pad "1" thru_hole circle
			(at -2.54 0)
			(size 1.27 1.27)
			(drill 0.889)
			(layers "*.Cu" "*.Mask")
			(remove_unused_layers no)
			(net "EXT2_LED_BLUE")
			(clearance 0.1651)
			(thermal_gap 0.1651)
		)
		(pad "2" thru_hole circle
			(at 0 0)
			(size 1.27 1.27)
			(drill 0.889)
			(layers "*.Cu" "*.Mask")
			(remove_unused_layers no)
			(net "GND")
			(clearance 0.1651)
			(thermal_gap 0.1651)
		)
		(pad "3" thru_hole circle
			(at 2.54 0)
			(size 1.27 1.27)
			(drill 0.889)
			(layers "*.Cu" "*.Mask")
			(remove_unused_layers no)
			(net "EXT2_LED_YELLOW")
			(clearance 0.1651)
			(thermal_gap 0.1651)
		)
	)
	(footprint ""
		(layer "F.Cu")
		(at 46.11116 -163.6903)
		(property "Reference" "TP191"
			(at 0 0 0)
			(layer "F.SilkS")
			(hide yes)
			(effects
				(font
					(size 1.27 1.27)
				)
			)
		)
		(property "Value" "TPAD28-2-GP"
			(at -0.0127 -1.6637 0)
			(unlocked yes)
			(layer "F.Fab")
			(hide yes)
			(effects
				(font
					(size 1.016 1.016)
					(thickness 0.1524)
				)
			)
		)
		(property "Device Type" "TPAD28"
			(at -0.0127 -3.1877 0)
			(unlocked yes)
			(layer "F.Fab")
			(hide yes)
			(effects
				(font
					(size 1.016 1.016)
					(thickness 0.1524)
				)
			)
		)
		(duplicate_pad_numbers_are_jumpers no)
		(fp_poly
			(pts
				(arc
					(start 0.3556 0)
					(mid -0.3556 0)
					(end 0.3556 0)
				)
			)
			(stroke
				(width 0)
				(type default)
			)
			(fill no)
			(layer "F.CrtYd")
		)
		(fp_poly
			(pts
				(arc
					(start 0.6096 0)
					(mid -0.6096 0)
					(end 0.6096 0)
				)
			)
			(stroke
				(width 0)
				(type default)
			)
			(fill no)
			(layer "F.Fab")
		)
		(pad "1" smd circle
			(at 0 0)
			(size 0.7112 0.7112)
			(layers "F.Cu" "F.Mask" "F.Paste")
			(net "TP_BMC_GPIOL5")
		)
	)
	(footprint ""
		(layer "F.Cu")
		(at 76.2508 -150.3426 180)
		(property "Reference" "R307"
			(at 0 0 180)
			(layer "F.SilkS")
			(hide yes)
			(effects
				(font
					(size 1.27 1.27)
				)
			)
		)
		(property "Value" "10KR2F-2-GP"
			(at 0.064008 -3.993896 180)
			(unlocked yes)
			(layer "F.Fab")
			(hide yes)
			(effects
				(font
					(size 1.016 1.016)
					(thickness 0.1524)
				)
			)
		)
		(property "Device Type" "R402H16"
			(at 0.064008 -5.517896 180)
			(unlocked yes)
			(layer "F.Fab")
			(hide yes)
			(effects
				(font
					(size 1.016 1.016)
					(thickness 0.1524)
				)
			)
		)
		(duplicate_pad_numbers_are_jumpers no)
		(fp_line
			(start 0.508 -0.9398)
			(end -0.508 -0.9398)
			(stroke
				(width 0.1524)
				(type default)
			)
			(layer "F.SilkS")
		)
		(fp_line
			(start -0.508 -0.9398)
			(end -0.508 0.9398)
			(stroke
				(width 0.1524)
				(type default)
			)
			(layer "F.SilkS")
		)
		(fp_rect
			(start -0.508 0.9398)
			(end 0.508 -0.9398)
			(stroke
				(width 0)
				(type default)
			)
			(fill no)
			(layer "F.CrtYd")
		)
		(fp_rect
			(start -0.508 0.9398)
			(end 0.508 -0.9398)
			(stroke
				(width 0)
				(type default)
			)
			(fill no)
			(layer "F.Fab")
		)
		(pad "1" smd custom
			(at 0 -0.4445 180)
			(size 0.1397 0.1397)
			(layers "F.Cu" "F.Mask" "F.Paste")
			(net "P3V3_STBY")
			(options
				(clearance outline)
				(anchor circle)
			)
			(primitives
				(gr_poly
					(pts
						(arc
							(start -0.1778 -0.2794)
							(mid -0.249642 -0.249642)
							(end -0.2794 -0.1778)
						)
						(arc
							(start -0.2794 0.1778)
							(mid -0.249642 0.249642)
							(end -0.1778 0.2794)
						)
						(arc
							(start 0.1778 0.2794)
							(mid 0.249642 0.249642)
							(end 0.2794 0.1778)
						)
						(arc
							(start 0.2794 -0.1778)
							(mid 0.249642 -0.249642)
							(end 0.1778 -0.2794)
						)
					)
					(width 0)
					(fill yes)
				)
			)
		)
		(pad "2" smd custom
			(at 0 0.4445 180)
			(size 0.1397 0.1397)
			(layers "F.Cu" "F.Mask" "F.Paste")
			(net "50M_CLK_OE")
			(options
				(clearance outline)
				(anchor circle)
			)
			(primitives
				(gr_poly
					(pts
						(arc
							(start -0.1778 -0.2794)
							(mid -0.249642 -0.249642)
							(end -0.2794 -0.1778)
						)
						(arc
							(start -0.2794 0.1778)
							(mid -0.249642 0.249642)
							(end -0.1778 0.2794)
						)
						(arc
							(start 0.1778 0.2794)
							(mid 0.249642 0.249642)
							(end 0.2794 0.1778)
						)
						(arc
							(start 0.2794 -0.1778)
							(mid 0.249642 -0.249642)
							(end 0.1778 -0.2794)
						)
					)
					(width 0)
					(fill yes)
				)
			)
		)
	)
	(footprint ""
		(layer "F.Cu")
		(at 201.4728 -49.9618)
		(property "Reference" "TP140"
			(at 0 0 0)
			(layer "F.SilkS")
			(hide yes)
			(effects
				(font
					(size 1.27 1.27)
				)
			)
		)
		(property "Value" "TPAD28-2-GP"
			(at -0.0127 -1.6637 0)
			(unlocked yes)
			(layer "F.Fab")
			(hide yes)
			(effects
				(font
					(size 1.016 1.016)
					(thickness 0.1524)
				)
			)
		)
		(property "Device Type" "TPAD28"
			(at -0.0127 -3.1877 0)
			(unlocked yes)
			(layer "F.Fab")
			(hide yes)
			(effects
				(font
					(size 1.016 1.016)
					(thickness 0.1524)
				)
			)
		)
		(duplicate_pad_numbers_are_jumpers no)
		(fp_poly
			(pts
				(arc
					(start 0.3556 0)
					(mid -0.3556 0)
					(end 0.3556 0)
				)
			)
			(stroke
				(width 0)
				(type default)
			)
			(fill no)
			(layer "F.CrtYd")
		)
		(fp_poly
			(pts
				(arc
					(start 0.6096 0)
					(mid -0.6096 0)
					(end 0.6096 0)
				)
			)
			(stroke
				(width 0)
				(type default)
			)
			(fill no)
			(layer "F.Fab")
		)
		(pad "1" smd circle
			(at 0 0)
			(size 0.7112 0.7112)
			(layers "F.Cu" "F.Mask" "F.Paste")
			(net "ICE1_TCK")
		)
	)
	(footprint ""
		(layer "F.Cu")
		(at 157.8864 -38.5064)
		(property "Reference" "TP184"
			(at 0 0 0)
			(layer "F.SilkS")
			(hide yes)
			(effects
				(font
					(size 1.27 1.27)
				)
			)
		)
		(property "Value" "TPAD28-2-GP"
			(at -0.0127 -1.6637 0)
			(unlocked yes)
			(layer "F.Fab")
			(hide yes)
			(effects
				(font
					(size 1.016 1.016)
					(thickness 0.1524)
				)
			)
		)
		(property "Device Type" "TPAD28"
			(at -0.0127 -3.1877 0)
			(unlocked yes)
			(layer "F.Fab")
			(hide yes)
			(effects
				(font
					(size 1.016 1.016)
					(thickness 0.1524)
				)
			)
		)
		(duplicate_pad_numbers_are_jumpers no)
		(fp_poly
			(pts
				(arc
					(start 0.3556 0)
					(mid -0.3556 0)
					(end 0.3556 0)
				)
			)
			(stroke
				(width 0)
				(type default)
			)
			(fill no)
			(layer "F.CrtYd")
		)
		(fp_poly
			(pts
				(arc
					(start 0.6096 0)
					(mid -0.6096 0)
					(end 0.6096 0)
				)
			)
			(stroke
				(width 0)
				(type default)
			)
			(fill no)
			(layer "F.Fab")
		)
		(pad "1" smd circle
			(at 0 0)
			(size 0.7112 0.7112)
			(layers "F.Cu" "F.Mask" "F.Paste")
			(net "ZDEF_EXTB_TP_D2")
		)
	)
	(footprint ""
		(layer "F.Cu")
		(at 45.44568 -123.794012)
		(property "Reference" "R781"
			(at 0 0 0)
			(layer "F.SilkS")
			(hide yes)
			(effects
				(font
					(size 1.27 1.27)
				)
			)
		)
		(property "Value" "0R2J-2-GP"
			(at 0.064008 -3.993896 0)
			(unlocked yes)
			(layer "F.Fab")
			(hide yes)
			(effects
				(font
					(size 1.016 1.016)
					(thickness 0.1524)
				)
			)
		)
		(property "Device Type" "R402H16"
			(at 0.064008 -5.517896 0)
			(unlocked yes)
			(layer "F.Fab")
			(hide yes)
			(effects
				(font
					(size 1.016 1.016)
					(thickness 0.1524)
				)
			)
		)
		(duplicate_pad_numbers_are_jumpers no)
		(fp_line
			(start -0.508 -0.9398)
			(end -0.508 0.9398)
			(stroke
				(width 0.1524)
				(type default)
			)
			(layer "F.SilkS")
		)
		(fp_line
			(start 0.508 -0.9398)
			(end -0.508 -0.9398)
			(stroke
				(width 0.1524)
				(type default)
			)
			(layer "F.SilkS")
		)
		(fp_rect
			(start -0.508 0.9398)
			(end 0.508 -0.9398)
			(stroke
				(width 0)
				(type default)
			)
			(fill no)
			(layer "F.CrtYd")
		)
		(fp_rect
			(start -0.508 0.9398)
			(end 0.508 -0.9398)
			(stroke
				(width 0)
				(type default)
			)
			(fill no)
			(layer "F.Fab")
		)
		(pad "1" smd custom
			(at 0 -0.4445)
			(size 0.1397 0.1397)
			(layers "F.Cu" "F.Mask" "F.Paste")
			(net "FLA_CS_0_R")
			(options
				(clearance outline)
				(anchor circle)
			)
			(primitives
				(gr_poly
					(pts
						(arc
							(start -0.1778 -0.2794)
							(mid -0.249642 -0.249642)
							(end -0.2794 -0.1778)
						)
						(arc
							(start -0.2794 0.1778)
							(mid -0.249642 0.249642)
							(end -0.1778 0.2794)
						)
						(arc
							(start 0.1778 0.2794)
							(mid 0.249642 0.249642)
							(end 0.2794 0.1778)
						)
						(arc
							(start 0.2794 -0.1778)
							(mid 0.249642 -0.249642)
							(end 0.1778 -0.2794)
						)
					)
					(width 0)
					(fill yes)
				)
			)
		)
		(pad "2" smd custom
			(at 0 0.4445)
			(size 0.1397 0.1397)
			(layers "F.Cu" "F.Mask" "F.Paste")
			(net "BMC_CPU_DIS")
			(options
				(clearance outline)
				(anchor circle)
			)
			(primitives
				(gr_poly
					(pts
						(arc
							(start -0.1778 -0.2794)
							(mid -0.249642 -0.249642)
							(end -0.2794 -0.1778)
						)
						(arc
							(start -0.2794 0.1778)
							(mid -0.249642 0.249642)
							(end -0.1778 0.2794)
						)
						(arc
							(start 0.1778 0.2794)
							(mid 0.249642 0.249642)
							(end 0.2794 0.1778)
						)
						(arc
							(start 0.2794 -0.1778)
							(mid 0.249642 -0.249642)
							(end 0.1778 -0.2794)
						)
					)
					(width 0)
					(fill yes)
				)
			)
		)
	)
	(footprint ""
		(layer "F.Cu")
		(at 183.3626 -142.3924 -90)
		(property "Reference" "R472"
			(at 0 0 270)
			(layer "F.SilkS")
			(hide yes)
			(effects
				(font
					(size 1.27 1.27)
				)
			)
		)
		(property "Value" "100KR2F-L1-GP"
			(at 0.064008 -3.993896 270)
			(unlocked yes)
			(layer "F.Fab")
			(hide yes)
			(effects
				(font
					(size 1.016 1.016)
					(thickness 0.1524)
				)
			)
		)
		(property "Device Type" "R402H16"
			(at 0.064008 -5.517896 270)
			(unlocked yes)
			(layer "F.Fab")
			(hide yes)
			(effects
				(font
					(size 1.016 1.016)
					(thickness 0.1524)
				)
			)
		)
		(duplicate_pad_numbers_are_jumpers no)
		(fp_line
			(start -0.508 -0.9398)
			(end -0.508 0.9398)
			(stroke
				(width 0.1524)
				(type default)
			)
			(layer "F.SilkS")
		)
		(fp_line
			(start 0.508 -0.9398)
			(end -0.508 -0.9398)
			(stroke
				(width 0.1524)
				(type default)
			)
			(layer "F.SilkS")
		)
		(fp_rect
			(start -0.508 0.9398)
			(end 0.508 -0.9398)
			(stroke
				(width 0)
				(type default)
			)
			(fill no)
			(layer "F.CrtYd")
		)
		(fp_rect
			(start -0.508 0.9398)
			(end 0.508 -0.9398)
			(stroke
				(width 0)
				(type default)
			)
			(fill no)
			(layer "F.Fab")
		)
		(pad "1" smd custom
			(at 0 -0.4445 270)
			(size 0.1397 0.1397)
			(layers "F.Cu" "F.Mask" "F.Paste")
			(net "AGND_P5V")
			(options
				(clearance outline)
				(anchor circle)
			)
			(primitives
				(gr_poly
					(pts
						(arc
							(start -0.1778 -0.2794)
							(mid -0.249642 -0.249642)
							(end -0.2794 -0.1778)
						)
						(arc
							(start -0.2794 0.1778)
							(mid -0.249642 0.249642)
							(end -0.1778 0.2794)
						)
						(arc
							(start 0.1778 0.2794)
							(mid 0.249642 0.249642)
							(end 0.2794 0.1778)
						)
						(arc
							(start 0.2794 -0.1778)
							(mid 0.249642 -0.249642)
							(end 0.1778 -0.2794)
						)
					)
					(width 0)
					(fill yes)
				)
			)
		)
		(pad "2" smd custom
			(at 0 0.4445 270)
			(size 0.1397 0.1397)
			(layers "F.Cu" "F.Mask" "F.Paste")
			(net "P5V_MODE")
			(options
				(clearance outline)
				(anchor circle)
			)
			(primitives
				(gr_poly
					(pts
						(arc
							(start -0.1778 -0.2794)
							(mid -0.249642 -0.249642)
							(end -0.2794 -0.1778)
						)
						(arc
							(start -0.2794 0.1778)
							(mid -0.249642 0.249642)
							(end -0.1778 0.2794)
						)
						(arc
							(start 0.1778 0.2794)
							(mid 0.249642 0.249642)
							(end 0.2794 0.1778)
						)
						(arc
							(start 0.2794 -0.1778)
							(mid 0.249642 -0.249642)
							(end 0.1778 -0.2794)
						)
					)
					(width 0)
					(fill yes)
				)
			)
		)
	)
	(footprint ""
		(layer "F.Cu")
		(at 37.299646 -174.67961 90)
		(property "Reference" "C184"
			(at 0 0 90)
			(layer "F.SilkS")
			(hide yes)
			(effects
				(font
					(size 1.27 1.27)
				)
			)
		)
		(property "Value" "SC68P50V2JN-2-GP"
			(at 1.1811 -2.7051 90)
			(unlocked yes)
			(layer "F.Fab")
			(hide yes)
			(effects
				(font
					(size 1.016 1.016)
					(thickness 0.1524)
				)
			)
		)
		(property "Device Type" "C402H22"
			(at 1.1811 -4.2291 90)
			(unlocked yes)
			(layer "F.Fab")
			(hide yes)
			(effects
				(font
					(size 1.016 1.016)
					(thickness 0.1524)
				)
			)
		)
		(duplicate_pad_numbers_are_jumpers no)
		(fp_rect
			(start -0.4318 0.9525)
			(end 0.4318 -0.9525)
			(stroke
				(width 0)
				(type default)
			)
			(fill no)
			(layer "F.CrtYd")
		)
		(fp_rect
			(start -0.4318 0.9525)
			(end 0.4318 -0.9525)
			(stroke
				(width 0)
				(type default)
			)
			(fill no)
			(layer "F.Fab")
		)
		(pad "1" smd custom
			(at 0 -0.4445 90)
			(size 0.1524 0.1524)
			(layers "F.Cu" "F.Mask" "F.Paste")
			(net "P3V3_STBY_VFB")
			(options
				(clearance outline)
				(anchor circle)
			)
			(primitives
				(gr_poly
					(pts
						(arc
							(start 0.3048 -0.2032)
							(mid 0.275042 -0.275042)
							(end 0.2032 -0.3048)
						)
						(arc
							(start -0.2032 -0.3048)
							(mid -0.275042 -0.275042)
							(end -0.3048 -0.2032)
						)
						(arc
							(start -0.3048 0.2032)
							(mid -0.275042 0.275042)
							(end -0.2032 0.3048)
						)
						(arc
							(start 0.2032 0.3048)
							(mid 0.275042 0.275042)
							(end 0.3048 0.2032)
						)
					)
					(width 0)
					(fill yes)
				)
			)
		)
		(pad "2" smd custom
			(at 0 0.4445 90)
			(size 0.1524 0.1524)
			(layers "F.Cu" "F.Mask" "F.Paste")
			(net "P3V3_STBY_VFB_R")
			(options
				(clearance outline)
				(anchor circle)
			)
			(primitives
				(gr_poly
					(pts
						(arc
							(start 0.3048 -0.2032)
							(mid 0.275042 -0.275042)
							(end 0.2032 -0.3048)
						)
						(arc
							(start -0.2032 -0.3048)
							(mid -0.275042 -0.275042)
							(end -0.3048 -0.2032)
						)
						(arc
							(start -0.3048 0.2032)
							(mid -0.275042 0.275042)
							(end -0.2032 0.3048)
						)
						(arc
							(start 0.2032 0.3048)
							(mid 0.275042 0.275042)
							(end 0.3048 0.2032)
						)
					)
					(width 0)
					(fill yes)
				)
			)
		)
	)
	(footprint ""
		(layer "F.Cu")
		(at 61.468 -149.5806 90)
		(property "Reference" "R338"
			(at 0 0 90)
			(layer "F.SilkS")
			(hide yes)
			(effects
				(font
					(size 1.27 1.27)
				)
			)
		)
		(property "Value" "8K2R2J-3-GP"
			(at 0.063754 -3.993896 90)
			(unlocked yes)
			(layer "F.Fab")
			(hide yes)
			(effects
				(font
					(size 1.016 1.016)
					(thickness 0.1524)
				)
			)
		)
		(property "Device Type" "R402H16"
			(at 0.063754 -5.517896 90)
			(unlocked yes)
			(layer "F.Fab")
			(hide yes)
			(effects
				(font
					(size 1.016 1.016)
					(thickness 0.1524)
				)
			)
		)
		(duplicate_pad_numbers_are_jumpers no)
		(fp_line
			(start 0.508 -0.9398)
			(end -0.508 -0.9398)
			(stroke
				(width 0.1524)
				(type default)
			)
			(layer "F.SilkS")
		)
		(fp_line
			(start -0.508 -0.9398)
			(end -0.508 0.9398)
			(stroke
				(width 0.1524)
				(type default)
			)
			(layer "F.SilkS")
		)
		(fp_rect
			(start -0.508 0.9398)
			(end 0.508 -0.9398)
			(stroke
				(width 0)
				(type default)
			)
			(fill no)
			(layer "F.CrtYd")
		)
		(fp_rect
			(start -0.508 0.9398)
			(end 0.508 -0.9398)
			(stroke
				(width 0)
				(type default)
			)
			(fill no)
			(layer "F.Fab")
		)
		(pad "1" smd custom
			(at 0 -0.4445 90)
			(size 0.1397 0.1397)
			(layers "F.Cu" "F.Mask" "F.Paste")
			(net "PD_USB2AVRES")
			(options
				(clearance outline)
				(anchor circle)
			)
			(primitives
				(gr_poly
					(pts
						(arc
							(start -0.1778 -0.2794)
							(mid -0.249642 -0.249642)
							(end -0.2794 -0.1778)
						)
						(arc
							(start -0.2794 0.1778)
							(mid -0.249642 0.249642)
							(end -0.1778 0.2794)
						)
						(arc
							(start 0.1778 0.2794)
							(mid 0.249642 0.249642)
							(end 0.2794 0.1778)
						)
						(arc
							(start 0.2794 -0.1778)
							(mid 0.249642 -0.249642)
							(end 0.1778 -0.2794)
						)
					)
					(width 0)
					(fill yes)
				)
			)
		)
		(pad "2" smd custom
			(at 0 0.4445 90)
			(size 0.1397 0.1397)
			(layers "F.Cu" "F.Mask" "F.Paste")
			(net "GND")
			(options
				(clearance outline)
				(anchor circle)
			)
			(primitives
				(gr_poly
					(pts
						(arc
							(start -0.1778 -0.2794)
							(mid -0.249642 -0.249642)
							(end -0.2794 -0.1778)
						)
						(arc
							(start -0.2794 0.1778)
							(mid -0.249642 0.249642)
							(end -0.1778 0.2794)
						)
						(arc
							(start 0.1778 0.2794)
							(mid 0.249642 0.249642)
							(end 0.2794 0.1778)
						)
						(arc
							(start 0.2794 -0.1778)
							(mid 0.249642 -0.249642)
							(end 0.1778 -0.2794)
						)
					)
					(width 0)
					(fill yes)
				)
			)
		)
	)
	(footprint ""
		(layer "F.Cu")
		(at 194.136772 -88.6968 135)
		(property "Reference" "VIA22"
			(at 0 0 135)
			(layer "F.SilkS")
			(hide yes)
			(effects
				(font
					(size 1.27 1.27)
				)
			)
		)
		(property "Value" "85OHM-8L-1D6MM-L16L18-GP"
			(at 4.064105 0.609655 135)
			(unlocked yes)
			(layer "F.Fab")
			(hide yes)
			(effects
				(font
					(size 1.016 1.016)
					(thickness 0.1524)
				)
			)
		)
		(property "Device Type" "VIA-PCIE-4P-368076"
			(at 4.064105 -0.914474 135)
			(unlocked yes)
			(layer "F.Fab")
			(hide yes)
			(effects
				(font
					(size 1.016 1.016)
					(thickness 0.1524)
				)
			)
		)
		(duplicate_pad_numbers_are_jumpers no)
		(fp_poly
			(pts
				(xy -1.841491 -0.381057) (xy 1.841509 -0.381058) (xy 1.841508 0.380942) (xy -1.841491 0.380942)
			)
			(stroke
				(width 0)
				(type default)
			)
			(fill no)
			(layer "F.CrtYd")
		)
		(fp_poly
			(pts
				(xy -1.841491 -0.381057) (xy 1.841509 -0.381058) (xy 1.841508 0.380942) (xy -1.841491 0.380942)
			)
			(stroke
				(width 0)
				(type default)
			)
			(fill no)
			(layer "F.Fab")
		)
		(pad "1" thru_hole circle
			(at -1.460499 0 135)
			(size 0.508 0.508)
			(drill 0.254)
			(layers "*.Cu" "*.Mask")
			(remove_unused_layers no)
			(net "GND")
			(clearance 0.127)
			(thermal_gap 0.127)
		)
		(pad "2" thru_hole circle
			(at -0.4445 0 135)
			(size 0.508 0.508)
			(drill 0.254)
			(layers "*.Cu" "*.Mask")
			(remove_unused_layers no)
			(net "PCIE_COMP_TO_IOM_12_DP")
			(clearance 0.127)
			(thermal_gap 0.127)
		)
		(pad "3" thru_hole circle
			(at 0.4445 0 135)
			(size 0.508 0.508)
			(drill 0.254)
			(layers "*.Cu" "*.Mask")
			(remove_unused_layers no)
			(net "PCIE_COMP_TO_IOM_12_DN")
			(clearance 0.127)
			(thermal_gap 0.127)
		)
		(pad "4" thru_hole circle
			(at 1.460499 0 135)
			(size 0.508 0.508)
			(drill 0.254)
			(layers "*.Cu" "*.Mask")
			(remove_unused_layers no)
			(net "GND")
			(clearance 0.127)
			(thermal_gap 0.127)
		)
	)
	(footprint ""
		(layer "F.Cu")
		(at 155.499816 -187.999878)
		(property "Reference" ""
			(at 0 0 0)
			(layer "F.SilkS")
			(hide yes)
			(effects
				(font
					(size 1.27 1.27)
				)
			)
		)
		(property "Value" "*"
			(at -6.38175 0.19685 0)
			(unlocked yes)
			(layer "F.Fab")
			(hide yes)
			(effects
				(font
					(size 1.016 1.016)
					(thickness 0.1524)
				)
			)
		)
		(duplicate_pad_numbers_are_jumpers no)
		(fp_poly
			(pts
				(arc
					(start 5.0673 0)
					(mid -5.0673 0)
					(end 5.0673 0)
				)
			)
			(stroke
				(width 0)
				(type default)
			)
			(fill no)
			(layer "B.CrtYd")
		)
		(fp_poly
			(pts
				(arc
					(start 5.0673 0)
					(mid -5.0673 0)
					(end 5.0673 0)
				)
			)
			(stroke
				(width 0)
				(type default)
			)
			(fill no)
			(layer "F.CrtYd")
		)
		(fp_poly
			(pts
				(arc
					(start 5.0673 0)
					(mid -5.0673 0)
					(end 5.0673 0)
				)
			)
			(stroke
				(width 0)
				(type default)
			)
			(fill no)
			(layer "B.Fab")
		)
		(fp_poly
			(pts
				(arc
					(start 5.0673 0)
					(mid -5.0673 0)
					(end 5.0673 0)
				)
			)
			(stroke
				(width 0)
				(type default)
			)
			(fill no)
			(layer "F.Fab")
		)
		(pad "1" thru_hole circle
			(at 0 0)
			(size 9.525 9.525)
			(drill 3.5052)
			(layers "*.Cu" "*.Mask")
			(remove_unused_layers no)
			(net "Net_13")
			(clearance -2.5019)
			(thermal_gap 0.3048)
			(padstack
				(mode front_inner_back)
				(layer "Inner"
					(shape circle)
					(size 3.9116 3.9116)
					(clearance 0.3048)
				)
				(layer "B.Cu"
					(shape circle)
					(size 9.525 9.525)
					(clearance -2.5019)
				)
			)
		)
	)
	(footprint ""
		(layer "F.Cu")
		(at 68.4784 -134.5692)
		(property "Reference" "R52"
			(at 0 0 0)
			(layer "F.SilkS")
			(hide yes)
			(effects
				(font
					(size 1.27 1.27)
				)
			)
		)
		(property "Value" "33R2F-3-GP"
			(at 0.064008 -3.993896 0)
			(unlocked yes)
			(layer "F.Fab")
			(hide yes)
			(effects
				(font
					(size 1.016 1.016)
					(thickness 0.1524)
				)
			)
		)
		(property "Device Type" "R402H16"
			(at 0.064008 -5.517896 0)
			(unlocked yes)
			(layer "F.Fab")
			(hide yes)
			(effects
				(font
					(size 1.016 1.016)
					(thickness 0.1524)
				)
			)
		)
		(duplicate_pad_numbers_are_jumpers no)
		(fp_line
			(start -0.508 -0.9398)
			(end -0.508 0.9398)
			(stroke
				(width 0.1524)
				(type default)
			)
			(layer "F.SilkS")
		)
		(fp_line
			(start 0.508 -0.9398)
			(end -0.508 -0.9398)
			(stroke
				(width 0.1524)
				(type default)
			)
			(layer "F.SilkS")
		)
		(fp_rect
			(start -0.508 0.9398)
			(end 0.508 -0.9398)
			(stroke
				(width 0)
				(type default)
			)
			(fill no)
			(layer "F.CrtYd")
		)
		(fp_rect
			(start -0.508 0.9398)
			(end 0.508 -0.9398)
			(stroke
				(width 0)
				(type default)
			)
			(fill no)
			(layer "F.Fab")
		)
		(pad "1" smd custom
			(at 0 -0.4445)
			(size 0.1397 0.1397)
			(layers "F.Cu" "F.Mask" "F.Paste")
			(net "FP_PWRBTN")
			(options
				(clearance outline)
				(anchor circle)
			)
			(primitives
				(gr_poly
					(pts
						(arc
							(start -0.1778 -0.2794)
							(mid -0.249642 -0.249642)
							(end -0.2794 -0.1778)
						)
						(arc
							(start -0.2794 0.1778)
							(mid -0.249642 0.249642)
							(end -0.1778 0.2794)
						)
						(arc
							(start 0.1778 0.2794)
							(mid 0.249642 0.249642)
							(end 0.2794 0.1778)
						)
						(arc
							(start 0.2794 -0.1778)
							(mid 0.249642 -0.249642)
							(end 0.1778 -0.2794)
						)
					)
					(width 0)
					(fill yes)
				)
			)
		)
		(pad "2" smd custom
			(at 0 0.4445)
			(size 0.1397 0.1397)
			(layers "F.Cu" "F.Mask" "F.Paste")
			(net "PWRBTN_OUT_N")
			(options
				(clearance outline)
				(anchor circle)
			)
			(primitives
				(gr_poly
					(pts
						(arc
							(start -0.1778 -0.2794)
							(mid -0.249642 -0.249642)
							(end -0.2794 -0.1778)
						)
						(arc
							(start -0.2794 0.1778)
							(mid -0.249642 0.249642)
							(end -0.1778 0.2794)
						)
						(arc
							(start 0.1778 0.2794)
							(mid 0.249642 0.249642)
							(end 0.2794 0.1778)
						)
						(arc
							(start 0.2794 -0.1778)
							(mid 0.249642 -0.249642)
							(end 0.1778 -0.2794)
						)
					)
					(width 0)
					(fill yes)
				)
			)
		)
	)
	(footprint ""
		(layer "F.Cu")
		(at 63.04661 -156.181298 180)
		(property "Reference" "R387"
			(at 0 0 180)
			(layer "F.SilkS")
			(hide yes)
			(effects
				(font
					(size 1.27 1.27)
				)
			)
		)
		(property "Value" "4K7R2F-GP"
			(at 0.064008 -3.993896 180)
			(unlocked yes)
			(layer "F.Fab")
			(hide yes)
			(effects
				(font
					(size 1.016 1.016)
					(thickness 0.1524)
				)
			)
		)
		(property "Device Type" "R402H16"
			(at 0.064008 -5.517896 180)
			(unlocked yes)
			(layer "F.Fab")
			(hide yes)
			(effects
				(font
					(size 1.016 1.016)
					(thickness 0.1524)
				)
			)
		)
		(duplicate_pad_numbers_are_jumpers no)
		(fp_line
			(start 0.508 -0.9398)
			(end -0.508 -0.9398)
			(stroke
				(width 0.1524)
				(type default)
			)
			(layer "F.SilkS")
		)
		(fp_line
			(start -0.508 -0.9398)
			(end -0.508 0.9398)
			(stroke
				(width 0.1524)
				(type default)
			)
			(layer "F.SilkS")
		)
		(fp_rect
			(start -0.508 0.9398)
			(end 0.508 -0.9398)
			(stroke
				(width 0)
				(type default)
			)
			(fill no)
			(layer "F.CrtYd")
		)
		(fp_rect
			(start -0.508 0.9398)
			(end 0.508 -0.9398)
			(stroke
				(width 0)
				(type default)
			)
			(fill no)
			(layer "F.Fab")
		)
		(pad "1" smd custom
			(at 0 -0.4445 180)
			(size 0.1397 0.1397)
			(layers "F.Cu" "F.Mask" "F.Paste")
			(net "GND")
			(options
				(clearance outline)
				(anchor circle)
			)
			(primitives
				(gr_poly
					(pts
						(arc
							(start -0.1778 -0.2794)
							(mid -0.249642 -0.249642)
							(end -0.2794 -0.1778)
						)
						(arc
							(start -0.2794 0.1778)
							(mid -0.249642 0.249642)
							(end -0.1778 0.2794)
						)
						(arc
							(start 0.1778 0.2794)
							(mid 0.249642 0.249642)
							(end 0.2794 0.1778)
						)
						(arc
							(start 0.2794 -0.1778)
							(mid 0.249642 -0.249642)
							(end 0.1778 -0.2794)
						)
					)
					(width 0)
					(fill yes)
				)
			)
		)
		(pad "2" smd custom
			(at 0 0.4445 180)
			(size 0.1397 0.1397)
			(layers "F.Cu" "F.Mask" "F.Paste")
			(net "NCSI_TXD1")
			(options
				(clearance outline)
				(anchor circle)
			)
			(primitives
				(gr_poly
					(pts
						(arc
							(start -0.1778 -0.2794)
							(mid -0.249642 -0.249642)
							(end -0.2794 -0.1778)
						)
						(arc
							(start -0.2794 0.1778)
							(mid -0.249642 0.249642)
							(end -0.1778 0.2794)
						)
						(arc
							(start 0.1778 0.2794)
							(mid 0.249642 0.249642)
							(end 0.2794 0.1778)
						)
						(arc
							(start 0.2794 -0.1778)
							(mid 0.249642 -0.249642)
							(end 0.1778 -0.2794)
						)
					)
					(width 0)
					(fill yes)
				)
			)
		)
	)
	(footprint ""
		(layer "F.Cu")
		(at 208.055972 -66.6496 90)
		(property "Reference" "C319"
			(at 0 0 90)
			(layer "F.SilkS")
			(hide yes)
			(effects
				(font
					(size 1.27 1.27)
				)
			)
		)
		(property "Value" "SCD01U16V1KX-GP"
			(at -2.8321 -1.7399 90)
			(unlocked yes)
			(layer "F.Fab")
			(hide yes)
			(effects
				(font
					(size 1.016 1.016)
					(thickness 0.1524)
				)
			)
		)
		(property "Device Type" "C0201H13"
			(at -2.8321 -3.2639 90)
			(unlocked yes)
			(layer "F.Fab")
			(hide yes)
			(effects
				(font
					(size 1.016 1.016)
					(thickness 0.1524)
				)
			)
		)
		(duplicate_pad_numbers_are_jumpers no)
		(fp_rect
			(start -0.2794 0.6477)
			(end 0.2794 -0.6477)
			(stroke
				(width 0)
				(type default)
			)
			(fill no)
			(layer "F.CrtYd")
		)
		(fp_rect
			(start -0.2794 0.6477)
			(end 0.2794 -0.6477)
			(stroke
				(width 0)
				(type default)
			)
			(fill no)
			(layer "F.Fab")
		)
		(pad "1" smd custom
			(at 0 -0.2794 90)
			(size 0.0762 0.0762)
			(layers "F.Cu" "F.Mask" "F.Paste")
			(net "PHY_IOC_TO_CON_B_2_DP_C")
			(options
				(clearance outline)
				(anchor circle)
			)
			(primitives
				(gr_poly
					(pts
						(arc
							(start 0.1524 -0.127)
							(mid 0.137521 -0.162921)
							(end 0.1016 -0.1778)
						)
						(arc
							(start -0.1016 -0.1778)
							(mid -0.137521 -0.162921)
							(end -0.1524 -0.127)
						)
						(arc
							(start -0.1524 0.127)
							(mid -0.137521 0.162921)
							(end -0.1016 0.1778)
						)
						(arc
							(start 0.1016 0.1778)
							(mid 0.137521 0.162921)
							(end 0.1524 0.127)
						)
					)
					(width 0)
					(fill yes)
				)
			)
		)
		(pad "2" smd custom
			(at 0 0.2794 90)
			(size 0.0762 0.0762)
			(layers "F.Cu" "F.Mask" "F.Paste")
			(net "PHY_IOC_TO_CON_B_2_DP")
			(options
				(clearance outline)
				(anchor circle)
			)
			(primitives
				(gr_poly
					(pts
						(arc
							(start 0.1524 -0.127)
							(mid 0.137521 -0.162921)
							(end 0.1016 -0.1778)
						)
						(arc
							(start -0.1016 -0.1778)
							(mid -0.137521 -0.162921)
							(end -0.1524 -0.127)
						)
						(arc
							(start -0.1524 0.127)
							(mid -0.137521 0.162921)
							(end -0.1016 0.1778)
						)
						(arc
							(start 0.1016 0.1778)
							(mid 0.137521 0.162921)
							(end 0.1524 0.127)
						)
					)
					(width 0)
					(fill yes)
				)
			)
		)
	)
	(footprint ""
		(layer "F.Cu")
		(at 174.560738 -68.38442 90)
		(property "Reference" "R585"
			(at 0 0 90)
			(layer "F.SilkS")
			(hide yes)
			(effects
				(font
					(size 1.27 1.27)
				)
			)
		)
		(property "Value" "2K2R2F-GP"
			(at 0.064008 -3.993896 90)
			(unlocked yes)
			(layer "F.Fab")
			(hide yes)
			(effects
				(font
					(size 1.016 1.016)
					(thickness 0.1524)
				)
			)
		)
		(property "Device Type" "R402H16"
			(at 0.064008 -5.517896 90)
			(unlocked yes)
			(layer "F.Fab")
			(hide yes)
			(effects
				(font
					(size 1.016 1.016)
					(thickness 0.1524)
				)
			)
		)
		(duplicate_pad_numbers_are_jumpers no)
		(fp_line
			(start 0.508 -0.9398)
			(end -0.508 -0.9398)
			(stroke
				(width 0.1524)
				(type default)
			)
			(layer "F.SilkS")
		)
		(fp_line
			(start -0.508 -0.9398)
			(end -0.508 0.9398)
			(stroke
				(width 0.1524)
				(type default)
			)
			(layer "F.SilkS")
		)
		(fp_rect
			(start -0.508 0.9398)
			(end 0.508 -0.9398)
			(stroke
				(width 0)
				(type default)
			)
			(fill no)
			(layer "F.CrtYd")
		)
		(fp_rect
			(start -0.508 0.9398)
			(end 0.508 -0.9398)
			(stroke
				(width 0)
				(type default)
			)
			(fill no)
			(layer "F.Fab")
		)
		(pad "1" smd custom
			(at 0 -0.4445 90)
			(size 0.1397 0.1397)
			(layers "F.Cu" "F.Mask" "F.Paste")
			(net "P1V8")
			(options
				(clearance outline)
				(anchor circle)
			)
			(primitives
				(gr_poly
					(pts
						(arc
							(start -0.1778 -0.2794)
							(mid -0.249642 -0.249642)
							(end -0.2794 -0.1778)
						)
						(arc
							(start -0.2794 0.1778)
							(mid -0.249642 0.249642)
							(end -0.1778 0.2794)
						)
						(arc
							(start 0.1778 0.2794)
							(mid 0.249642 0.249642)
							(end 0.2794 0.1778)
						)
						(arc
							(start 0.2794 -0.1778)
							(mid 0.249642 -0.249642)
							(end 0.1778 -0.2794)
						)
					)
					(width 0)
					(fill yes)
				)
			)
		)
		(pad "2" smd custom
			(at 0 0.4445 90)
			(size 0.1397 0.1397)
			(layers "F.Cu" "F.Mask" "F.Paste")
			(net "IOC_SDA_3")
			(options
				(clearance outline)
				(anchor circle)
			)
			(primitives
				(gr_poly
					(pts
						(arc
							(start -0.1778 -0.2794)
							(mid -0.249642 -0.249642)
							(end -0.2794 -0.1778)
						)
						(arc
							(start -0.2794 0.1778)
							(mid -0.249642 0.249642)
							(end -0.1778 0.2794)
						)
						(arc
							(start 0.1778 0.2794)
							(mid 0.249642 0.249642)
							(end 0.2794 0.1778)
						)
						(arc
							(start 0.2794 -0.1778)
							(mid 0.249642 -0.249642)
							(end 0.1778 -0.2794)
						)
					)
					(width 0)
					(fill yes)
				)
			)
		)
	)
	(footprint ""
		(layer "F.Cu")
		(at 154.09164 -134.249922 90)
		(property "Reference" "R520"
			(at 0 0 90)
			(layer "F.SilkS")
			(hide yes)
			(effects
				(font
					(size 1.27 1.27)
				)
			)
		)
		(property "Value" "3D01R5F-GP"
			(at 0 -8.9535 90)
			(unlocked yes)
			(layer "F.Fab")
			(hide yes)
			(effects
				(font
					(size 1.27 1.016)
					(thickness 0.1524)
				)
			)
		)
		(property "Device Type" "R805H24"
			(at 0 -10.6299 90)
			(unlocked yes)
			(layer "F.Fab")
			(hide yes)
			(effects
				(font
					(size 1.27 1.016)
					(thickness 0.1524)
				)
			)
		)
		(duplicate_pad_numbers_are_jumpers no)
		(fp_line
			(start 0.889 -1.7018)
			(end -0.889 -1.7018)
			(stroke
				(width 0.1524)
				(type default)
			)
			(layer "F.SilkS")
		)
		(fp_line
			(start 0.889 -1.7018)
			(end 0.889 -0.381)
			(stroke
				(width 0.1524)
				(type default)
			)
			(layer "F.SilkS")
		)
		(fp_line
			(start -0.889 -1.7018)
			(end -0.889 0.2794)
			(stroke
				(width 0.1524)
				(type default)
			)
			(layer "F.SilkS")
		)
		(fp_line
			(start -0.889 0.0762)
			(end -0.889 1.7018)
			(stroke
				(width 0.1524)
				(type default)
			)
			(layer "F.SilkS")
		)
		(fp_line
			(start 0.889 1.7018)
			(end 0.889 -0.508)
			(stroke
				(width 0.1524)
				(type default)
			)
			(layer "F.SilkS")
		)
		(fp_line
			(start -0.889 1.7018)
			(end 0.889 1.7018)
			(stroke
				(width 0.1524)
				(type default)
			)
			(layer "F.SilkS")
		)
		(fp_poly
			(pts
				(xy 0.9652 -1.778) (xy 0.9652 1.778) (xy -0.9652 1.778) (xy -0.9652 -1.778)
			)
			(stroke
				(width 0)
				(type default)
			)
			(fill no)
			(layer "F.CrtYd")
		)
		(fp_rect
			(start -0.9652 1.778)
			(end 0.9652 -1.778)
			(stroke
				(width 0)
				(type default)
			)
			(fill no)
			(layer "F.Fab")
		)
		(pad "1" smd rect
			(at 0 -0.9652 90)
			(size 1.397 1.143)
			(layers "F.Cu" "F.Mask" "F.Paste")
			(net "P1V8_STBY_SNB")
		)
		(pad "2" smd rect
			(at 0 0.9652 90)
			(size 1.397 1.143)
			(layers "F.Cu" "F.Mask" "F.Paste")
			(net "GND")
		)
	)
	(footprint ""
		(layer "F.Cu")
		(at 190.4746 -48.3616 180)
		(property "Reference" "R640"
			(at 0 0 180)
			(layer "F.SilkS")
			(hide yes)
			(effects
				(font
					(size 1.27 1.27)
				)
			)
		)
		(property "Value" "4K7R2F-GP"
			(at 0.064008 -3.993896 180)
			(unlocked yes)
			(layer "F.Fab")
			(hide yes)
			(effects
				(font
					(size 1.016 1.016)
					(thickness 0.1524)
				)
			)
		)
		(property "Device Type" "R402H16"
			(at 0.064008 -5.517896 180)
			(unlocked yes)
			(layer "F.Fab")
			(hide yes)
			(effects
				(font
					(size 1.016 1.016)
					(thickness 0.1524)
				)
			)
		)
		(duplicate_pad_numbers_are_jumpers no)
		(fp_line
			(start 0.508 -0.9398)
			(end -0.508 -0.9398)
			(stroke
				(width 0.1524)
				(type default)
			)
			(layer "F.SilkS")
		)
		(fp_line
			(start -0.508 -0.9398)
			(end -0.508 0.9398)
			(stroke
				(width 0.1524)
				(type default)
			)
			(layer "F.SilkS")
		)
		(fp_rect
			(start -0.508 0.9398)
			(end 0.508 -0.9398)
			(stroke
				(width 0)
				(type default)
			)
			(fill no)
			(layer "F.CrtYd")
		)
		(fp_rect
			(start -0.508 0.9398)
			(end 0.508 -0.9398)
			(stroke
				(width 0)
				(type default)
			)
			(fill no)
			(layer "F.Fab")
		)
		(pad "1" smd custom
			(at 0 -0.4445 180)
			(size 0.1397 0.1397)
			(layers "F.Cu" "F.Mask" "F.Paste")
			(net "P1V8")
			(options
				(clearance outline)
				(anchor circle)
			)
			(primitives
				(gr_poly
					(pts
						(arc
							(start -0.1778 -0.2794)
							(mid -0.249642 -0.249642)
							(end -0.2794 -0.1778)
						)
						(arc
							(start -0.2794 0.1778)
							(mid -0.249642 0.249642)
							(end -0.1778 0.2794)
						)
						(arc
							(start 0.1778 0.2794)
							(mid 0.249642 0.249642)
							(end 0.2794 0.1778)
						)
						(arc
							(start 0.2794 -0.1778)
							(mid 0.249642 -0.249642)
							(end 0.1778 -0.2794)
						)
					)
					(width 0)
					(fill yes)
				)
			)
		)
		(pad "2" smd custom
			(at 0 0.4445 180)
			(size 0.1397 0.1397)
			(layers "F.Cu" "F.Mask" "F.Paste")
			(net "LSI_SCAN_EN")
			(options
				(clearance outline)
				(anchor circle)
			)
			(primitives
				(gr_poly
					(pts
						(arc
							(start -0.1778 -0.2794)
							(mid -0.249642 -0.249642)
							(end -0.2794 -0.1778)
						)
						(arc
							(start -0.2794 0.1778)
							(mid -0.249642 0.249642)
							(end -0.1778 0.2794)
						)
						(arc
							(start 0.1778 0.2794)
							(mid 0.249642 0.249642)
							(end 0.2794 0.1778)
						)
						(arc
							(start 0.2794 -0.1778)
							(mid 0.249642 -0.249642)
							(end 0.1778 -0.2794)
						)
					)
					(width 0)
					(fill yes)
				)
			)
		)
	)
	(footprint ""
		(layer "F.Cu")
		(at 94.765876 -20.34413 90)
		(property "Reference" "D16"
			(at 0 0 90)
			(layer "F.SilkS")
			(hide yes)
			(effects
				(font
					(size 1.27 1.27)
				)
			)
		)
		(property "Value" "PESD5V0S1BL-1-GP"
			(at 1.8923 -1.5621 90)
			(unlocked yes)
			(layer "F.Fab")
			(hide yes)
			(effects
				(font
					(size 1.016 1.016)
					(thickness 0.1524)
				)
			)
		)
		(property "Device Type" "SOD882-10D6-1H20"
			(at 1.8923 -3.0861 90)
			(unlocked yes)
			(layer "F.Fab")
			(hide yes)
			(effects
				(font
					(size 1.016 1.016)
					(thickness 0.1524)
				)
			)
		)
		(duplicate_pad_numbers_are_jumpers no)
		(fp_line
			(start -0.3048 -0.9271)
			(end 0.3048 -0.9271)
			(stroke
				(width 0.254)
				(type default)
			)
			(layer "F.SilkS")
		)
		(fp_rect
			(start -0.2921 0.4953)
			(end 0.2921 -0.4953)
			(stroke
				(width 0)
				(type default)
			)
			(fill no)
			(layer "F.CrtYd")
		)
		(fp_poly
			(pts
				(xy -0.4318 0.8001) (xy -0.4318 -0.266192) (xy -0.2921 -0.266192) (xy -0.2921 0.4953) (xy 0.2921 0.4953)
				(xy 0.2921 -0.4953) (xy -0.2921 -0.4953) (xy -0.2921 -0.2667) (xy -0.4318 -0.2667) (xy -0.4318 -0.8001)
				(xy 0.4318 -0.8001) (xy 0.4318 0.8001)
			)
			(stroke
				(width 0)
				(type default)
			)
			(fill no)
			(layer "F.CrtYd")
		)
		(fp_rect
			(start -0.4318 0.8001)
			(end 0.4318 -0.8001)
			(stroke
				(width 0)
				(type default)
			)
			(fill no)
			(layer "F.Fab")
		)
		(pad "1" smd custom
			(at 0 -0.4445 90)
			(size 0.1143 0.1143)
			(layers "F.Cu" "F.Mask" "F.Paste")
			(net "UART_IOM_TX")
			(options
				(clearance outline)
				(anchor circle)
			)
			(primitives
				(gr_poly
					(pts
						(arc
							(start -0.2032 0.2286)
							(mid -0.275042 0.198842)
							(end -0.3048 0.127)
						)
						(arc
							(start -0.3048 -0.127)
							(mid -0.275042 -0.198842)
							(end -0.2032 -0.2286)
						)
						(arc
							(start 0.2032 -0.2286)
							(mid 0.275042 -0.198842)
							(end 0.3048 -0.127)
						)
						(arc
							(start 0.3048 0.127)
							(mid 0.275042 0.198842)
							(end 0.2032 0.2286)
						)
					)
					(width 0)
					(fill yes)
				)
			)
		)
		(pad "2" smd custom
			(at 0 0.4445 90)
			(size 0.1143 0.1143)
			(layers "F.Cu" "F.Mask" "F.Paste")
			(net "GND")
			(options
				(clearance outline)
				(anchor circle)
			)
			(primitives
				(gr_poly
					(pts
						(arc
							(start 0.2032 -0.2286)
							(mid 0.275042 -0.198842)
							(end 0.3048 -0.127)
						)
						(arc
							(start 0.3048 0.127)
							(mid 0.275042 0.198842)
							(end 0.2032 0.2286)
						)
						(arc
							(start -0.2032 0.2286)
							(mid -0.275042 0.198842)
							(end -0.3048 0.127)
						)
						(arc
							(start -0.3048 -0.127)
							(mid -0.275042 -0.198842)
							(end -0.2032 -0.2286)
						)
					)
					(width 0)
					(fill yes)
				)
			)
		)
	)
	(footprint ""
		(layer "F.Cu")
		(at 110.71479 -9.666478 -90)
		(property "Reference" "R454"
			(at 0 0 270)
			(layer "F.SilkS")
			(hide yes)
			(effects
				(font
					(size 1.27 1.27)
				)
			)
		)
		(property "Value" "51KR2F-L-GP"
			(at 0.064008 -3.993896 270)
			(unlocked yes)
			(layer "F.Fab")
			(hide yes)
			(effects
				(font
					(size 1.016 1.016)
					(thickness 0.1524)
				)
			)
		)
		(property "Device Type" "R402H16"
			(at 0.064008 -5.517896 270)
			(unlocked yes)
			(layer "F.Fab")
			(hide yes)
			(effects
				(font
					(size 1.016 1.016)
					(thickness 0.1524)
				)
			)
		)
		(duplicate_pad_numbers_are_jumpers no)
		(fp_line
			(start -0.508 -0.9398)
			(end -0.508 0.9398)
			(stroke
				(width 0.1524)
				(type default)
			)
			(layer "F.SilkS")
		)
		(fp_line
			(start 0.508 -0.9398)
			(end -0.508 -0.9398)
			(stroke
				(width 0.1524)
				(type default)
			)
			(layer "F.SilkS")
		)
		(fp_rect
			(start -0.508 0.9398)
			(end 0.508 -0.9398)
			(stroke
				(width 0)
				(type default)
			)
			(fill no)
			(layer "F.CrtYd")
		)
		(fp_rect
			(start -0.508 0.9398)
			(end 0.508 -0.9398)
			(stroke
				(width 0)
				(type default)
			)
			(fill no)
			(layer "F.Fab")
		)
		(pad "1" smd custom
			(at 0 -0.4445 270)
			(size 0.1397 0.1397)
			(layers "F.Cu" "F.Mask" "F.Paste")
			(net "MB0_ISET_R")
			(options
				(clearance outline)
				(anchor circle)
			)
			(primitives
				(gr_poly
					(pts
						(arc
							(start -0.1778 -0.2794)
							(mid -0.249642 -0.249642)
							(end -0.2794 -0.1778)
						)
						(arc
							(start -0.2794 0.1778)
							(mid -0.249642 0.249642)
							(end -0.1778 0.2794)
						)
						(arc
							(start 0.1778 0.2794)
							(mid 0.249642 0.249642)
							(end 0.2794 0.1778)
						)
						(arc
							(start 0.2794 -0.1778)
							(mid 0.249642 -0.249642)
							(end 0.1778 -0.2794)
						)
					)
					(width 0)
					(fill yes)
				)
			)
		)
		(pad "2" smd custom
			(at 0 0.4445 270)
			(size 0.1397 0.1397)
			(layers "F.Cu" "F.Mask" "F.Paste")
			(net "AGND_CURRENT_MON")
			(options
				(clearance outline)
				(anchor circle)
			)
			(primitives
				(gr_poly
					(pts
						(arc
							(start -0.1778 -0.2794)
							(mid -0.249642 -0.249642)
							(end -0.2794 -0.1778)
						)
						(arc
							(start -0.2794 0.1778)
							(mid -0.249642 0.249642)
							(end -0.1778 0.2794)
						)
						(arc
							(start 0.1778 0.2794)
							(mid 0.249642 0.249642)
							(end 0.2794 0.1778)
						)
						(arc
							(start 0.2794 -0.1778)
							(mid 0.249642 -0.249642)
							(end 0.1778 -0.2794)
						)
					)
					(width 0)
					(fill yes)
				)
			)
		)
	)
	(footprint ""
		(layer "F.Cu")
		(at 76.484226 -140.627862 -90)
		(property "Reference" "C135"
			(at 0 0 270)
			(layer "F.SilkS")
			(hide yes)
			(effects
				(font
					(size 1.27 1.27)
				)
			)
		)
		(property "Value" "SCD1U16V2KX-3GP"
			(at 1.1811 -2.7051 270)
			(unlocked yes)
			(layer "F.Fab")
			(hide yes)
			(effects
				(font
					(size 1.016 1.016)
					(thickness 0.1524)
				)
			)
		)
		(property "Device Type" "C402H22"
			(at 1.1811 -4.2291 270)
			(unlocked yes)
			(layer "F.Fab")
			(hide yes)
			(effects
				(font
					(size 1.016 1.016)
					(thickness 0.1524)
				)
			)
		)
		(duplicate_pad_numbers_are_jumpers no)
		(fp_rect
			(start -0.4318 0.9525)
			(end 0.4318 -0.9525)
			(stroke
				(width 0)
				(type default)
			)
			(fill no)
			(layer "F.CrtYd")
		)
		(fp_rect
			(start -0.4318 0.9525)
			(end 0.4318 -0.9525)
			(stroke
				(width 0)
				(type default)
			)
			(fill no)
			(layer "F.Fab")
		)
		(pad "1" smd custom
			(at 0 -0.4445 270)
			(size 0.1524 0.1524)
			(layers "F.Cu" "F.Mask" "F.Paste")
			(net "P3V3_STBY")
			(options
				(clearance outline)
				(anchor circle)
			)
			(primitives
				(gr_poly
					(pts
						(arc
							(start 0.3048 -0.2032)
							(mid 0.275042 -0.275042)
							(end 0.2032 -0.3048)
						)
						(arc
							(start -0.2032 -0.3048)
							(mid -0.275042 -0.275042)
							(end -0.3048 -0.2032)
						)
						(arc
							(start -0.3048 0.2032)
							(mid -0.275042 0.275042)
							(end -0.2032 0.3048)
						)
						(arc
							(start 0.2032 0.3048)
							(mid 0.275042 0.275042)
							(end 0.3048 0.2032)
						)
					)
					(width 0)
					(fill yes)
				)
			)
		)
		(pad "2" smd custom
			(at 0 0.4445 270)
			(size 0.1524 0.1524)
			(layers "F.Cu" "F.Mask" "F.Paste")
			(net "GND")
			(options
				(clearance outline)
				(anchor circle)
			)
			(primitives
				(gr_poly
					(pts
						(arc
							(start 0.3048 -0.2032)
							(mid 0.275042 -0.275042)
							(end 0.2032 -0.3048)
						)
						(arc
							(start -0.2032 -0.3048)
							(mid -0.275042 -0.275042)
							(end -0.3048 -0.2032)
						)
						(arc
							(start -0.3048 0.2032)
							(mid -0.275042 0.275042)
							(end -0.2032 0.3048)
						)
						(arc
							(start 0.2032 0.3048)
							(mid 0.275042 0.275042)
							(end 0.3048 0.2032)
						)
					)
					(width 0)
					(fill yes)
				)
			)
		)
	)
	(footprint ""
		(layer "F.Cu")
		(at 34.5694 -165.0238 180)
		(property "Reference" "R699"
			(at 0 0 180)
			(layer "F.SilkS")
			(hide yes)
			(effects
				(font
					(size 1.27 1.27)
				)
			)
		)
		(property "Value" "4K7R2F-GP"
			(at 0.064008 -3.993896 180)
			(unlocked yes)
			(layer "F.Fab")
			(hide yes)
			(effects
				(font
					(size 1.016 1.016)
					(thickness 0.1524)
				)
			)
		)
		(property "Device Type" "R402H16"
			(at 0.064008 -5.517896 180)
			(unlocked yes)
			(layer "F.Fab")
			(hide yes)
			(effects
				(font
					(size 1.016 1.016)
					(thickness 0.1524)
				)
			)
		)
		(duplicate_pad_numbers_are_jumpers no)
		(fp_line
			(start 0.508 -0.9398)
			(end -0.508 -0.9398)
			(stroke
				(width 0.1524)
				(type default)
			)
			(layer "F.SilkS")
		)
		(fp_line
			(start -0.508 -0.9398)
			(end -0.508 0.9398)
			(stroke
				(width 0.1524)
				(type default)
			)
			(layer "F.SilkS")
		)
		(fp_rect
			(start -0.508 0.9398)
			(end 0.508 -0.9398)
			(stroke
				(width 0)
				(type default)
			)
			(fill no)
			(layer "F.CrtYd")
		)
		(fp_rect
			(start -0.508 0.9398)
			(end 0.508 -0.9398)
			(stroke
				(width 0)
				(type default)
			)
			(fill no)
			(layer "F.Fab")
		)
		(pad "1" smd custom
			(at 0 -0.4445 180)
			(size 0.1397 0.1397)
			(layers "F.Cu" "F.Mask" "F.Paste")
			(net "IOM_TYPE2")
			(options
				(clearance outline)
				(anchor circle)
			)
			(primitives
				(gr_poly
					(pts
						(arc
							(start -0.1778 -0.2794)
							(mid -0.249642 -0.249642)
							(end -0.2794 -0.1778)
						)
						(arc
							(start -0.2794 0.1778)
							(mid -0.249642 0.249642)
							(end -0.1778 0.2794)
						)
						(arc
							(start 0.1778 0.2794)
							(mid 0.249642 0.249642)
							(end 0.2794 0.1778)
						)
						(arc
							(start 0.2794 -0.1778)
							(mid 0.249642 -0.249642)
							(end 0.1778 -0.2794)
						)
					)
					(width 0)
					(fill yes)
				)
			)
		)
		(pad "2" smd custom
			(at 0 0.4445 180)
			(size 0.1397 0.1397)
			(layers "F.Cu" "F.Mask" "F.Paste")
			(net "GND")
			(options
				(clearance outline)
				(anchor circle)
			)
			(primitives
				(gr_poly
					(pts
						(arc
							(start -0.1778 -0.2794)
							(mid -0.249642 -0.249642)
							(end -0.2794 -0.1778)
						)
						(arc
							(start -0.2794 0.1778)
							(mid -0.249642 0.249642)
							(end -0.1778 0.2794)
						)
						(arc
							(start 0.1778 0.2794)
							(mid 0.249642 0.249642)
							(end 0.2794 0.1778)
						)
						(arc
							(start 0.2794 -0.1778)
							(mid 0.249642 -0.249642)
							(end 0.1778 -0.2794)
						)
					)
					(width 0)
					(fill yes)
				)
			)
		)
	)
	(footprint ""
		(layer "F.Cu")
		(at 85.471 -170.6372 180)
		(property "Reference" "R723"
			(at 0 0 180)
			(layer "F.SilkS")
			(hide yes)
			(effects
				(font
					(size 1.27 1.27)
				)
			)
		)
		(property "Value" "4K7R2F-GP"
			(at 0.064008 -3.993896 180)
			(unlocked yes)
			(layer "F.Fab")
			(hide yes)
			(effects
				(font
					(size 1.016 1.016)
					(thickness 0.1524)
				)
			)
		)
		(property "Device Type" "R402H16"
			(at 0.064008 -5.517896 180)
			(unlocked yes)
			(layer "F.Fab")
			(hide yes)
			(effects
				(font
					(size 1.016 1.016)
					(thickness 0.1524)
				)
			)
		)
		(duplicate_pad_numbers_are_jumpers no)
		(fp_line
			(start 0.508 -0.9398)
			(end -0.508 -0.9398)
			(stroke
				(width 0.1524)
				(type default)
			)
			(layer "F.SilkS")
		)
		(fp_line
			(start -0.508 -0.9398)
			(end -0.508 0.9398)
			(stroke
				(width 0.1524)
				(type default)
			)
			(layer "F.SilkS")
		)
		(fp_rect
			(start -0.508 0.9398)
			(end 0.508 -0.9398)
			(stroke
				(width 0)
				(type default)
			)
			(fill no)
			(layer "F.CrtYd")
		)
		(fp_rect
			(start -0.508 0.9398)
			(end 0.508 -0.9398)
			(stroke
				(width 0)
				(type default)
			)
			(fill no)
			(layer "F.Fab")
		)
		(pad "1" smd custom
			(at 0 -0.4445 180)
			(size 0.1397 0.1397)
			(layers "F.Cu" "F.Mask" "F.Paste")
			(net "P5V_STBY")
			(options
				(clearance outline)
				(anchor circle)
			)
			(primitives
				(gr_poly
					(pts
						(arc
							(start -0.1778 -0.2794)
							(mid -0.249642 -0.249642)
							(end -0.2794 -0.1778)
						)
						(arc
							(start -0.2794 0.1778)
							(mid -0.249642 0.249642)
							(end -0.1778 0.2794)
						)
						(arc
							(start 0.1778 0.2794)
							(mid 0.249642 0.249642)
							(end 0.2794 0.1778)
						)
						(arc
							(start 0.2794 -0.1778)
							(mid 0.249642 -0.249642)
							(end 0.1778 -0.2794)
						)
					)
					(width 0)
					(fill yes)
				)
			)
		)
		(pad "2" smd custom
			(at 0 0.4445 180)
			(size 0.1397 0.1397)
			(layers "F.Cu" "F.Mask" "F.Paste")
			(net "P1V15_STBY_PG_G")
			(options
				(clearance outline)
				(anchor circle)
			)
			(primitives
				(gr_poly
					(pts
						(arc
							(start -0.1778 -0.2794)
							(mid -0.249642 -0.249642)
							(end -0.2794 -0.1778)
						)
						(arc
							(start -0.2794 0.1778)
							(mid -0.249642 0.249642)
							(end -0.1778 0.2794)
						)
						(arc
							(start 0.1778 0.2794)
							(mid 0.249642 0.249642)
							(end 0.2794 0.1778)
						)
						(arc
							(start 0.2794 -0.1778)
							(mid 0.249642 -0.249642)
							(end 0.1778 -0.2794)
						)
					)
					(width 0)
					(fill yes)
				)
			)
		)
	)
	(footprint ""
		(layer "F.Cu")
		(at 88.138 -138.4554 90)
		(property "Reference" "R136"
			(at 0 0 90)
			(layer "F.SilkS")
			(hide yes)
			(effects
				(font
					(size 1.27 1.27)
				)
			)
		)
		(property "Value" "8K2R2J-3-GP"
			(at 0.064008 -3.993896 90)
			(unlocked yes)
			(layer "F.Fab")
			(hide yes)
			(effects
				(font
					(size 1.016 1.016)
					(thickness 0.1524)
				)
			)
		)
		(property "Device Type" "R402H16"
			(at 0.064008 -5.517896 90)
			(unlocked yes)
			(layer "F.Fab")
			(hide yes)
			(effects
				(font
					(size 1.016 1.016)
					(thickness 0.1524)
				)
			)
		)
		(duplicate_pad_numbers_are_jumpers no)
		(fp_line
			(start 0.508 -0.9398)
			(end -0.508 -0.9398)
			(stroke
				(width 0.1524)
				(type default)
			)
			(layer "F.SilkS")
		)
		(fp_line
			(start -0.508 -0.9398)
			(end -0.508 0.9398)
			(stroke
				(width 0.1524)
				(type default)
			)
			(layer "F.SilkS")
		)
		(fp_rect
			(start -0.508 0.9398)
			(end 0.508 -0.9398)
			(stroke
				(width 0)
				(type default)
			)
			(fill no)
			(layer "F.CrtYd")
		)
		(fp_rect
			(start -0.508 0.9398)
			(end 0.508 -0.9398)
			(stroke
				(width 0)
				(type default)
			)
			(fill no)
			(layer "F.Fab")
		)
		(pad "1" smd custom
			(at 0 -0.4445 90)
			(size 0.1397 0.1397)
			(layers "F.Cu" "F.Mask" "F.Paste")
			(net "EEPROM_A0")
			(options
				(clearance outline)
				(anchor circle)
			)
			(primitives
				(gr_poly
					(pts
						(arc
							(start -0.1778 -0.2794)
							(mid -0.249642 -0.249642)
							(end -0.2794 -0.1778)
						)
						(arc
							(start -0.2794 0.1778)
							(mid -0.249642 0.249642)
							(end -0.1778 0.2794)
						)
						(arc
							(start 0.1778 0.2794)
							(mid 0.249642 0.249642)
							(end 0.2794 0.1778)
						)
						(arc
							(start 0.2794 -0.1778)
							(mid 0.249642 -0.249642)
							(end 0.1778 -0.2794)
						)
					)
					(width 0)
					(fill yes)
				)
			)
		)
		(pad "2" smd custom
			(at 0 0.4445 90)
			(size 0.1397 0.1397)
			(layers "F.Cu" "F.Mask" "F.Paste")
			(net "GND")
			(options
				(clearance outline)
				(anchor circle)
			)
			(primitives
				(gr_poly
					(pts
						(arc
							(start -0.1778 -0.2794)
							(mid -0.249642 -0.249642)
							(end -0.2794 -0.1778)
						)
						(arc
							(start -0.2794 0.1778)
							(mid -0.249642 0.249642)
							(end -0.1778 0.2794)
						)
						(arc
							(start 0.1778 0.2794)
							(mid 0.249642 0.249642)
							(end 0.2794 0.1778)
						)
						(arc
							(start 0.2794 -0.1778)
							(mid 0.249642 -0.249642)
							(end 0.1778 -0.2794)
						)
					)
					(width 0)
					(fill yes)
				)
			)
		)
	)
	(footprint ""
		(layer "F.Cu")
		(at 180.213 -156.083 90)
		(property "Reference" "R468"
			(at 0 0 90)
			(layer "F.SilkS")
			(hide yes)
			(effects
				(font
					(size 1.27 1.27)
				)
			)
		)
		(property "Value" "3K3R2J-3-GP"
			(at 0.064008 -3.993896 90)
			(unlocked yes)
			(layer "F.Fab")
			(hide yes)
			(effects
				(font
					(size 1.016 1.016)
					(thickness 0.1524)
				)
			)
		)
		(property "Device Type" "R402H16"
			(at 0.064008 -5.517896 90)
			(unlocked yes)
			(layer "F.Fab")
			(hide yes)
			(effects
				(font
					(size 1.016 1.016)
					(thickness 0.1524)
				)
			)
		)
		(duplicate_pad_numbers_are_jumpers no)
		(fp_line
			(start 0.508 -0.9398)
			(end -0.508 -0.9398)
			(stroke
				(width 0.1524)
				(type default)
			)
			(layer "F.SilkS")
		)
		(fp_line
			(start -0.508 -0.9398)
			(end -0.508 0.9398)
			(stroke
				(width 0.1524)
				(type default)
			)
			(layer "F.SilkS")
		)
		(fp_rect
			(start -0.508 0.9398)
			(end 0.508 -0.9398)
			(stroke
				(width 0)
				(type default)
			)
			(fill no)
			(layer "F.CrtYd")
		)
		(fp_rect
			(start -0.508 0.9398)
			(end 0.508 -0.9398)
			(stroke
				(width 0)
				(type default)
			)
			(fill no)
			(layer "F.Fab")
		)
		(pad "1" smd custom
			(at 0 -0.4445 90)
			(size 0.1397 0.1397)
			(layers "F.Cu" "F.Mask" "F.Paste")
			(net "P5V_LL")
			(options
				(clearance outline)
				(anchor circle)
			)
			(primitives
				(gr_poly
					(pts
						(arc
							(start -0.1778 -0.2794)
							(mid -0.249642 -0.249642)
							(end -0.2794 -0.1778)
						)
						(arc
							(start -0.2794 0.1778)
							(mid -0.249642 0.249642)
							(end -0.1778 0.2794)
						)
						(arc
							(start 0.1778 0.2794)
							(mid 0.249642 0.249642)
							(end 0.2794 0.1778)
						)
						(arc
							(start 0.2794 -0.1778)
							(mid 0.249642 -0.249642)
							(end 0.1778 -0.2794)
						)
					)
					(width 0)
					(fill yes)
				)
			)
		)
		(pad "2" smd custom
			(at 0 0.4445 90)
			(size 0.1397 0.1397)
			(layers "F.Cu" "F.Mask" "F.Paste")
			(net "P5V_LL_R")
			(options
				(clearance outline)
				(anchor circle)
			)
			(primitives
				(gr_poly
					(pts
						(arc
							(start -0.1778 -0.2794)
							(mid -0.249642 -0.249642)
							(end -0.2794 -0.1778)
						)
						(arc
							(start -0.2794 0.1778)
							(mid -0.249642 0.249642)
							(end -0.1778 0.2794)
						)
						(arc
							(start 0.1778 0.2794)
							(mid 0.249642 0.249642)
							(end 0.2794 0.1778)
						)
						(arc
							(start 0.2794 -0.1778)
							(mid 0.249642 -0.249642)
							(end 0.1778 -0.2794)
						)
					)
					(width 0)
					(fill yes)
				)
			)
		)
	)
	(footprint ""
		(layer "F.Cu")
		(at 137.2362 -13.1064 180)
		(property "Reference" "R444"
			(at 0 0 180)
			(layer "F.SilkS")
			(hide yes)
			(effects
				(font
					(size 1.27 1.27)
				)
			)
		)
		(property "Value" "D002RL3115F-L-GP"
			(at 3.2258 1.2954 180)
			(unlocked yes)
			(layer "F.Fab")
			(hide yes)
			(effects
				(font
					(size 1.016 1.016)
					(thickness 0.1524)
				)
			)
		)
		(property "Device Type" "RL3115-4PH45"
			(at 3.2258 -0.2286 180)
			(unlocked yes)
			(layer "F.Fab")
			(hide yes)
			(effects
				(font
					(size 1.016 1.016)
					(thickness 0.1524)
				)
			)
		)
		(duplicate_pad_numbers_are_jumpers no)
		(fp_line
			(start 1.9685 1.651)
			(end -1.9685 1.651)
			(stroke
				(width 0.1524)
				(type default)
			)
			(layer "F.SilkS")
		)
		(fp_line
			(start 1.9685 -1.651)
			(end 1.9685 1.651)
			(stroke
				(width 0.1524)
				(type default)
			)
			(layer "F.SilkS")
		)
		(fp_line
			(start -0.5334 -1.7653)
			(end -2.0574 -1.7653)
			(stroke
				(width 0.3302)
				(type default)
			)
			(layer "F.SilkS")
		)
		(fp_line
			(start -1.9685 1.651)
			(end -1.9685 -1.651)
			(stroke
				(width 0.1524)
				(type default)
			)
			(layer "F.SilkS")
		)
		(fp_line
			(start -1.9685 -1.651)
			(end 1.9685 -1.651)
			(stroke
				(width 0.1524)
				(type default)
			)
			(layer "F.SilkS")
		)
		(fp_line
			(start -2.0574 -1.7653)
			(end -2.0574 -0.4064)
			(stroke
				(width 0.3302)
				(type default)
			)
			(layer "F.SilkS")
		)
		(fp_poly
			(pts
				(xy -0.561594 -1.726946) (xy -0.053594 -2.234946) (xy -1.069594 -2.234946)
			)
			(stroke
				(width 0)
				(type default)
			)
			(fill yes)
			(layer "F.SilkS")
		)
		(fp_rect
			(start -1.524 0.7493)
			(end 1.524 -0.7493)
			(stroke
				(width 0)
				(type default)
			)
			(fill no)
			(layer "F.CrtYd")
		)
		(fp_poly
			(pts
				(xy -2.2225 1.905) (xy -2.2225 -1.905) (xy 2.2225 -1.905) (xy 2.2225 -0.7493) (xy -1.524 -0.7493)
				(xy -1.524 0.7493) (xy 1.524 0.7493) (xy 1.524 -0.7366) (xy 2.2225 -0.7366) (xy 2.2225 1.905)
			)
			(stroke
				(width 0)
				(type default)
			)
			(fill no)
			(layer "F.CrtYd")
		)
		(fp_rect
			(start -2.2225 1.905)
			(end 2.2225 -1.905)
			(stroke
				(width 0)
				(type default)
			)
			(fill no)
			(layer "F.Fab")
		)
		(pad "1" smd rect
			(at -0.5715 -0.813562 180)
			(size 2.286 1.143)
			(layers "F.Cu" "F.Mask" "F.Paste")
			(net "MB0_P12V_MAIN_R")
		)
		(pad "2" smd rect
			(at -0.5715 0.813562 180)
			(size 2.286 1.143)
			(layers "F.Cu" "F.Mask" "F.Paste")
			(net "P12V_IOM")
		)
		(pad "3" smd rect
			(at 1.334008 -0.813562 180)
			(size 0.762 1.143)
			(layers "F.Cu" "F.Mask" "F.Paste")
			(net "MB0_CM_SENSE_R1_N")
		)
		(pad "4" smd rect
			(at 1.334008 0.813562 180)
			(size 0.762 1.143)
			(layers "F.Cu" "F.Mask" "F.Paste")
			(net "MB0_CM_SENSE_R1_P")
		)
		(zone
			(layer "F.Cu")
			(hatch none 0.5)
			(connect_pads
				(clearance 0)
			)
			(min_thickness 0.25)
			(keepout
				(tracks allowed)
				(vias not_allowed)
				(pads allowed)
				(copperpour not_allowed)
				(footprints allowed)
			)
			(placement
				(enabled no)
				(sheetname "")
			)
			(fill
				(thermal_gap 0.5)
				(thermal_bridge_width 0.5)
				(island_removal_mode 0)
			)
			(polygon
				(pts
					(xy 136.6647 -13.8557) (xy 136.283192 -13.8557) (xy 136.283192 -13.348462) (xy 136.6647 -13.348462)
				)
			)
		)
		(zone
			(layer "F.Cu")
			(hatch none 0.5)
			(connect_pads
				(clearance 0)
			)
			(min_thickness 0.25)
			(keepout
				(tracks not_allowed)
				(vias allowed)
				(pads allowed)
				(copperpour not_allowed)
				(footprints allowed)
			)
			(placement
				(enabled no)
				(sheetname "")
			)
			(fill
				(thermal_gap 0.5)
				(thermal_bridge_width 0.5)
				(island_removal_mode 0)
			)
			(polygon
				(pts
					(xy 136.6647 -13.8557) (xy 136.283192 -13.8557) (xy 136.283192 -13.348462) (xy 136.6647 -13.348462)
				)
			)
		)
		(zone
			(layer "F.Cu")
			(hatch none 0.5)
			(connect_pads
				(clearance 0)
			)
			(min_thickness 0.25)
			(keepout
				(tracks allowed)
				(vias not_allowed)
				(pads allowed)
				(copperpour not_allowed)
				(footprints allowed)
			)
			(placement
				(enabled no)
				(sheetname "")
			)
			(fill
				(thermal_gap 0.5)
				(thermal_bridge_width 0.5)
				(island_removal_mode 0)
			)
			(polygon
				(pts
					(xy 136.6647 -12.864338) (xy 136.283192 -12.864338) (xy 136.283192 -12.3571) (xy 136.6647 -12.3571)
				)
			)
		)
		(zone
			(layer "F.Cu")
			(hatch none 0.5)
			(connect_pads
				(clearance 0)
			)
			(min_thickness 0.25)
			(keepout
				(tracks not_allowed)
				(vias allowed)
				(pads allowed)
				(copperpour not_allowed)
				(footprints allowed)
			)
			(placement
				(enabled no)
				(sheetname "")
			)
			(fill
				(thermal_gap 0.5)
				(thermal_bridge_width 0.5)
				(island_removal_mode 0)
			)
			(polygon
				(pts
					(xy 136.6647 -12.864338) (xy 136.283192 -12.864338) (xy 136.283192 -12.3571) (xy 136.6647 -12.3571)
				)
			)
		)
	)
	(footprint ""
		(layer "F.Cu")
		(at 112.959388 -13.13561 180)
		(property "Reference" "R457"
			(at 0 0 180)
			(layer "F.SilkS")
			(hide yes)
			(effects
				(font
					(size 1.27 1.27)
				)
			)
		)
		(property "Value" "100KR2J-4-GP"
			(at 0.064008 -3.993896 180)
			(unlocked yes)
			(layer "F.Fab")
			(hide yes)
			(effects
				(font
					(size 1.016 1.016)
					(thickness 0.1524)
				)
			)
		)
		(property "Device Type" "R402H15"
			(at 0.064008 -5.517896 180)
			(unlocked yes)
			(layer "F.Fab")
			(hide yes)
			(effects
				(font
					(size 1.016 1.016)
					(thickness 0.1524)
				)
			)
		)
		(duplicate_pad_numbers_are_jumpers no)
		(fp_line
			(start 0.508 -0.9398)
			(end -0.508 -0.9398)
			(stroke
				(width 0.1524)
				(type default)
			)
			(layer "F.SilkS")
		)
		(fp_line
			(start -0.508 -0.9398)
			(end -0.508 0.9398)
			(stroke
				(width 0.1524)
				(type default)
			)
			(layer "F.SilkS")
		)
		(fp_rect
			(start -0.508 0.9398)
			(end 0.508 -0.9398)
			(stroke
				(width 0)
				(type default)
			)
			(fill no)
			(layer "F.CrtYd")
		)
		(fp_rect
			(start -0.508 0.9398)
			(end 0.508 -0.9398)
			(stroke
				(width 0)
				(type default)
			)
			(fill no)
			(layer "F.Fab")
		)
		(pad "1" smd custom
			(at 0 -0.4445 180)
			(size 0.1397 0.1397)
			(layers "F.Cu" "F.Mask" "F.Paste")
			(net "MB0_VCAP_R")
			(options
				(clearance outline)
				(anchor circle)
			)
			(primitives
				(gr_poly
					(pts
						(arc
							(start -0.1778 -0.2794)
							(mid -0.249642 -0.249642)
							(end -0.2794 -0.1778)
						)
						(arc
							(start -0.2794 0.1778)
							(mid -0.249642 0.249642)
							(end -0.1778 0.2794)
						)
						(arc
							(start 0.1778 0.2794)
							(mid 0.249642 0.249642)
							(end 0.2794 0.1778)
						)
						(arc
							(start 0.2794 -0.1778)
							(mid 0.249642 -0.249642)
							(end 0.1778 -0.2794)
						)
					)
					(width 0)
					(fill yes)
				)
			)
		)
		(pad "2" smd custom
			(at 0 0.4445 180)
			(size 0.1397 0.1397)
			(layers "F.Cu" "F.Mask" "F.Paste")
			(net "MB0_PSET_R")
			(options
				(clearance outline)
				(anchor circle)
			)
			(primitives
				(gr_poly
					(pts
						(arc
							(start -0.1778 -0.2794)
							(mid -0.249642 -0.249642)
							(end -0.2794 -0.1778)
						)
						(arc
							(start -0.2794 0.1778)
							(mid -0.249642 0.249642)
							(end -0.1778 0.2794)
						)
						(arc
							(start 0.1778 0.2794)
							(mid 0.249642 0.249642)
							(end 0.2794 0.1778)
						)
						(arc
							(start 0.2794 -0.1778)
							(mid 0.249642 -0.249642)
							(end 0.1778 -0.2794)
						)
					)
					(width 0)
					(fill yes)
				)
			)
		)
	)
	(footprint ""
		(layer "F.Cu")
		(at 28.194 -151.638 -90)
		(property "Reference" "R768"
			(at 0 0 270)
			(layer "F.SilkS")
			(hide yes)
			(effects
				(font
					(size 1.27 1.27)
				)
			)
		)
		(property "Value" "0R2J-2-GP"
			(at 0.064008 -3.993896 270)
			(unlocked yes)
			(layer "F.Fab")
			(hide yes)
			(effects
				(font
					(size 1.016 1.016)
					(thickness 0.1524)
				)
			)
		)
		(property "Device Type" "R402H16"
			(at 0.064008 -5.517896 270)
			(unlocked yes)
			(layer "F.Fab")
			(hide yes)
			(effects
				(font
					(size 1.016 1.016)
					(thickness 0.1524)
				)
			)
		)
		(duplicate_pad_numbers_are_jumpers no)
		(fp_line
			(start -0.508 -0.9398)
			(end -0.508 0.9398)
			(stroke
				(width 0.1524)
				(type default)
			)
			(layer "F.SilkS")
		)
		(fp_line
			(start 0.508 -0.9398)
			(end -0.508 -0.9398)
			(stroke
				(width 0.1524)
				(type default)
			)
			(layer "F.SilkS")
		)
		(fp_rect
			(start -0.508 0.9398)
			(end 0.508 -0.9398)
			(stroke
				(width 0)
				(type default)
			)
			(fill no)
			(layer "F.CrtYd")
		)
		(fp_rect
			(start -0.508 0.9398)
			(end 0.508 -0.9398)
			(stroke
				(width 0)
				(type default)
			)
			(fill no)
			(layer "F.Fab")
		)
		(pad "1" smd custom
			(at 0 -0.4445 270)
			(size 0.1397 0.1397)
			(layers "F.Cu" "F.Mask" "F.Paste")
			(net "DEBUG_GPIO_BMC_R_1")
			(options
				(clearance outline)
				(anchor circle)
			)
			(primitives
				(gr_poly
					(pts
						(arc
							(start -0.1778 -0.2794)
							(mid -0.249642 -0.249642)
							(end -0.2794 -0.1778)
						)
						(arc
							(start -0.2794 0.1778)
							(mid -0.249642 0.249642)
							(end -0.1778 0.2794)
						)
						(arc
							(start 0.1778 0.2794)
							(mid 0.249642 0.249642)
							(end 0.2794 0.1778)
						)
						(arc
							(start 0.2794 -0.1778)
							(mid 0.249642 -0.249642)
							(end 0.1778 -0.2794)
						)
					)
					(width 0)
					(fill yes)
				)
			)
		)
		(pad "2" smd custom
			(at 0 0.4445 270)
			(size 0.1397 0.1397)
			(layers "F.Cu" "F.Mask" "F.Paste")
			(net "DEBUG_GPIO_BMC_1")
			(options
				(clearance outline)
				(anchor circle)
			)
			(primitives
				(gr_poly
					(pts
						(arc
							(start -0.1778 -0.2794)
							(mid -0.249642 -0.249642)
							(end -0.2794 -0.1778)
						)
						(arc
							(start -0.2794 0.1778)
							(mid -0.249642 0.249642)
							(end -0.1778 0.2794)
						)
						(arc
							(start 0.1778 0.2794)
							(mid 0.249642 0.249642)
							(end 0.2794 0.1778)
						)
						(arc
							(start 0.2794 -0.1778)
							(mid 0.249642 -0.249642)
							(end 0.1778 -0.2794)
						)
					)
					(width 0)
					(fill yes)
				)
			)
		)
	)
	(footprint ""
		(layer "F.Cu")
		(at 90.424 -29.6418 90)
		(property "Reference" "U98"
			(at 0 0 90)
			(layer "F.SilkS")
			(hide yes)
			(effects
				(font
					(size 1.27 1.27)
				)
			)
		)
		(property "Value" "TPS2065DBVT-GP"
			(at 0 -5.1308 90)
			(unlocked yes)
			(layer "F.Fab")
			(hide yes)
			(effects
				(font
					(size 1.016 1.016)
					(thickness 0.1524)
				)
			)
		)
		(property "Device Type" "SOT-23-5H58"
			(at 0 -6.7564 90)
			(unlocked yes)
			(layer "F.Fab")
			(hide yes)
			(effects
				(font
					(size 1.016 1.016)
					(thickness 0.1524)
				)
			)
		)
		(duplicate_pad_numbers_are_jumpers no)
		(fp_line
			(start 1.778 -2.286)
			(end -1.778 -2.286)
			(stroke
				(width 0.1524)
				(type default)
			)
			(layer "F.SilkS")
		)
		(fp_line
			(start -1.778 -2.286)
			(end -1.778 2.286)
			(stroke
				(width 0.1524)
				(type default)
			)
			(layer "F.SilkS")
		)
		(fp_line
			(start -0.7112 2.2352)
			(end -1.7272 2.2352)
			(stroke
				(width 0.3302)
				(type default)
			)
			(layer "F.SilkS")
		)
		(fp_line
			(start -1.7272 2.2352)
			(end -1.7272 0.762)
			(stroke
				(width 0.3302)
				(type default)
			)
			(layer "F.SilkS")
		)
		(fp_line
			(start 1.778 2.286)
			(end 1.778 -2.286)
			(stroke
				(width 0.1524)
				(type default)
			)
			(layer "F.SilkS")
		)
		(fp_line
			(start -0.254 2.286)
			(end 1.778 2.286)
			(stroke
				(width 0.1524)
				(type default)
			)
			(layer "F.SilkS")
		)
		(fp_line
			(start -1.778 2.286)
			(end 1.778 2.286)
			(stroke
				(width 0.1524)
				(type default)
			)
			(layer "F.SilkS")
		)
		(fp_line
			(start -1.778 2.286)
			(end -0.254 2.286)
			(stroke
				(width 0.1524)
				(type default)
			)
			(layer "F.SilkS")
		)
		(fp_poly
			(pts
				(xy -0.9652 2.4384) (xy -1.3208 2.794) (xy -0.6096 2.794)
			)
			(stroke
				(width 0)
				(type default)
			)
			(fill yes)
			(layer "F.SilkS")
		)
		(fp_rect
			(start -1.778 2.286)
			(end 1.778 -2.286)
			(stroke
				(width 0)
				(type default)
			)
			(fill no)
			(layer "F.CrtYd")
		)
		(fp_rect
			(start -1.778 2.286)
			(end 1.778 -2.286)
			(stroke
				(width 0)
				(type default)
			)
			(fill no)
			(layer "F.Fab")
		)
		(pad "1" smd rect
			(at -0.94996 1.143 90)
			(size 0.508 1.524)
			(layers "F.Cu" "F.Mask" "F.Paste")
			(net "P5V_USB")
		)
		(pad "2" smd rect
			(at 0 1.143 90)
			(size 0.508 1.524)
			(layers "F.Cu" "F.Mask" "F.Paste")
			(net "GND")
		)
		(pad "3" smd rect
			(at 0.94996 1.143 90)
			(size 0.508 1.524)
			(layers "F.Cu" "F.Mask" "F.Paste")
			(net "USB_OCS_N1")
		)
		(pad "4" smd rect
			(at 0.94996 -1.143 90)
			(size 0.508 1.524)
			(layers "F.Cu" "F.Mask" "F.Paste")
			(net "USB_EN_1")
		)
		(pad "5" smd rect
			(at -0.94996 -1.143 90)
			(size 0.508 1.524)
			(layers "F.Cu" "F.Mask" "F.Paste")
			(net "P5V_STBY")
		)
	)
	(footprint ""
		(layer "F.Cu")
		(at 193.4972 -114.321336)
		(property "Reference" "L12"
			(at 0 0 0)
			(layer "F.SilkS")
			(hide yes)
			(effects
				(font
					(size 1.27 1.27)
				)
			)
		)
		(property "Value" "COIL-D24UH-GP"
			(at -5.5118 1.5748 0)
			(unlocked yes)
			(layer "F.Fab")
			(hide yes)
			(effects
				(font
					(size 1.016 1.016)
					(thickness 0.1524)
				)
			)
		)
		(property "Device Type" "L7267-1630H158"
			(at -5.5118 0.0508 0)
			(unlocked yes)
			(layer "F.Fab")
			(hide yes)
			(effects
				(font
					(size 1.016 1.016)
					(thickness 0.1524)
				)
			)
		)
		(duplicate_pad_numbers_are_jumpers no)
		(fp_line
			(start -3.6068 -4.6101)
			(end 3.6068 -4.6101)
			(stroke
				(width 0.1524)
				(type default)
			)
			(layer "F.SilkS")
		)
		(fp_line
			(start -3.6068 4.6101)
			(end -3.6068 -4.6101)
			(stroke
				(width 0.1524)
				(type default)
			)
			(layer "F.SilkS")
		)
		(fp_line
			(start 3.6068 -4.6101)
			(end 3.6068 4.6101)
			(stroke
				(width 0.1524)
				(type default)
			)
			(layer "F.SilkS")
		)
		(fp_line
			(start 3.6068 4.6101)
			(end -3.6068 4.6101)
			(stroke
				(width 0.1524)
				(type default)
			)
			(layer "F.SilkS")
		)
		(fp_rect
			(start -3.3528 3.5941)
			(end 3.3528 -3.5941)
			(stroke
				(width 0)
				(type default)
			)
			(fill no)
			(layer "F.CrtYd")
		)
		(fp_poly
			(pts
				(xy -3.8608 4.6863) (xy -3.8608 3.5941) (xy 3.3528 3.5941) (xy 3.3528 -3.5941) (xy -3.3528 -3.5941)
				(xy -3.3528 3.5814) (xy -3.8608 3.5814) (xy -3.8608 -4.6863) (xy 3.8608 -4.6863) (xy 3.8608 4.6863)
			)
			(stroke
				(width 0)
				(type default)
			)
			(fill no)
			(layer "F.CrtYd")
		)
		(fp_rect
			(start -3.8608 4.6863)
			(end 3.8608 -4.6863)
			(stroke
				(width 0)
				(type default)
			)
			(fill no)
			(layer "F.Fab")
		)
		(pad "1" smd rect
			(at 0 -2.990596)
			(size 3.5052 2.7432)
			(layers "F.Cu" "F.Mask" "F.Paste")
			(net "VT235_VX")
		)
		(pad "2" smd rect
			(at 0 2.990596)
			(size 3.5052 2.7432)
			(layers "F.Cu" "F.Mask" "F.Paste")
			(net "P0V975")
		)
	)
	(footprint ""
		(layer "F.Cu")
		(at 183.4261 -48.1457)
		(property "Reference" "R668"
			(at 0 0 0)
			(layer "F.SilkS")
			(hide yes)
			(effects
				(font
					(size 1.27 1.27)
				)
			)
		)
		(property "Value" "10KR2F-2-GP"
			(at 0.064008 -3.993896 0)
			(unlocked yes)
			(layer "F.Fab")
			(hide yes)
			(effects
				(font
					(size 1.016 1.016)
					(thickness 0.1524)
				)
			)
		)
		(property "Device Type" "R402H16"
			(at 0.064008 -5.517896 0)
			(unlocked yes)
			(layer "F.Fab")
			(hide yes)
			(effects
				(font
					(size 1.016 1.016)
					(thickness 0.1524)
				)
			)
		)
		(duplicate_pad_numbers_are_jumpers no)
		(fp_line
			(start -0.508 -0.9398)
			(end -0.508 0.9398)
			(stroke
				(width 0.1524)
				(type default)
			)
			(layer "F.SilkS")
		)
		(fp_line
			(start 0.508 -0.9398)
			(end -0.508 -0.9398)
			(stroke
				(width 0.1524)
				(type default)
			)
			(layer "F.SilkS")
		)
		(fp_rect
			(start -0.508 0.9398)
			(end 0.508 -0.9398)
			(stroke
				(width 0)
				(type default)
			)
			(fill no)
			(layer "F.CrtYd")
		)
		(fp_rect
			(start -0.508 0.9398)
			(end 0.508 -0.9398)
			(stroke
				(width 0)
				(type default)
			)
			(fill no)
			(layer "F.Fab")
		)
		(pad "1" smd custom
			(at 0 -0.4445)
			(size 0.1397 0.1397)
			(layers "F.Cu" "F.Mask" "F.Paste")
			(net "XM_ADDR_1")
			(options
				(clearance outline)
				(anchor circle)
			)
			(primitives
				(gr_poly
					(pts
						(arc
							(start -0.1778 -0.2794)
							(mid -0.249642 -0.249642)
							(end -0.2794 -0.1778)
						)
						(arc
							(start -0.2794 0.1778)
							(mid -0.249642 0.249642)
							(end -0.1778 0.2794)
						)
						(arc
							(start 0.1778 0.2794)
							(mid 0.249642 0.249642)
							(end 0.2794 0.1778)
						)
						(arc
							(start 0.2794 -0.1778)
							(mid 0.249642 -0.249642)
							(end 0.1778 -0.2794)
						)
					)
					(width 0)
					(fill yes)
				)
			)
		)
		(pad "2" smd custom
			(at 0 0.4445)
			(size 0.1397 0.1397)
			(layers "F.Cu" "F.Mask" "F.Paste")
			(net "GND")
			(options
				(clearance outline)
				(anchor circle)
			)
			(primitives
				(gr_poly
					(pts
						(arc
							(start -0.1778 -0.2794)
							(mid -0.249642 -0.249642)
							(end -0.2794 -0.1778)
						)
						(arc
							(start -0.2794 0.1778)
							(mid -0.249642 0.249642)
							(end -0.1778 0.2794)
						)
						(arc
							(start 0.1778 0.2794)
							(mid 0.249642 0.249642)
							(end 0.2794 0.1778)
						)
						(arc
							(start 0.2794 -0.1778)
							(mid 0.249642 -0.249642)
							(end 0.1778 -0.2794)
						)
					)
					(width 0)
					(fill yes)
				)
			)
		)
	)
	(footprint ""
		(layer "F.Cu")
		(at 70.104 -146.05 90)
		(property "Reference" "R763"
			(at 0 0 90)
			(layer "F.SilkS")
			(hide yes)
			(effects
				(font
					(size 1.27 1.27)
				)
			)
		)
		(property "Value" "33R2J-2-GP"
			(at 0.064008 -3.993896 90)
			(unlocked yes)
			(layer "F.Fab")
			(hide yes)
			(effects
				(font
					(size 1.016 1.016)
					(thickness 0.1524)
				)
			)
		)
		(property "Device Type" "R402H16"
			(at 0.064008 -5.517896 90)
			(unlocked yes)
			(layer "F.Fab")
			(hide yes)
			(effects
				(font
					(size 1.016 1.016)
					(thickness 0.1524)
				)
			)
		)
		(duplicate_pad_numbers_are_jumpers no)
		(fp_line
			(start 0.508 -0.9398)
			(end -0.508 -0.9398)
			(stroke
				(width 0.1524)
				(type default)
			)
			(layer "F.SilkS")
		)
		(fp_line
			(start -0.508 -0.9398)
			(end -0.508 0.9398)
			(stroke
				(width 0.1524)
				(type default)
			)
			(layer "F.SilkS")
		)
		(fp_rect
			(start -0.508 0.9398)
			(end 0.508 -0.9398)
			(stroke
				(width 0)
				(type default)
			)
			(fill no)
			(layer "F.CrtYd")
		)
		(fp_rect
			(start -0.508 0.9398)
			(end 0.508 -0.9398)
			(stroke
				(width 0)
				(type default)
			)
			(fill no)
			(layer "F.Fab")
		)
		(pad "1" smd custom
			(at 0 -0.4445 90)
			(size 0.1397 0.1397)
			(layers "F.Cu" "F.Mask" "F.Paste")
			(net "NCSI_RCLK_R")
			(options
				(clearance outline)
				(anchor circle)
			)
			(primitives
				(gr_poly
					(pts
						(arc
							(start -0.1778 -0.2794)
							(mid -0.249642 -0.249642)
							(end -0.2794 -0.1778)
						)
						(arc
							(start -0.2794 0.1778)
							(mid -0.249642 0.249642)
							(end -0.1778 0.2794)
						)
						(arc
							(start 0.1778 0.2794)
							(mid 0.249642 0.249642)
							(end 0.2794 0.1778)
						)
						(arc
							(start 0.2794 -0.1778)
							(mid 0.249642 -0.249642)
							(end 0.1778 -0.2794)
						)
					)
					(width 0)
					(fill yes)
				)
			)
		)
		(pad "2" smd custom
			(at 0 0.4445 90)
			(size 0.1397 0.1397)
			(layers "F.Cu" "F.Mask" "F.Paste")
			(net "NCSI_RCLK")
			(options
				(clearance outline)
				(anchor circle)
			)
			(primitives
				(gr_poly
					(pts
						(arc
							(start -0.1778 -0.2794)
							(mid -0.249642 -0.249642)
							(end -0.2794 -0.1778)
						)
						(arc
							(start -0.2794 0.1778)
							(mid -0.249642 0.249642)
							(end -0.1778 0.2794)
						)
						(arc
							(start 0.1778 0.2794)
							(mid 0.249642 0.249642)
							(end 0.2794 0.1778)
						)
						(arc
							(start 0.2794 -0.1778)
							(mid 0.249642 -0.249642)
							(end 0.1778 -0.2794)
						)
					)
					(width 0)
					(fill yes)
				)
			)
		)
	)
	(footprint ""
		(layer "F.Cu")
		(at 199.8345 -22.8092)
		(property "Reference" "Q24"
			(at 0 0 0)
			(layer "F.SilkS")
			(hide yes)
			(effects
				(font
					(size 1.27 1.27)
				)
			)
		)
		(property "Value" "SSM3K324R-GP"
			(at 0.127 -8.9662 0)
			(unlocked yes)
			(layer "F.Fab")
			(hide yes)
			(effects
				(font
					(size 1.016 1.016)
					(thickness 0.1524)
				)
			)
		)
		(property "Device Type" "SOT23DGS2D4H35"
			(at 0.127 -10.4902 0)
			(unlocked yes)
			(layer "F.Fab")
			(hide yes)
			(effects
				(font
					(size 1.016 1.016)
					(thickness 0.1524)
				)
			)
		)
		(duplicate_pad_numbers_are_jumpers no)
		(fp_line
			(start -1.651 -1.778)
			(end -1.651 1.778)
			(stroke
				(width 0.1524)
				(type default)
			)
			(layer "F.SilkS")
		)
		(fp_line
			(start -1.651 1.778)
			(end 1.651 1.778)
			(stroke
				(width 0.1524)
				(type default)
			)
			(layer "F.SilkS")
		)
		(fp_line
			(start 1.651 -1.778)
			(end -1.651 -1.778)
			(stroke
				(width 0.1524)
				(type default)
			)
			(layer "F.SilkS")
		)
		(fp_line
			(start 1.651 1.778)
			(end 1.651 -1.778)
			(stroke
				(width 0.1524)
				(type default)
			)
			(layer "F.SilkS")
		)
		(fp_poly
			(pts
				(xy -1.778 1.8796) (xy -1.778 -1.8796) (xy 1.778 -1.8796) (xy 1.778 1.8796)
			)
			(stroke
				(width 0)
				(type default)
			)
			(fill no)
			(layer "F.CrtYd")
		)
		(fp_poly
			(pts
				(xy -1.778 1.8796) (xy -1.778 -1.8796) (xy 1.778 -1.8796) (xy 1.778 1.8796)
			)
			(stroke
				(width 0)
				(type default)
			)
			(fill no)
			(layer "F.Fab")
		)
		(pad "D" smd custom
			(at 0 -0.9525)
			(size 0.1905 0.1905)
			(layers "F.Cu" "F.Mask" "F.Paste")
			(net "EXT1_LED_BLUE_G2")
			(options
				(clearance outline)
				(anchor circle)
			)
			(primitives
				(gr_poly
					(pts
						(arc
							(start -0.1778 0.5715)
							(mid -0.321484 0.511984)
							(end -0.381 0.3683)
						)
						(arc
							(start -0.381 -0.3683)
							(mid -0.321484 -0.511984)
							(end -0.1778 -0.5715)
						)
						(arc
							(start 0.1778 -0.5715)
							(mid 0.321484 -0.511984)
							(end 0.381 -0.3683)
						)
						(arc
							(start 0.381 0.3683)
							(mid 0.321484 0.511984)
							(end 0.1778 0.5715)
						)
					)
					(width 0)
					(fill yes)
				)
			)
		)
		(pad "G" smd custom
			(at -0.98425 0.9525)
			(size 0.1905 0.1905)
			(layers "F.Cu" "F.Mask" "F.Paste")
			(net "EXT1_LED_BLUE_G_Q24")
			(options
				(clearance outline)
				(anchor circle)
			)
			(primitives
				(gr_poly
					(pts
						(arc
							(start -0.1778 0.5715)
							(mid -0.321484 0.511984)
							(end -0.381 0.3683)
						)
						(arc
							(start -0.381 -0.3683)
							(mid -0.321484 -0.511984)
							(end -0.1778 -0.5715)
						)
						(arc
							(start 0.1778 -0.5715)
							(mid 0.321484 -0.511984)
							(end 0.381 -0.3683)
						)
						(arc
							(start 0.381 0.3683)
							(mid 0.321484 0.511984)
							(end 0.1778 0.5715)
						)
					)
					(width 0)
					(fill yes)
				)
			)
		)
		(pad "S" smd custom
			(at 0.98425 0.9525)
			(size 0.1905 0.1905)
			(layers "F.Cu" "F.Mask" "F.Paste")
			(net "GND")
			(options
				(clearance outline)
				(anchor circle)
			)
			(primitives
				(gr_poly
					(pts
						(arc
							(start -0.1778 0.5715)
							(mid -0.321484 0.511984)
							(end -0.381 0.3683)
						)
						(arc
							(start -0.381 -0.3683)
							(mid -0.321484 -0.511984)
							(end -0.1778 -0.5715)
						)
						(arc
							(start 0.1778 -0.5715)
							(mid 0.321484 -0.511984)
							(end 0.381 -0.3683)
						)
						(arc
							(start 0.381 0.3683)
							(mid 0.321484 0.511984)
							(end 0.1778 0.5715)
						)
					)
					(width 0)
					(fill yes)
				)
			)
		)
	)
	(footprint ""
		(layer "F.Cu")
		(at 188.4172 -127.3302 -90)
		(property "Reference" "R564"
			(at 0 0 270)
			(layer "F.SilkS")
			(hide yes)
			(effects
				(font
					(size 1.27 1.27)
				)
			)
		)
		(property "Value" "7K32R2F-GP"
			(at 0.064008 -3.993896 270)
			(unlocked yes)
			(layer "F.Fab")
			(hide yes)
			(effects
				(font
					(size 1.016 1.016)
					(thickness 0.1524)
				)
			)
		)
		(property "Device Type" "R402H16"
			(at 0.064008 -5.517896 270)
			(unlocked yes)
			(layer "F.Fab")
			(hide yes)
			(effects
				(font
					(size 1.016 1.016)
					(thickness 0.1524)
				)
			)
		)
		(duplicate_pad_numbers_are_jumpers no)
		(fp_line
			(start -0.508 -0.9398)
			(end -0.508 0.9398)
			(stroke
				(width 0.1524)
				(type default)
			)
			(layer "F.SilkS")
		)
		(fp_line
			(start 0.508 -0.9398)
			(end -0.508 -0.9398)
			(stroke
				(width 0.1524)
				(type default)
			)
			(layer "F.SilkS")
		)
		(fp_rect
			(start -0.508 0.9398)
			(end 0.508 -0.9398)
			(stroke
				(width 0)
				(type default)
			)
			(fill no)
			(layer "F.CrtYd")
		)
		(fp_rect
			(start -0.508 0.9398)
			(end 0.508 -0.9398)
			(stroke
				(width 0)
				(type default)
			)
			(fill no)
			(layer "F.Fab")
		)
		(pad "1" smd custom
			(at 0 -0.4445 270)
			(size 0.1397 0.1397)
			(layers "F.Cu" "F.Mask" "F.Paste")
			(net "VT235_VREF")
			(options
				(clearance outline)
				(anchor circle)
			)
			(primitives
				(gr_poly
					(pts
						(arc
							(start -0.1778 -0.2794)
							(mid -0.249642 -0.249642)
							(end -0.2794 -0.1778)
						)
						(arc
							(start -0.2794 0.1778)
							(mid -0.249642 0.249642)
							(end -0.1778 0.2794)
						)
						(arc
							(start 0.1778 0.2794)
							(mid 0.249642 0.249642)
							(end 0.2794 0.1778)
						)
						(arc
							(start 0.2794 -0.1778)
							(mid 0.249642 -0.249642)
							(end 0.1778 -0.2794)
						)
					)
					(width 0)
					(fill yes)
				)
			)
		)
		(pad "2" smd custom
			(at 0 0.4445 270)
			(size 0.1397 0.1397)
			(layers "F.Cu" "F.Mask" "F.Paste")
			(net "VT235_VDES_RR")
			(options
				(clearance outline)
				(anchor circle)
			)
			(primitives
				(gr_poly
					(pts
						(arc
							(start -0.1778 -0.2794)
							(mid -0.249642 -0.249642)
							(end -0.2794 -0.1778)
						)
						(arc
							(start -0.2794 0.1778)
							(mid -0.249642 0.249642)
							(end -0.1778 0.2794)
						)
						(arc
							(start 0.1778 0.2794)
							(mid 0.249642 0.249642)
							(end 0.2794 0.1778)
						)
						(arc
							(start 0.2794 -0.1778)
							(mid 0.249642 -0.249642)
							(end 0.1778 -0.2794)
						)
					)
					(width 0)
					(fill yes)
				)
			)
		)
	)
	(footprint ""
		(layer "F.Cu")
		(at 195.51777 -10.09269 90)
		(property "Reference" "R733"
			(at 0 0 90)
			(layer "F.SilkS")
			(hide yes)
			(effects
				(font
					(size 1.27 1.27)
				)
			)
		)
		(property "Value" "120R3F-L-GP"
			(at -0.0254 -2.5146 90)
			(unlocked yes)
			(layer "F.Fab")
			(hide yes)
			(effects
				(font
					(size 1.016 1.016)
					(thickness 0.1524)
				)
			)
		)
		(property "Device Type" "R603H22"
			(at -0.0254 -4.0386 90)
			(unlocked yes)
			(layer "F.Fab")
			(hide yes)
			(effects
				(font
					(size 1.016 1.016)
					(thickness 0.1524)
				)
			)
		)
		(duplicate_pad_numbers_are_jumpers no)
		(fp_line
			(start 0.2032 0)
			(end 0.4826 0)
			(stroke
				(width 0.2032)
				(type default)
			)
			(layer "F.SilkS")
		)
		(fp_line
			(start -0.4826 0)
			(end -0.2032 0)
			(stroke
				(width 0.2032)
				(type default)
			)
			(layer "F.SilkS")
		)
		(fp_rect
			(start -0.5842 1.3335)
			(end 0.5842 -1.3335)
			(stroke
				(width 0)
				(type default)
			)
			(fill no)
			(layer "F.CrtYd")
		)
		(fp_rect
			(start -0.5842 1.3335)
			(end 0.5842 -1.3335)
			(stroke
				(width 0)
				(type default)
			)
			(fill no)
			(layer "F.Fab")
		)
		(pad "1" smd custom
			(at 0 -0.762 90)
			(size 0.2159 0.2159)
			(layers "F.Cu" "F.Mask" "F.Paste")
			(net "EXT1_LED_YELLOW_D1")
			(options
				(clearance outline)
				(anchor circle)
			)
			(primitives
				(gr_poly
					(pts
						(arc
							(start -0.3302 -0.4318)
							(mid -0.402042 -0.402042)
							(end -0.4318 -0.3302)
						)
						(arc
							(start -0.4318 0.3302)
							(mid -0.402042 0.402042)
							(end -0.3302 0.4318)
						)
						(arc
							(start 0.3302 0.4318)
							(mid 0.402042 0.402042)
							(end 0.4318 0.3302)
						)
						(arc
							(start 0.4318 -0.3302)
							(mid 0.402042 -0.402042)
							(end 0.3302 -0.4318)
						)
					)
					(width 0)
					(fill yes)
				)
			)
		)
		(pad "2" smd custom
			(at 0 0.762 90)
			(size 0.2159 0.2159)
			(layers "F.Cu" "F.Mask" "F.Paste")
			(net "EXT1_LED_YELLOW")
			(options
				(clearance outline)
				(anchor circle)
			)
			(primitives
				(gr_poly
					(pts
						(arc
							(start -0.3302 -0.4318)
							(mid -0.402042 -0.402042)
							(end -0.4318 -0.3302)
						)
						(arc
							(start -0.4318 0.3302)
							(mid -0.402042 0.402042)
							(end -0.3302 0.4318)
						)
						(arc
							(start 0.3302 0.4318)
							(mid 0.402042 0.402042)
							(end 0.4318 0.3302)
						)
						(arc
							(start 0.4318 -0.3302)
							(mid 0.402042 -0.402042)
							(end 0.3302 -0.4318)
						)
					)
					(width 0)
					(fill yes)
				)
			)
		)
	)
	(footprint ""
		(layer "F.Cu")
		(at 88.773 -127.9144 -90)
		(property "Reference" "R715"
			(at 0 0 270)
			(layer "F.SilkS")
			(hide yes)
			(effects
				(font
					(size 1.27 1.27)
				)
			)
		)
		(property "Value" "0R2J-2-GP"
			(at 0.064008 -3.993896 270)
			(unlocked yes)
			(layer "F.Fab")
			(hide yes)
			(effects
				(font
					(size 1.016 1.016)
					(thickness 0.1524)
				)
			)
		)
		(property "Device Type" "R402H16"
			(at 0.064008 -5.517896 270)
			(unlocked yes)
			(layer "F.Fab")
			(hide yes)
			(effects
				(font
					(size 1.016 1.016)
					(thickness 0.1524)
				)
			)
		)
		(duplicate_pad_numbers_are_jumpers no)
		(fp_line
			(start -0.508 -0.9398)
			(end -0.508 0.9398)
			(stroke
				(width 0.1524)
				(type default)
			)
			(layer "F.SilkS")
		)
		(fp_line
			(start 0.508 -0.9398)
			(end -0.508 -0.9398)
			(stroke
				(width 0.1524)
				(type default)
			)
			(layer "F.SilkS")
		)
		(fp_rect
			(start -0.508 0.9398)
			(end 0.508 -0.9398)
			(stroke
				(width 0)
				(type default)
			)
			(fill no)
			(layer "F.CrtYd")
		)
		(fp_rect
			(start -0.508 0.9398)
			(end 0.508 -0.9398)
			(stroke
				(width 0)
				(type default)
			)
			(fill no)
			(layer "F.Fab")
		)
		(pad "1" smd custom
			(at 0 -0.4445 270)
			(size 0.1397 0.1397)
			(layers "F.Cu" "F.Mask" "F.Paste")
			(net "UART_SEL_MUX")
			(options
				(clearance outline)
				(anchor circle)
			)
			(primitives
				(gr_poly
					(pts
						(arc
							(start -0.1778 -0.2794)
							(mid -0.249642 -0.249642)
							(end -0.2794 -0.1778)
						)
						(arc
							(start -0.2794 0.1778)
							(mid -0.249642 0.249642)
							(end -0.1778 0.2794)
						)
						(arc
							(start 0.1778 0.2794)
							(mid 0.249642 0.249642)
							(end 0.2794 0.1778)
						)
						(arc
							(start 0.2794 -0.1778)
							(mid 0.249642 -0.249642)
							(end 0.1778 -0.2794)
						)
					)
					(width 0)
					(fill yes)
				)
			)
		)
		(pad "2" smd custom
			(at 0 0.4445 270)
			(size 0.1397 0.1397)
			(layers "F.Cu" "F.Mask" "F.Paste")
			(net "BMC_UART_SEL_OUT")
			(options
				(clearance outline)
				(anchor circle)
			)
			(primitives
				(gr_poly
					(pts
						(arc
							(start -0.1778 -0.2794)
							(mid -0.249642 -0.249642)
							(end -0.2794 -0.1778)
						)
						(arc
							(start -0.2794 0.1778)
							(mid -0.249642 0.249642)
							(end -0.1778 0.2794)
						)
						(arc
							(start 0.1778 0.2794)
							(mid 0.249642 0.249642)
							(end 0.2794 0.1778)
						)
						(arc
							(start 0.2794 -0.1778)
							(mid 0.249642 -0.249642)
							(end 0.1778 -0.2794)
						)
					)
					(width 0)
					(fill yes)
				)
			)
		)
	)
	(footprint ""
		(layer "F.Cu")
		(at 79.231744 -153.745184 180)
		(property "Reference" "R536"
			(at 0 0 180)
			(layer "F.SilkS")
			(hide yes)
			(effects
				(font
					(size 1.27 1.27)
				)
			)
		)
		(property "Value" "0R5J-5-GP"
			(at 0 -8.9535 180)
			(unlocked yes)
			(layer "F.Fab")
			(hide yes)
			(effects
				(font
					(size 1.27 1.016)
					(thickness 0.1524)
				)
			)
		)
		(property "Device Type" "R805H24"
			(at 0 -10.6299 180)
			(unlocked yes)
			(layer "F.Fab")
			(hide yes)
			(effects
				(font
					(size 1.27 1.016)
					(thickness 0.1524)
				)
			)
		)
		(duplicate_pad_numbers_are_jumpers no)
		(fp_line
			(start 0.889 1.7018)
			(end 0.889 -0.508)
			(stroke
				(width 0.1524)
				(type default)
			)
			(layer "F.SilkS")
		)
		(fp_line
			(start 0.889 -1.7018)
			(end 0.889 -0.381)
			(stroke
				(width 0.1524)
				(type default)
			)
			(layer "F.SilkS")
		)
		(fp_line
			(start 0.889 -1.7018)
			(end -0.889 -1.7018)
			(stroke
				(width 0.1524)
				(type default)
			)
			(layer "F.SilkS")
		)
		(fp_line
			(start -0.889 1.7018)
			(end 0.889 1.7018)
			(stroke
				(width 0.1524)
				(type default)
			)
			(layer "F.SilkS")
		)
		(fp_line
			(start -0.889 0.0762)
			(end -0.889 1.7018)
			(stroke
				(width 0.1524)
				(type default)
			)
			(layer "F.SilkS")
		)
		(fp_line
			(start -0.889 -1.7018)
			(end -0.889 0.2794)
			(stroke
				(width 0.1524)
				(type default)
			)
			(layer "F.SilkS")
		)
		(fp_poly
			(pts
				(xy 0.9652 -1.778) (xy 0.9652 1.778) (xy -0.9652 1.778) (xy -0.9652 -1.778)
			)
			(stroke
				(width 0)
				(type default)
			)
			(fill no)
			(layer "F.CrtYd")
		)
		(fp_rect
			(start -0.9652 1.778)
			(end 0.9652 -1.778)
			(stroke
				(width 0)
				(type default)
			)
			(fill no)
			(layer "F.Fab")
		)
		(pad "1" smd rect
			(at 0 -0.9652 180)
			(size 1.397 1.143)
			(layers "F.Cu" "F.Mask" "F.Paste")
			(net "P1V15_STBY")
		)
		(pad "2" smd rect
			(at 0 0.9652 180)
			(size 1.397 1.143)
			(layers "F.Cu" "F.Mask" "F.Paste")
			(net "TPS74801_P1V15_STBY_OUT")
		)
	)
	(footprint ""
		(layer "F.Cu")
		(at 63.459868 -180.08854)
		(property "Reference" "R356"
			(at 0 0 0)
			(layer "F.SilkS")
			(hide yes)
			(effects
				(font
					(size 1.27 1.27)
				)
			)
		)
		(property "Value" "0R2J-2-GP"
			(at 0.064008 -3.993896 0)
			(unlocked yes)
			(layer "F.Fab")
			(hide yes)
			(effects
				(font
					(size 1.016 1.016)
					(thickness 0.1524)
				)
			)
		)
		(property "Device Type" "R402H16"
			(at 0.064008 -5.517896 0)
			(unlocked yes)
			(layer "F.Fab")
			(hide yes)
			(effects
				(font
					(size 1.016 1.016)
					(thickness 0.1524)
				)
			)
		)
		(duplicate_pad_numbers_are_jumpers no)
		(fp_line
			(start -0.508 -0.9398)
			(end -0.508 0.9398)
			(stroke
				(width 0.1524)
				(type default)
			)
			(layer "F.SilkS")
		)
		(fp_line
			(start 0.508 -0.9398)
			(end -0.508 -0.9398)
			(stroke
				(width 0.1524)
				(type default)
			)
			(layer "F.SilkS")
		)
		(fp_rect
			(start -0.508 0.9398)
			(end 0.508 -0.9398)
			(stroke
				(width 0)
				(type default)
			)
			(fill no)
			(layer "F.CrtYd")
		)
		(fp_rect
			(start -0.508 0.9398)
			(end 0.508 -0.9398)
			(stroke
				(width 0)
				(type default)
			)
			(fill no)
			(layer "F.Fab")
		)
		(pad "1" smd custom
			(at 0 -0.4445)
			(size 0.1397 0.1397)
			(layers "F.Cu" "F.Mask" "F.Paste")
			(net "IOM_STBY_PGOOD")
			(options
				(clearance outline)
				(anchor circle)
			)
			(primitives
				(gr_poly
					(pts
						(arc
							(start -0.1778 -0.2794)
							(mid -0.249642 -0.249642)
							(end -0.2794 -0.1778)
						)
						(arc
							(start -0.2794 0.1778)
							(mid -0.249642 0.249642)
							(end -0.1778 0.2794)
						)
						(arc
							(start 0.1778 0.2794)
							(mid 0.249642 0.249642)
							(end 0.2794 0.1778)
						)
						(arc
							(start 0.2794 -0.1778)
							(mid 0.249642 -0.249642)
							(end 0.1778 -0.2794)
						)
					)
					(width 0)
					(fill yes)
				)
			)
		)
		(pad "2" smd custom
			(at 0 0.4445)
			(size 0.1397 0.1397)
			(layers "F.Cu" "F.Mask" "F.Paste")
			(net "FM_BMC_RESET_N")
			(options
				(clearance outline)
				(anchor circle)
			)
			(primitives
				(gr_poly
					(pts
						(arc
							(start -0.1778 -0.2794)
							(mid -0.249642 -0.249642)
							(end -0.2794 -0.1778)
						)
						(arc
							(start -0.2794 0.1778)
							(mid -0.249642 0.249642)
							(end -0.1778 0.2794)
						)
						(arc
							(start 0.1778 0.2794)
							(mid 0.249642 0.249642)
							(end 0.2794 0.1778)
						)
						(arc
							(start 0.2794 -0.1778)
							(mid 0.249642 -0.249642)
							(end 0.1778 -0.2794)
						)
					)
					(width 0)
					(fill yes)
				)
			)
		)
	)
	(footprint ""
		(layer "F.Cu")
		(at 82.441796 -175.58258 90)
		(property "Reference" "C191"
			(at 0 0 90)
			(layer "F.SilkS")
			(hide yes)
			(effects
				(font
					(size 1.27 1.27)
				)
			)
		)
		(property "Value" "SC10U6D3V5KX-4GP"
			(at -0.0762 -6.1214 90)
			(unlocked yes)
			(layer "F.Fab")
			(hide yes)
			(effects
				(font
					(size 1.016 1.016)
					(thickness 0.1524)
				)
			)
		)
		(property "Device Type" "C805H58"
			(at -0.0762 -8.1534 90)
			(unlocked yes)
			(layer "F.Fab")
			(hide yes)
			(effects
				(font
					(size 1.016 1.016)
					(thickness 0.1524)
				)
			)
		)
		(duplicate_pad_numbers_are_jumpers no)
		(fp_line
			(start 0.635 0)
			(end -0.635 0)
			(stroke
				(width 0.508)
				(type default)
			)
			(layer "F.SilkS")
		)
		(fp_rect
			(start -0.9652 1.778)
			(end 0.9652 -1.778)
			(stroke
				(width 0)
				(type default)
			)
			(fill no)
			(layer "F.CrtYd")
		)
		(fp_poly
			(pts
				(xy -0.9652 -1.778) (xy 0.9652 -1.778) (xy 0.9652 1.778) (xy -0.9652 1.778)
			)
			(stroke
				(width 0)
				(type default)
			)
			(fill no)
			(layer "F.Fab")
		)
		(pad "1" smd rect
			(at 0 -0.9652 90)
			(size 1.397 1.143)
			(layers "F.Cu" "F.Mask" "F.Paste")
			(net "TPS74801_P2V5_STBY_OUT")
		)
		(pad "2" smd rect
			(at 0 0.9652 90)
			(size 1.397 1.143)
			(layers "F.Cu" "F.Mask" "F.Paste")
			(net "GND")
		)
	)
	(footprint ""
		(layer "F.Cu")
		(at 93.124528 -49.429416 180)
		(property "Reference" "C507"
			(at 0 0 180)
			(layer "F.SilkS")
			(hide yes)
			(effects
				(font
					(size 1.27 1.27)
				)
			)
		)
		(property "Value" "SCD1U16V2KX-3GP"
			(at 1.1811 -2.7051 180)
			(unlocked yes)
			(layer "F.Fab")
			(hide yes)
			(effects
				(font
					(size 1.016 1.016)
					(thickness 0.1524)
				)
			)
		)
		(property "Device Type" "C402H22"
			(at 1.1811 -4.2291 180)
			(unlocked yes)
			(layer "F.Fab")
			(hide yes)
			(effects
				(font
					(size 1.016 1.016)
					(thickness 0.1524)
				)
			)
		)
		(duplicate_pad_numbers_are_jumpers no)
		(fp_rect
			(start -0.4318 0.9525)
			(end 0.4318 -0.9525)
			(stroke
				(width 0)
				(type default)
			)
			(fill no)
			(layer "F.CrtYd")
		)
		(fp_rect
			(start -0.4318 0.9525)
			(end 0.4318 -0.9525)
			(stroke
				(width 0)
				(type default)
			)
			(fill no)
			(layer "F.Fab")
		)
		(pad "1" smd custom
			(at 0 -0.4445 180)
			(size 0.1524 0.1524)
			(layers "F.Cu" "F.Mask" "F.Paste")
			(net "P3V3_EN_R")
			(options
				(clearance outline)
				(anchor circle)
			)
			(primitives
				(gr_poly
					(pts
						(arc
							(start 0.3048 -0.2032)
							(mid 0.275042 -0.275042)
							(end 0.2032 -0.3048)
						)
						(arc
							(start -0.2032 -0.3048)
							(mid -0.275042 -0.275042)
							(end -0.3048 -0.2032)
						)
						(arc
							(start -0.3048 0.2032)
							(mid -0.275042 0.275042)
							(end -0.2032 0.3048)
						)
						(arc
							(start 0.2032 0.3048)
							(mid 0.275042 0.275042)
							(end 0.3048 0.2032)
						)
					)
					(width 0)
					(fill yes)
				)
			)
		)
		(pad "2" smd custom
			(at 0 0.4445 180)
			(size 0.1524 0.1524)
			(layers "F.Cu" "F.Mask" "F.Paste")
			(net "GND")
			(options
				(clearance outline)
				(anchor circle)
			)
			(primitives
				(gr_poly
					(pts
						(arc
							(start 0.3048 -0.2032)
							(mid 0.275042 -0.275042)
							(end 0.2032 -0.3048)
						)
						(arc
							(start -0.2032 -0.3048)
							(mid -0.275042 -0.275042)
							(end -0.3048 -0.2032)
						)
						(arc
							(start -0.3048 0.2032)
							(mid -0.275042 0.275042)
							(end -0.2032 0.3048)
						)
						(arc
							(start 0.2032 0.3048)
							(mid 0.275042 0.275042)
							(end 0.3048 0.2032)
						)
					)
					(width 0)
					(fill yes)
				)
			)
		)
	)
	(footprint ""
		(layer "F.Cu")
		(at 133.9088 -12.5476 -90)
		(property "Reference" "R443"
			(at 0 0 270)
			(layer "F.SilkS")
			(hide yes)
			(effects
				(font
					(size 1.27 1.27)
				)
			)
		)
		(property "Value" "10R2F-L-GP"
			(at 0.064008 -3.993896 270)
			(unlocked yes)
			(layer "F.Fab")
			(hide yes)
			(effects
				(font
					(size 1.016 1.016)
					(thickness 0.1524)
				)
			)
		)
		(property "Device Type" "R402H14"
			(at 0.064008 -5.517896 270)
			(unlocked yes)
			(layer "F.Fab")
			(hide yes)
			(effects
				(font
					(size 1.016 1.016)
					(thickness 0.1524)
				)
			)
		)
		(duplicate_pad_numbers_are_jumpers no)
		(fp_line
			(start -0.508 -0.9398)
			(end -0.508 0.9398)
			(stroke
				(width 0.1524)
				(type default)
			)
			(layer "F.SilkS")
		)
		(fp_line
			(start 0.508 -0.9398)
			(end -0.508 -0.9398)
			(stroke
				(width 0.1524)
				(type default)
			)
			(layer "F.SilkS")
		)
		(fp_rect
			(start -0.508 0.9398)
			(end 0.508 -0.9398)
			(stroke
				(width 0)
				(type default)
			)
			(fill no)
			(layer "F.CrtYd")
		)
		(fp_rect
			(start -0.508 0.9398)
			(end 0.508 -0.9398)
			(stroke
				(width 0)
				(type default)
			)
			(fill no)
			(layer "F.Fab")
		)
		(pad "1" smd custom
			(at 0 -0.4445 270)
			(size 0.1397 0.1397)
			(layers "F.Cu" "F.Mask" "F.Paste")
			(net "MB0_CM_SENSE_R1_N")
			(options
				(clearance outline)
				(anchor circle)
			)
			(primitives
				(gr_poly
					(pts
						(arc
							(start -0.1778 -0.2794)
							(mid -0.249642 -0.249642)
							(end -0.2794 -0.1778)
						)
						(arc
							(start -0.2794 0.1778)
							(mid -0.249642 0.249642)
							(end -0.1778 0.2794)
						)
						(arc
							(start 0.1778 0.2794)
							(mid 0.249642 0.249642)
							(end 0.2794 0.1778)
						)
						(arc
							(start 0.2794 -0.1778)
							(mid 0.249642 -0.249642)
							(end 0.1778 -0.2794)
						)
					)
					(width 0)
					(fill yes)
				)
			)
		)
		(pad "2" smd custom
			(at 0 0.4445 270)
			(size 0.1397 0.1397)
			(layers "F.Cu" "F.Mask" "F.Paste")
			(net "ADM1278_HS_N")
			(options
				(clearance outline)
				(anchor circle)
			)
			(primitives
				(gr_poly
					(pts
						(arc
							(start -0.1778 -0.2794)
							(mid -0.249642 -0.249642)
							(end -0.2794 -0.1778)
						)
						(arc
							(start -0.2794 0.1778)
							(mid -0.249642 0.249642)
							(end -0.1778 0.2794)
						)
						(arc
							(start 0.1778 0.2794)
							(mid 0.249642 0.249642)
							(end 0.2794 0.1778)
						)
						(arc
							(start 0.2794 -0.1778)
							(mid 0.249642 -0.249642)
							(end 0.1778 -0.2794)
						)
					)
					(width 0)
					(fill yes)
				)
			)
		)
	)
	(footprint ""
		(layer "F.Cu")
		(at 44.958 -157.9118)
		(property "Reference" "R173"
			(at 0 0 0)
			(layer "F.SilkS")
			(hide yes)
			(effects
				(font
					(size 1.27 1.27)
				)
			)
		)
		(property "Value" "0R2J-2-GP"
			(at 0.064008 -3.993896 0)
			(unlocked yes)
			(layer "F.Fab")
			(hide yes)
			(effects
				(font
					(size 1.016 1.016)
					(thickness 0.1524)
				)
			)
		)
		(property "Device Type" "R402H16"
			(at 0.064008 -5.517896 0)
			(unlocked yes)
			(layer "F.Fab")
			(hide yes)
			(effects
				(font
					(size 1.016 1.016)
					(thickness 0.1524)
				)
			)
		)
		(duplicate_pad_numbers_are_jumpers no)
		(fp_line
			(start -0.508 -0.9398)
			(end -0.508 0.9398)
			(stroke
				(width 0.1524)
				(type default)
			)
			(layer "F.SilkS")
		)
		(fp_line
			(start 0.508 -0.9398)
			(end -0.508 -0.9398)
			(stroke
				(width 0.1524)
				(type default)
			)
			(layer "F.SilkS")
		)
		(fp_rect
			(start -0.508 0.9398)
			(end 0.508 -0.9398)
			(stroke
				(width 0)
				(type default)
			)
			(fill no)
			(layer "F.CrtYd")
		)
		(fp_rect
			(start -0.508 0.9398)
			(end 0.508 -0.9398)
			(stroke
				(width 0)
				(type default)
			)
			(fill no)
			(layer "F.Fab")
		)
		(pad "1" smd custom
			(at 0 -0.4445)
			(size 0.1397 0.1397)
			(layers "F.Cu" "F.Mask" "F.Paste")
			(net "I2C_M2_1_SCL")
			(options
				(clearance outline)
				(anchor circle)
			)
			(primitives
				(gr_poly
					(pts
						(arc
							(start -0.1778 -0.2794)
							(mid -0.249642 -0.249642)
							(end -0.2794 -0.1778)
						)
						(arc
							(start -0.2794 0.1778)
							(mid -0.249642 0.249642)
							(end -0.1778 0.2794)
						)
						(arc
							(start 0.1778 0.2794)
							(mid 0.249642 0.249642)
							(end 0.2794 0.1778)
						)
						(arc
							(start 0.2794 -0.1778)
							(mid 0.249642 -0.249642)
							(end 0.1778 -0.2794)
						)
					)
					(width 0)
					(fill yes)
				)
			)
		)
		(pad "2" smd custom
			(at 0 0.4445)
			(size 0.1397 0.1397)
			(layers "F.Cu" "F.Mask" "F.Paste")
			(net "BMC_SMB8_CLK")
			(options
				(clearance outline)
				(anchor circle)
			)
			(primitives
				(gr_poly
					(pts
						(arc
							(start -0.1778 -0.2794)
							(mid -0.249642 -0.249642)
							(end -0.2794 -0.1778)
						)
						(arc
							(start -0.2794 0.1778)
							(mid -0.249642 0.249642)
							(end -0.1778 0.2794)
						)
						(arc
							(start 0.1778 0.2794)
							(mid 0.249642 0.249642)
							(end 0.2794 0.1778)
						)
						(arc
							(start 0.2794 -0.1778)
							(mid 0.249642 -0.249642)
							(end 0.1778 -0.2794)
						)
					)
					(width 0)
					(fill yes)
				)
			)
		)
	)
	(footprint ""
		(layer "F.Cu")
		(at 54.0004 -131.7498)
		(property "Reference" "R147"
			(at 0 0 0)
			(layer "F.SilkS")
			(hide yes)
			(effects
				(font
					(size 1.27 1.27)
				)
			)
		)
		(property "Value" "100KR2F-L1-GP"
			(at 0.064008 -3.993896 0)
			(unlocked yes)
			(layer "F.Fab")
			(hide yes)
			(effects
				(font
					(size 1.016 1.016)
					(thickness 0.1524)
				)
			)
		)
		(property "Device Type" "R402H16"
			(at 0.064008 -5.517896 0)
			(unlocked yes)
			(layer "F.Fab")
			(hide yes)
			(effects
				(font
					(size 1.016 1.016)
					(thickness 0.1524)
				)
			)
		)
		(duplicate_pad_numbers_are_jumpers no)
		(fp_line
			(start -0.508 -0.9398)
			(end -0.508 0.9398)
			(stroke
				(width 0.1524)
				(type default)
			)
			(layer "F.SilkS")
		)
		(fp_line
			(start 0.508 -0.9398)
			(end -0.508 -0.9398)
			(stroke
				(width 0.1524)
				(type default)
			)
			(layer "F.SilkS")
		)
		(fp_rect
			(start -0.508 0.9398)
			(end 0.508 -0.9398)
			(stroke
				(width 0)
				(type default)
			)
			(fill no)
			(layer "F.CrtYd")
		)
		(fp_rect
			(start -0.508 0.9398)
			(end 0.508 -0.9398)
			(stroke
				(width 0)
				(type default)
			)
			(fill no)
			(layer "F.Fab")
		)
		(pad "1" smd custom
			(at 0 -0.4445)
			(size 0.1397 0.1397)
			(layers "F.Cu" "F.Mask" "F.Paste")
			(net "LPC_CPU_FRAME_N")
			(options
				(clearance outline)
				(anchor circle)
			)
			(primitives
				(gr_poly
					(pts
						(arc
							(start -0.1778 -0.2794)
							(mid -0.249642 -0.249642)
							(end -0.2794 -0.1778)
						)
						(arc
							(start -0.2794 0.1778)
							(mid -0.249642 0.249642)
							(end -0.1778 0.2794)
						)
						(arc
							(start 0.1778 0.2794)
							(mid 0.249642 0.249642)
							(end 0.2794 0.1778)
						)
						(arc
							(start 0.2794 -0.1778)
							(mid 0.249642 -0.249642)
							(end 0.1778 -0.2794)
						)
					)
					(width 0)
					(fill yes)
				)
			)
		)
		(pad "2" smd custom
			(at 0 0.4445)
			(size 0.1397 0.1397)
			(layers "F.Cu" "F.Mask" "F.Paste")
			(net "GND")
			(options
				(clearance outline)
				(anchor circle)
			)
			(primitives
				(gr_poly
					(pts
						(arc
							(start -0.1778 -0.2794)
							(mid -0.249642 -0.249642)
							(end -0.2794 -0.1778)
						)
						(arc
							(start -0.2794 0.1778)
							(mid -0.249642 0.249642)
							(end -0.1778 0.2794)
						)
						(arc
							(start 0.1778 0.2794)
							(mid 0.249642 0.249642)
							(end 0.2794 0.1778)
						)
						(arc
							(start 0.2794 -0.1778)
							(mid 0.249642 -0.249642)
							(end 0.1778 -0.2794)
						)
					)
					(width 0)
					(fill yes)
				)
			)
		)
	)
	(footprint ""
		(layer "F.Cu")
		(at 218.694 -102.8954 180)
		(property "Reference" "R605"
			(at 0 0 180)
			(layer "F.SilkS")
			(hide yes)
			(effects
				(font
					(size 1.27 1.27)
				)
			)
		)
		(property "Value" "4K7R2F-GP"
			(at 0.064008 -3.993896 180)
			(unlocked yes)
			(layer "F.Fab")
			(hide yes)
			(effects
				(font
					(size 1.016 1.016)
					(thickness 0.1524)
				)
			)
		)
		(property "Device Type" "R402H16"
			(at 0.064008 -5.517896 180)
			(unlocked yes)
			(layer "F.Fab")
			(hide yes)
			(effects
				(font
					(size 1.016 1.016)
					(thickness 0.1524)
				)
			)
		)
		(duplicate_pad_numbers_are_jumpers no)
		(fp_line
			(start 0.508 -0.9398)
			(end -0.508 -0.9398)
			(stroke
				(width 0.1524)
				(type default)
			)
			(layer "F.SilkS")
		)
		(fp_line
			(start -0.508 -0.9398)
			(end -0.508 0.9398)
			(stroke
				(width 0.1524)
				(type default)
			)
			(layer "F.SilkS")
		)
		(fp_rect
			(start -0.508 0.9398)
			(end 0.508 -0.9398)
			(stroke
				(width 0)
				(type default)
			)
			(fill no)
			(layer "F.CrtYd")
		)
		(fp_rect
			(start -0.508 0.9398)
			(end 0.508 -0.9398)
			(stroke
				(width 0)
				(type default)
			)
			(fill no)
			(layer "F.Fab")
		)
		(pad "1" smd custom
			(at 0 -0.4445 180)
			(size 0.1397 0.1397)
			(layers "F.Cu" "F.Mask" "F.Paste")
			(net "IOC_EEPROM_A2")
			(options
				(clearance outline)
				(anchor circle)
			)
			(primitives
				(gr_poly
					(pts
						(arc
							(start -0.1778 -0.2794)
							(mid -0.249642 -0.249642)
							(end -0.2794 -0.1778)
						)
						(arc
							(start -0.2794 0.1778)
							(mid -0.249642 0.249642)
							(end -0.1778 0.2794)
						)
						(arc
							(start 0.1778 0.2794)
							(mid 0.249642 0.249642)
							(end 0.2794 0.1778)
						)
						(arc
							(start 0.2794 -0.1778)
							(mid 0.249642 -0.249642)
							(end 0.1778 -0.2794)
						)
					)
					(width 0)
					(fill yes)
				)
			)
		)
		(pad "2" smd custom
			(at 0 0.4445 180)
			(size 0.1397 0.1397)
			(layers "F.Cu" "F.Mask" "F.Paste")
			(net "GND")
			(options
				(clearance outline)
				(anchor circle)
			)
			(primitives
				(gr_poly
					(pts
						(arc
							(start -0.1778 -0.2794)
							(mid -0.249642 -0.249642)
							(end -0.2794 -0.1778)
						)
						(arc
							(start -0.2794 0.1778)
							(mid -0.249642 0.249642)
							(end -0.1778 0.2794)
						)
						(arc
							(start 0.1778 0.2794)
							(mid 0.249642 0.249642)
							(end 0.2794 0.1778)
						)
						(arc
							(start 0.2794 -0.1778)
							(mid 0.249642 -0.249642)
							(end 0.1778 -0.2794)
						)
					)
					(width 0)
					(fill yes)
				)
			)
		)
	)
	(footprint ""
		(layer "F.Cu")
		(at 74.4601 -136.398 180)
		(property "Reference" "R738"
			(at 0 0 180)
			(layer "F.SilkS")
			(hide yes)
			(effects
				(font
					(size 1.27 1.27)
				)
			)
		)
		(property "Value" "4K7R2F-GP"
			(at 0.064008 -3.993896 180)
			(unlocked yes)
			(layer "F.Fab")
			(hide yes)
			(effects
				(font
					(size 1.016 1.016)
					(thickness 0.1524)
				)
			)
		)
		(property "Device Type" "R402H16"
			(at 0.064008 -5.517896 180)
			(unlocked yes)
			(layer "F.Fab")
			(hide yes)
			(effects
				(font
					(size 1.016 1.016)
					(thickness 0.1524)
				)
			)
		)
		(duplicate_pad_numbers_are_jumpers no)
		(fp_line
			(start 0.508 -0.9398)
			(end -0.508 -0.9398)
			(stroke
				(width 0.1524)
				(type default)
			)
			(layer "F.SilkS")
		)
		(fp_line
			(start -0.508 -0.9398)
			(end -0.508 0.9398)
			(stroke
				(width 0.1524)
				(type default)
			)
			(layer "F.SilkS")
		)
		(fp_rect
			(start -0.508 0.9398)
			(end 0.508 -0.9398)
			(stroke
				(width 0)
				(type default)
			)
			(fill no)
			(layer "F.CrtYd")
		)
		(fp_rect
			(start -0.508 0.9398)
			(end 0.508 -0.9398)
			(stroke
				(width 0)
				(type default)
			)
			(fill no)
			(layer "F.Fab")
		)
		(pad "1" smd custom
			(at 0 -0.4445 180)
			(size 0.1397 0.1397)
			(layers "F.Cu" "F.Mask" "F.Paste")
			(net "P3V3_STBY")
			(options
				(clearance outline)
				(anchor circle)
			)
			(primitives
				(gr_poly
					(pts
						(arc
							(start -0.1778 -0.2794)
							(mid -0.249642 -0.249642)
							(end -0.2794 -0.1778)
						)
						(arc
							(start -0.2794 0.1778)
							(mid -0.249642 0.249642)
							(end -0.1778 0.2794)
						)
						(arc
							(start 0.1778 0.2794)
							(mid 0.249642 0.249642)
							(end 0.2794 0.1778)
						)
						(arc
							(start 0.2794 -0.1778)
							(mid 0.249642 -0.249642)
							(end 0.1778 -0.2794)
						)
					)
					(width 0)
					(fill yes)
				)
			)
		)
		(pad "2" smd custom
			(at 0 0.4445 180)
			(size 0.1397 0.1397)
			(layers "F.Cu" "F.Mask" "F.Paste")
			(net "DEBUG_HDR_UART_SEL")
			(options
				(clearance outline)
				(anchor circle)
			)
			(primitives
				(gr_poly
					(pts
						(arc
							(start -0.1778 -0.2794)
							(mid -0.249642 -0.249642)
							(end -0.2794 -0.1778)
						)
						(arc
							(start -0.2794 0.1778)
							(mid -0.249642 0.249642)
							(end -0.1778 0.2794)
						)
						(arc
							(start 0.1778 0.2794)
							(mid 0.249642 0.249642)
							(end 0.2794 0.1778)
						)
						(arc
							(start 0.2794 -0.1778)
							(mid 0.249642 -0.249642)
							(end 0.1778 -0.2794)
						)
					)
					(width 0)
					(fill yes)
				)
			)
		)
	)
	(footprint ""
		(layer "F.Cu")
		(at 28.2448 -180.7464)
		(property "Reference" "R495"
			(at 0 0 0)
			(layer "F.SilkS")
			(hide yes)
			(effects
				(font
					(size 1.27 1.27)
				)
			)
		)
		(property "Value" "866KR2F-GP"
			(at 0.064008 -3.993896 0)
			(unlocked yes)
			(layer "F.Fab")
			(hide yes)
			(effects
				(font
					(size 1.016 1.016)
					(thickness 0.1524)
				)
			)
		)
		(property "Device Type" "R402H16"
			(at 0.064008 -5.517896 0)
			(unlocked yes)
			(layer "F.Fab")
			(hide yes)
			(effects
				(font
					(size 1.016 1.016)
					(thickness 0.1524)
				)
			)
		)
		(duplicate_pad_numbers_are_jumpers no)
		(fp_line
			(start -0.508 -0.9398)
			(end -0.508 0.9398)
			(stroke
				(width 0.1524)
				(type default)
			)
			(layer "F.SilkS")
		)
		(fp_line
			(start 0.508 -0.9398)
			(end -0.508 -0.9398)
			(stroke
				(width 0.1524)
				(type default)
			)
			(layer "F.SilkS")
		)
		(fp_rect
			(start -0.508 0.9398)
			(end 0.508 -0.9398)
			(stroke
				(width 0)
				(type default)
			)
			(fill no)
			(layer "F.CrtYd")
		)
		(fp_rect
			(start -0.508 0.9398)
			(end 0.508 -0.9398)
			(stroke
				(width 0)
				(type default)
			)
			(fill no)
			(layer "F.Fab")
		)
		(pad "1" smd custom
			(at 0 -0.4445)
			(size 0.1397 0.1397)
			(layers "F.Cu" "F.Mask" "F.Paste")
			(net "P3V3_STBY_VREG")
			(options
				(clearance outline)
				(anchor circle)
			)
			(primitives
				(gr_poly
					(pts
						(arc
							(start -0.1778 -0.2794)
							(mid -0.249642 -0.249642)
							(end -0.2794 -0.1778)
						)
						(arc
							(start -0.2794 0.1778)
							(mid -0.249642 0.249642)
							(end -0.1778 0.2794)
						)
						(arc
							(start 0.1778 0.2794)
							(mid 0.249642 0.249642)
							(end 0.2794 0.1778)
						)
						(arc
							(start 0.2794 -0.1778)
							(mid 0.249642 -0.249642)
							(end 0.1778 -0.2794)
						)
					)
					(width 0)
					(fill yes)
				)
			)
		)
		(pad "2" smd custom
			(at 0 0.4445)
			(size 0.1397 0.1397)
			(layers "F.Cu" "F.Mask" "F.Paste")
			(net "P3V3_STBY_RF")
			(options
				(clearance outline)
				(anchor circle)
			)
			(primitives
				(gr_poly
					(pts
						(arc
							(start -0.1778 -0.2794)
							(mid -0.249642 -0.249642)
							(end -0.2794 -0.1778)
						)
						(arc
							(start -0.2794 0.1778)
							(mid -0.249642 0.249642)
							(end -0.1778 0.2794)
						)
						(arc
							(start 0.1778 0.2794)
							(mid 0.249642 0.249642)
							(end 0.2794 0.1778)
						)
						(arc
							(start 0.2794 -0.1778)
							(mid 0.249642 -0.249642)
							(end 0.1778 -0.2794)
						)
					)
					(width 0)
					(fill yes)
				)
			)
		)
	)
	(footprint ""
		(layer "F.Cu")
		(at 122.9614 -17.265142 90)
		(property "Reference" "R434"
			(at 0 0 90)
			(layer "F.SilkS")
			(hide yes)
			(effects
				(font
					(size 1.27 1.27)
				)
			)
		)
		(property "Value" "100R2D-GP"
			(at 0.064008 -3.993896 90)
			(unlocked yes)
			(layer "F.Fab")
			(hide yes)
			(effects
				(font
					(size 1.016 1.016)
					(thickness 0.1524)
				)
			)
		)
		(property "Device Type" "R402H14"
			(at 0.064008 -5.517896 90)
			(unlocked yes)
			(layer "F.Fab")
			(hide yes)
			(effects
				(font
					(size 1.016 1.016)
					(thickness 0.1524)
				)
			)
		)
		(duplicate_pad_numbers_are_jumpers no)
		(fp_line
			(start 0.508 -0.9398)
			(end -0.508 -0.9398)
			(stroke
				(width 0.1524)
				(type default)
			)
			(layer "F.SilkS")
		)
		(fp_line
			(start -0.508 -0.9398)
			(end -0.508 0.9398)
			(stroke
				(width 0.1524)
				(type default)
			)
			(layer "F.SilkS")
		)
		(fp_rect
			(start -0.508 0.9398)
			(end 0.508 -0.9398)
			(stroke
				(width 0)
				(type default)
			)
			(fill no)
			(layer "F.CrtYd")
		)
		(fp_rect
			(start -0.508 0.9398)
			(end 0.508 -0.9398)
			(stroke
				(width 0)
				(type default)
			)
			(fill no)
			(layer "F.Fab")
		)
		(pad "1" smd custom
			(at 0 -0.4445 90)
			(size 0.1397 0.1397)
			(layers "F.Cu" "F.Mask" "F.Paste")
			(net "GND")
			(options
				(clearance outline)
				(anchor circle)
			)
			(primitives
				(gr_poly
					(pts
						(arc
							(start -0.1778 -0.2794)
							(mid -0.249642 -0.249642)
							(end -0.2794 -0.1778)
						)
						(arc
							(start -0.2794 0.1778)
							(mid -0.249642 0.249642)
							(end -0.1778 0.2794)
						)
						(arc
							(start 0.1778 0.2794)
							(mid 0.249642 0.249642)
							(end 0.2794 0.1778)
						)
						(arc
							(start 0.2794 -0.1778)
							(mid 0.249642 -0.249642)
							(end 0.1778 -0.2794)
						)
					)
					(width 0)
					(fill yes)
				)
			)
		)
		(pad "2" smd custom
			(at 0 0.4445 90)
			(size 0.1397 0.1397)
			(layers "F.Cu" "F.Mask" "F.Paste")
			(net "MB0_TEMP_E")
			(options
				(clearance outline)
				(anchor circle)
			)
			(primitives
				(gr_poly
					(pts
						(arc
							(start -0.1778 -0.2794)
							(mid -0.249642 -0.249642)
							(end -0.2794 -0.1778)
						)
						(arc
							(start -0.2794 0.1778)
							(mid -0.249642 0.249642)
							(end -0.1778 0.2794)
						)
						(arc
							(start 0.1778 0.2794)
							(mid 0.249642 0.249642)
							(end 0.2794 0.1778)
						)
						(arc
							(start 0.2794 -0.1778)
							(mid 0.249642 -0.249642)
							(end 0.1778 -0.2794)
						)
					)
					(width 0)
					(fill yes)
				)
			)
		)
	)
	(footprint ""
		(layer "F.Cu")
		(at 53.4416 -125.8062 90)
		(property "Reference" "R269"
			(at 0 0 90)
			(layer "F.SilkS")
			(hide yes)
			(effects
				(font
					(size 1.27 1.27)
				)
			)
		)
		(property "Value" "2K2R2J-2-GP"
			(at 0.064008 -3.993896 90)
			(unlocked yes)
			(layer "F.Fab")
			(hide yes)
			(effects
				(font
					(size 1.016 1.016)
					(thickness 0.1524)
				)
			)
		)
		(property "Device Type" "R402H16"
			(at 0.064008 -5.517896 90)
			(unlocked yes)
			(layer "F.Fab")
			(hide yes)
			(effects
				(font
					(size 1.016 1.016)
					(thickness 0.1524)
				)
			)
		)
		(duplicate_pad_numbers_are_jumpers no)
		(fp_line
			(start 0.508 -0.9398)
			(end -0.508 -0.9398)
			(stroke
				(width 0.1524)
				(type default)
			)
			(layer "F.SilkS")
		)
		(fp_line
			(start -0.508 -0.9398)
			(end -0.508 0.9398)
			(stroke
				(width 0.1524)
				(type default)
			)
			(layer "F.SilkS")
		)
		(fp_rect
			(start -0.508 0.9398)
			(end 0.508 -0.9398)
			(stroke
				(width 0)
				(type default)
			)
			(fill no)
			(layer "F.CrtYd")
		)
		(fp_rect
			(start -0.508 0.9398)
			(end 0.508 -0.9398)
			(stroke
				(width 0)
				(type default)
			)
			(fill no)
			(layer "F.Fab")
		)
		(pad "1" smd custom
			(at 0 -0.4445 90)
			(size 0.1397 0.1397)
			(layers "F.Cu" "F.Mask" "F.Paste")
			(net "P3V3_STBY")
			(options
				(clearance outline)
				(anchor circle)
			)
			(primitives
				(gr_poly
					(pts
						(arc
							(start -0.1778 -0.2794)
							(mid -0.249642 -0.249642)
							(end -0.2794 -0.1778)
						)
						(arc
							(start -0.2794 0.1778)
							(mid -0.249642 0.249642)
							(end -0.1778 0.2794)
						)
						(arc
							(start 0.1778 0.2794)
							(mid 0.249642 0.249642)
							(end 0.2794 0.1778)
						)
						(arc
							(start 0.2794 -0.1778)
							(mid 0.249642 -0.249642)
							(end 0.1778 -0.2794)
						)
					)
					(width 0)
					(fill yes)
				)
			)
		)
		(pad "2" smd custom
			(at 0 0.4445 90)
			(size 0.1397 0.1397)
			(layers "F.Cu" "F.Mask" "F.Paste")
			(net "FLA1_WP_N")
			(options
				(clearance outline)
				(anchor circle)
			)
			(primitives
				(gr_poly
					(pts
						(arc
							(start -0.1778 -0.2794)
							(mid -0.249642 -0.249642)
							(end -0.2794 -0.1778)
						)
						(arc
							(start -0.2794 0.1778)
							(mid -0.249642 0.249642)
							(end -0.1778 0.2794)
						)
						(arc
							(start 0.1778 0.2794)
							(mid 0.249642 0.249642)
							(end 0.2794 0.1778)
						)
						(arc
							(start 0.2794 -0.1778)
							(mid 0.249642 -0.249642)
							(end 0.1778 -0.2794)
						)
					)
					(width 0)
					(fill yes)
				)
			)
		)
	)
	(footprint ""
		(layer "F.Cu")
		(at 184.1754 -110.109 90)
		(property "Reference" "C269"
			(at 0 0 90)
			(layer "F.SilkS")
			(hide yes)
			(effects
				(font
					(size 1.27 1.27)
				)
			)
		)
		(property "Value" "SC10U16V5KX-7-GP-U"
			(at -0.0762 -6.1214 90)
			(unlocked yes)
			(layer "F.Fab")
			(hide yes)
			(effects
				(font
					(size 1.016 1.016)
					(thickness 0.1524)
				)
			)
		)
		(property "Device Type" "C805H58"
			(at -0.0762 -8.1534 90)
			(unlocked yes)
			(layer "F.Fab")
			(hide yes)
			(effects
				(font
					(size 1.016 1.016)
					(thickness 0.1524)
				)
			)
		)
		(duplicate_pad_numbers_are_jumpers no)
		(fp_line
			(start 0.635 0)
			(end -0.635 0)
			(stroke
				(width 0.508)
				(type default)
			)
			(layer "F.SilkS")
		)
		(fp_rect
			(start -0.9652 1.778)
			(end 0.9652 -1.778)
			(stroke
				(width 0)
				(type default)
			)
			(fill no)
			(layer "F.CrtYd")
		)
		(fp_poly
			(pts
				(xy -0.9652 -1.778) (xy 0.9652 -1.778) (xy 0.9652 1.778) (xy -0.9652 1.778)
			)
			(stroke
				(width 0)
				(type default)
			)
			(fill no)
			(layer "F.Fab")
		)
		(pad "1" smd rect
			(at 0 -0.9652 90)
			(size 1.397 1.143)
			(layers "F.Cu" "F.Mask" "F.Paste")
			(net "VT235_VDDH")
		)
		(pad "2" smd rect
			(at 0 0.9652 90)
			(size 1.397 1.143)
			(layers "F.Cu" "F.Mask" "F.Paste")
			(net "GND")
		)
	)
	(footprint ""
		(layer "F.Cu")
		(at 67.2084 -144.0942 -90)
		(property "Reference" "R385"
			(at 0 0 270)
			(layer "F.SilkS")
			(hide yes)
			(effects
				(font
					(size 1.27 1.27)
				)
			)
		)
		(property "Value" "4K7R2F-GP"
			(at 0.064008 -3.993896 270)
			(unlocked yes)
			(layer "F.Fab")
			(hide yes)
			(effects
				(font
					(size 1.016 1.016)
					(thickness 0.1524)
				)
			)
		)
		(property "Device Type" "R402H16"
			(at 0.064008 -5.517896 270)
			(unlocked yes)
			(layer "F.Fab")
			(hide yes)
			(effects
				(font
					(size 1.016 1.016)
					(thickness 0.1524)
				)
			)
		)
		(duplicate_pad_numbers_are_jumpers no)
		(fp_line
			(start -0.508 -0.9398)
			(end -0.508 0.9398)
			(stroke
				(width 0.1524)
				(type default)
			)
			(layer "F.SilkS")
		)
		(fp_line
			(start 0.508 -0.9398)
			(end -0.508 -0.9398)
			(stroke
				(width 0.1524)
				(type default)
			)
			(layer "F.SilkS")
		)
		(fp_rect
			(start -0.508 0.9398)
			(end 0.508 -0.9398)
			(stroke
				(width 0)
				(type default)
			)
			(fill no)
			(layer "F.CrtYd")
		)
		(fp_rect
			(start -0.508 0.9398)
			(end 0.508 -0.9398)
			(stroke
				(width 0)
				(type default)
			)
			(fill no)
			(layer "F.Fab")
		)
		(pad "1" smd custom
			(at 0 -0.4445 270)
			(size 0.1397 0.1397)
			(layers "F.Cu" "F.Mask" "F.Paste")
			(net "GND")
			(options
				(clearance outline)
				(anchor circle)
			)
			(primitives
				(gr_poly
					(pts
						(arc
							(start -0.1778 -0.2794)
							(mid -0.249642 -0.249642)
							(end -0.2794 -0.1778)
						)
						(arc
							(start -0.2794 0.1778)
							(mid -0.249642 0.249642)
							(end -0.1778 0.2794)
						)
						(arc
							(start 0.1778 0.2794)
							(mid 0.249642 0.249642)
							(end 0.2794 0.1778)
						)
						(arc
							(start 0.2794 -0.1778)
							(mid 0.249642 -0.249642)
							(end 0.1778 -0.2794)
						)
					)
					(width 0)
					(fill yes)
				)
			)
		)
		(pad "2" smd custom
			(at 0 0.4445 270)
			(size 0.1397 0.1397)
			(layers "F.Cu" "F.Mask" "F.Paste")
			(net "NCSI_TXEN")
			(options
				(clearance outline)
				(anchor circle)
			)
			(primitives
				(gr_poly
					(pts
						(arc
							(start -0.1778 -0.2794)
							(mid -0.249642 -0.249642)
							(end -0.2794 -0.1778)
						)
						(arc
							(start -0.2794 0.1778)
							(mid -0.249642 0.249642)
							(end -0.1778 0.2794)
						)
						(arc
							(start 0.1778 0.2794)
							(mid 0.249642 0.249642)
							(end 0.2794 0.1778)
						)
						(arc
							(start 0.2794 -0.1778)
							(mid 0.249642 -0.249642)
							(end 0.1778 -0.2794)
						)
					)
					(width 0)
					(fill yes)
				)
			)
		)
	)
	(footprint ""
		(layer "F.Cu")
		(at 188.6458 -117.21592)
		(property "Reference" "R7909"
			(at 0 0 0)
			(layer "F.SilkS")
			(hide yes)
			(effects
				(font
					(size 1.27 1.27)
				)
			)
		)
		(property "Value" "2D2R5F-2-GP"
			(at 0 -8.9535 0)
			(unlocked yes)
			(layer "F.Fab")
			(hide yes)
			(effects
				(font
					(size 1.27 1.016)
					(thickness 0.1524)
				)
			)
		)
		(property "Device Type" "R805H24"
			(at 0 -10.6299 0)
			(unlocked yes)
			(layer "F.Fab")
			(hide yes)
			(effects
				(font
					(size 1.27 1.016)
					(thickness 0.1524)
				)
			)
		)
		(duplicate_pad_numbers_are_jumpers no)
		(fp_line
			(start -0.889 -1.7018)
			(end -0.889 0.2794)
			(stroke
				(width 0.1524)
				(type default)
			)
			(layer "F.SilkS")
		)
		(fp_line
			(start -0.889 0.0762)
			(end -0.889 1.7018)
			(stroke
				(width 0.1524)
				(type default)
			)
			(layer "F.SilkS")
		)
		(fp_line
			(start -0.889 1.7018)
			(end 0.889 1.7018)
			(stroke
				(width 0.1524)
				(type default)
			)
			(layer "F.SilkS")
		)
		(fp_line
			(start 0.889 -1.7018)
			(end -0.889 -1.7018)
			(stroke
				(width 0.1524)
				(type default)
			)
			(layer "F.SilkS")
		)
		(fp_line
			(start 0.889 -1.7018)
			(end 0.889 -0.381)
			(stroke
				(width 0.1524)
				(type default)
			)
			(layer "F.SilkS")
		)
		(fp_line
			(start 0.889 1.7018)
			(end 0.889 -0.508)
			(stroke
				(width 0.1524)
				(type default)
			)
			(layer "F.SilkS")
		)
		(fp_poly
			(pts
				(xy 0.9652 -1.778) (xy 0.9652 1.778) (xy -0.9652 1.778) (xy -0.9652 -1.778)
			)
			(stroke
				(width 0)
				(type default)
			)
			(fill no)
			(layer "F.CrtYd")
		)
		(fp_rect
			(start -0.9652 1.778)
			(end 0.9652 -1.778)
			(stroke
				(width 0)
				(type default)
			)
			(fill no)
			(layer "F.Fab")
		)
		(pad "1" smd rect
			(at 0 -0.9652)
			(size 1.397 1.143)
			(layers "F.Cu" "F.Mask" "F.Paste")
			(net "VT235_VX")
		)
		(pad "2" smd rect
			(at 0 0.9652)
			(size 1.397 1.143)
			(layers "F.Cu" "F.Mask" "F.Paste")
			(net "N62640349")
		)
	)
	(footprint ""
		(layer "F.Cu")
		(at 98.8695 -161.886392 -90)
		(property "Reference" "R32"
			(at 0 0 270)
			(layer "F.SilkS")
			(hide yes)
			(effects
				(font
					(size 1.27 1.27)
				)
			)
		)
		(property "Value" "4K7R2F-GP"
			(at 0.064008 -3.993896 270)
			(unlocked yes)
			(layer "F.Fab")
			(hide yes)
			(effects
				(font
					(size 1.016 1.016)
					(thickness 0.1524)
				)
			)
		)
		(property "Device Type" "R402H16"
			(at 0.064008 -5.517896 270)
			(unlocked yes)
			(layer "F.Fab")
			(hide yes)
			(effects
				(font
					(size 1.016 1.016)
					(thickness 0.1524)
				)
			)
		)
		(duplicate_pad_numbers_are_jumpers no)
		(fp_line
			(start -0.508 -0.9398)
			(end -0.508 0.9398)
			(stroke
				(width 0.1524)
				(type default)
			)
			(layer "F.SilkS")
		)
		(fp_line
			(start 0.508 -0.9398)
			(end -0.508 -0.9398)
			(stroke
				(width 0.1524)
				(type default)
			)
			(layer "F.SilkS")
		)
		(fp_rect
			(start -0.508 0.9398)
			(end 0.508 -0.9398)
			(stroke
				(width 0)
				(type default)
			)
			(fill no)
			(layer "F.CrtYd")
		)
		(fp_rect
			(start -0.508 0.9398)
			(end 0.508 -0.9398)
			(stroke
				(width 0)
				(type default)
			)
			(fill no)
			(layer "F.Fab")
		)
		(pad "1" smd custom
			(at 0 -0.4445 270)
			(size 0.1397 0.1397)
			(layers "F.Cu" "F.Mask" "F.Paste")
			(net "P3V3_STBY")
			(options
				(clearance outline)
				(anchor circle)
			)
			(primitives
				(gr_poly
					(pts
						(arc
							(start -0.1778 -0.2794)
							(mid -0.249642 -0.249642)
							(end -0.2794 -0.1778)
						)
						(arc
							(start -0.2794 0.1778)
							(mid -0.249642 0.249642)
							(end -0.1778 0.2794)
						)
						(arc
							(start 0.1778 0.2794)
							(mid 0.249642 0.249642)
							(end 0.2794 0.1778)
						)
						(arc
							(start 0.2794 -0.1778)
							(mid 0.249642 -0.249642)
							(end 0.1778 -0.2794)
						)
					)
					(width 0)
					(fill yes)
				)
			)
		)
		(pad "2" smd custom
			(at 0 0.4445 270)
			(size 0.1397 0.1397)
			(layers "F.Cu" "F.Mask" "F.Paste")
			(net "USB_SUSP_IND")
			(options
				(clearance outline)
				(anchor circle)
			)
			(primitives
				(gr_poly
					(pts
						(arc
							(start -0.1778 -0.2794)
							(mid -0.249642 -0.249642)
							(end -0.2794 -0.1778)
						)
						(arc
							(start -0.2794 0.1778)
							(mid -0.249642 0.249642)
							(end -0.1778 0.2794)
						)
						(arc
							(start 0.1778 0.2794)
							(mid 0.249642 0.249642)
							(end 0.2794 0.1778)
						)
						(arc
							(start 0.2794 -0.1778)
							(mid 0.249642 -0.249642)
							(end 0.1778 -0.2794)
						)
					)
					(width 0)
					(fill yes)
				)
			)
		)
	)
	(footprint ""
		(layer "F.Cu")
		(at 118.9228 -16.3322)
		(property "Reference" "R440"
			(at 0 0 0)
			(layer "F.SilkS")
			(hide yes)
			(effects
				(font
					(size 1.27 1.27)
				)
			)
		)
		(property "Value" "10R2F-L-GP"
			(at 0.064008 -3.993896 0)
			(unlocked yes)
			(layer "F.Fab")
			(hide yes)
			(effects
				(font
					(size 1.016 1.016)
					(thickness 0.1524)
				)
			)
		)
		(property "Device Type" "R402H14"
			(at 0.064008 -5.517896 0)
			(unlocked yes)
			(layer "F.Fab")
			(hide yes)
			(effects
				(font
					(size 1.016 1.016)
					(thickness 0.1524)
				)
			)
		)
		(duplicate_pad_numbers_are_jumpers no)
		(fp_line
			(start -0.508 -0.9398)
			(end -0.508 0.9398)
			(stroke
				(width 0.1524)
				(type default)
			)
			(layer "F.SilkS")
		)
		(fp_line
			(start 0.508 -0.9398)
			(end -0.508 -0.9398)
			(stroke
				(width 0.1524)
				(type default)
			)
			(layer "F.SilkS")
		)
		(fp_rect
			(start -0.508 0.9398)
			(end 0.508 -0.9398)
			(stroke
				(width 0)
				(type default)
			)
			(fill no)
			(layer "F.CrtYd")
		)
		(fp_rect
			(start -0.508 0.9398)
			(end 0.508 -0.9398)
			(stroke
				(width 0)
				(type default)
			)
			(fill no)
			(layer "F.Fab")
		)
		(pad "1" smd custom
			(at 0 -0.4445)
			(size 0.1397 0.1397)
			(layers "F.Cu" "F.Mask" "F.Paste")
			(net "MB0_CM_SENSE_R1_P")
			(options
				(clearance outline)
				(anchor circle)
			)
			(primitives
				(gr_poly
					(pts
						(arc
							(start -0.1778 -0.2794)
							(mid -0.249642 -0.249642)
							(end -0.2794 -0.1778)
						)
						(arc
							(start -0.2794 0.1778)
							(mid -0.249642 0.249642)
							(end -0.1778 0.2794)
						)
						(arc
							(start 0.1778 0.2794)
							(mid 0.249642 0.249642)
							(end 0.2794 0.1778)
						)
						(arc
							(start 0.2794 -0.1778)
							(mid 0.249642 -0.249642)
							(end 0.1778 -0.2794)
						)
					)
					(width 0)
					(fill yes)
				)
			)
		)
		(pad "2" smd custom
			(at 0 0.4445)
			(size 0.1397 0.1397)
			(layers "F.Cu" "F.Mask" "F.Paste")
			(net "MB0_CM_SENSE_P")
			(options
				(clearance outline)
				(anchor circle)
			)
			(primitives
				(gr_poly
					(pts
						(arc
							(start -0.1778 -0.2794)
							(mid -0.249642 -0.249642)
							(end -0.2794 -0.1778)
						)
						(arc
							(start -0.2794 0.1778)
							(mid -0.249642 0.249642)
							(end -0.1778 0.2794)
						)
						(arc
							(start 0.1778 0.2794)
							(mid 0.249642 0.249642)
							(end 0.2794 0.1778)
						)
						(arc
							(start 0.2794 -0.1778)
							(mid 0.249642 -0.249642)
							(end 0.1778 -0.2794)
						)
					)
					(width 0)
					(fill yes)
				)
			)
		)
	)
	(footprint ""
		(layer "F.Cu")
		(at 53.7972 -181.3306)
		(property "Reference" "C174"
			(at 0 0 0)
			(layer "F.SilkS")
			(hide yes)
			(effects
				(font
					(size 1.27 1.27)
				)
			)
		)
		(property "Value" "SC10U6D3V5KX-4GP"
			(at -0.0762 -6.1214 0)
			(unlocked yes)
			(layer "F.Fab")
			(hide yes)
			(effects
				(font
					(size 1.016 1.016)
					(thickness 0.1524)
				)
			)
		)
		(property "Device Type" "C805H58"
			(at -0.0762 -8.1534 0)
			(unlocked yes)
			(layer "F.Fab")
			(hide yes)
			(effects
				(font
					(size 1.016 1.016)
					(thickness 0.1524)
				)
			)
		)
		(duplicate_pad_numbers_are_jumpers no)
		(fp_line
			(start 0.635 0)
			(end -0.635 0)
			(stroke
				(width 0.508)
				(type default)
			)
			(layer "F.SilkS")
		)
		(fp_rect
			(start -0.9652 1.778)
			(end 0.9652 -1.778)
			(stroke
				(width 0)
				(type default)
			)
			(fill no)
			(layer "F.CrtYd")
		)
		(fp_poly
			(pts
				(xy -0.9652 -1.778) (xy 0.9652 -1.778) (xy 0.9652 1.778) (xy -0.9652 1.778)
			)
			(stroke
				(width 0)
				(type default)
			)
			(fill no)
			(layer "F.Fab")
		)
		(pad "1" smd rect
			(at 0 -0.9652)
			(size 1.397 1.143)
			(layers "F.Cu" "F.Mask" "F.Paste")
			(net "P3V3_STBY_OUT")
		)
		(pad "2" smd rect
			(at 0 0.9652)
			(size 1.397 1.143)
			(layers "F.Cu" "F.Mask" "F.Paste")
			(net "GND")
		)
	)
	(footprint ""
		(layer "F.Cu")
		(at 184.1754 -112.0902 90)
		(property "Reference" "C271"
			(at 0 0 90)
			(layer "F.SilkS")
			(hide yes)
			(effects
				(font
					(size 1.27 1.27)
				)
			)
		)
		(property "Value" "SC10U16V5KX-7-GP-U"
			(at -0.0762 -6.1214 90)
			(unlocked yes)
			(layer "F.Fab")
			(hide yes)
			(effects
				(font
					(size 1.016 1.016)
					(thickness 0.1524)
				)
			)
		)
		(property "Device Type" "C805H58"
			(at -0.0762 -8.1534 90)
			(unlocked yes)
			(layer "F.Fab")
			(hide yes)
			(effects
				(font
					(size 1.016 1.016)
					(thickness 0.1524)
				)
			)
		)
		(duplicate_pad_numbers_are_jumpers no)
		(fp_line
			(start 0.635 0)
			(end -0.635 0)
			(stroke
				(width 0.508)
				(type default)
			)
			(layer "F.SilkS")
		)
		(fp_rect
			(start -0.9652 1.778)
			(end 0.9652 -1.778)
			(stroke
				(width 0)
				(type default)
			)
			(fill no)
			(layer "F.CrtYd")
		)
		(fp_poly
			(pts
				(xy -0.9652 -1.778) (xy 0.9652 -1.778) (xy 0.9652 1.778) (xy -0.9652 1.778)
			)
			(stroke
				(width 0)
				(type default)
			)
			(fill no)
			(layer "F.Fab")
		)
		(pad "1" smd rect
			(at 0 -0.9652 90)
			(size 1.397 1.143)
			(layers "F.Cu" "F.Mask" "F.Paste")
			(net "VT235_VDDH")
		)
		(pad "2" smd rect
			(at 0 0.9652 90)
			(size 1.397 1.143)
			(layers "F.Cu" "F.Mask" "F.Paste")
			(net "GND")
		)
	)
	(footprint ""
		(layer "F.Cu")
		(at 213.2838 -119.253 -90)
		(property "Reference" "R543"
			(at 0 0 270)
			(layer "F.SilkS")
			(hide yes)
			(effects
				(font
					(size 1.27 1.27)
				)
			)
		)
		(property "Value" "0R5J-5-GP"
			(at 0 -8.9535 270)
			(unlocked yes)
			(layer "F.Fab")
			(hide yes)
			(effects
				(font
					(size 1.27 1.016)
					(thickness 0.1524)
				)
			)
		)
		(property "Device Type" "R805H24"
			(at 0 -10.6299 270)
			(unlocked yes)
			(layer "F.Fab")
			(hide yes)
			(effects
				(font
					(size 1.27 1.016)
					(thickness 0.1524)
				)
			)
		)
		(duplicate_pad_numbers_are_jumpers no)
		(fp_line
			(start -0.889 1.7018)
			(end 0.889 1.7018)
			(stroke
				(width 0.1524)
				(type default)
			)
			(layer "F.SilkS")
		)
		(fp_line
			(start 0.889 1.7018)
			(end 0.889 -0.508)
			(stroke
				(width 0.1524)
				(type default)
			)
			(layer "F.SilkS")
		)
		(fp_line
			(start -0.889 0.0762)
			(end -0.889 1.7018)
			(stroke
				(width 0.1524)
				(type default)
			)
			(layer "F.SilkS")
		)
		(fp_line
			(start -0.889 -1.7018)
			(end -0.889 0.2794)
			(stroke
				(width 0.1524)
				(type default)
			)
			(layer "F.SilkS")
		)
		(fp_line
			(start 0.889 -1.7018)
			(end 0.889 -0.381)
			(stroke
				(width 0.1524)
				(type default)
			)
			(layer "F.SilkS")
		)
		(fp_line
			(start 0.889 -1.7018)
			(end -0.889 -1.7018)
			(stroke
				(width 0.1524)
				(type default)
			)
			(layer "F.SilkS")
		)
		(fp_poly
			(pts
				(xy 0.9652 -1.778) (xy 0.9652 1.778) (xy -0.9652 1.778) (xy -0.9652 -1.778)
			)
			(stroke
				(width 0)
				(type default)
			)
			(fill no)
			(layer "F.CrtYd")
		)
		(fp_rect
			(start -0.9652 1.778)
			(end 0.9652 -1.778)
			(stroke
				(width 0)
				(type default)
			)
			(fill no)
			(layer "F.Fab")
		)
		(pad "1" smd rect
			(at 0 -0.9652 270)
			(size 1.397 1.143)
			(layers "F.Cu" "F.Mask" "F.Paste")
			(net "P1V5")
		)
		(pad "2" smd rect
			(at 0 0.9652 270)
			(size 1.397 1.143)
			(layers "F.Cu" "F.Mask" "F.Paste")
			(net "P1V5_OUT")
		)
	)
	(footprint ""
		(layer "F.Cu")
		(at 84.983828 -78.949296 90)
		(property "Reference" "VIA11"
			(at 0 0 90)
			(layer "F.SilkS")
			(hide yes)
			(effects
				(font
					(size 1.27 1.27)
				)
			)
		)
		(property "Value" "85OHM-8L-1D6MM-L16L18-GP"
			(at 4.064 0.6096 90)
			(unlocked yes)
			(layer "F.Fab")
			(hide yes)
			(effects
				(font
					(size 1.016 1.016)
					(thickness 0.1524)
				)
			)
		)
		(property "Device Type" "VIA-PCIE-4P-368076"
			(at 4.064 -0.9144 90)
			(unlocked yes)
			(layer "F.Fab")
			(hide yes)
			(effects
				(font
					(size 1.016 1.016)
					(thickness 0.1524)
				)
			)
		)
		(duplicate_pad_numbers_are_jumpers no)
		(fp_rect
			(start -1.8415 0.381)
			(end 1.8415 -0.381)
			(stroke
				(width 0)
				(type default)
			)
			(fill no)
			(layer "F.CrtYd")
		)
		(fp_rect
			(start -1.8415 0.381)
			(end 1.8415 -0.381)
			(stroke
				(width 0)
				(type default)
			)
			(fill no)
			(layer "F.Fab")
		)
		(pad "1" thru_hole circle
			(at -1.4605 0 90)
			(size 0.508 0.508)
			(drill 0.254)
			(layers "*.Cu" "*.Mask")
			(remove_unused_layers no)
			(net "GND")
			(clearance 0.127)
			(thermal_gap 0.127)
		)
		(pad "2" thru_hole circle
			(at -0.4445 0 90)
			(size 0.508 0.508)
			(drill 0.254)
			(layers "*.Cu" "*.Mask")
			(remove_unused_layers no)
			(net "PCIE_IOM_TO_COMP_18_DP")
			(clearance 0.127)
			(thermal_gap 0.127)
		)
		(pad "3" thru_hole circle
			(at 0.4445 0 90)
			(size 0.508 0.508)
			(drill 0.254)
			(layers "*.Cu" "*.Mask")
			(remove_unused_layers no)
			(net "PCIE_IOM_TO_COMP_18_DN")
			(clearance 0.127)
			(thermal_gap 0.127)
		)
		(pad "4" thru_hole circle
			(at 1.4605 0 90)
			(size 0.508 0.508)
			(drill 0.254)
			(layers "*.Cu" "*.Mask")
			(remove_unused_layers no)
			(net "GND")
			(clearance 0.127)
			(thermal_gap 0.127)
		)
	)
	(footprint ""
		(layer "F.Cu")
		(at 63.499492 -139.755626)
		(property "Reference" "TP16"
			(at 0 0 0)
			(layer "F.SilkS")
			(hide yes)
			(effects
				(font
					(size 1.27 1.27)
				)
			)
		)
		(property "Value" "TPAD28-2-GP"
			(at -0.0127 -1.6637 0)
			(unlocked yes)
			(layer "F.Fab")
			(hide yes)
			(effects
				(font
					(size 1.016 1.016)
					(thickness 0.1524)
				)
			)
		)
		(property "Device Type" "TPAD28"
			(at -0.0127 -3.1877 0)
			(unlocked yes)
			(layer "F.Fab")
			(hide yes)
			(effects
				(font
					(size 1.016 1.016)
					(thickness 0.1524)
				)
			)
		)
		(duplicate_pad_numbers_are_jumpers no)
		(fp_poly
			(pts
				(arc
					(start 0.3556 0)
					(mid -0.3556 0)
					(end 0.3556 0)
				)
			)
			(stroke
				(width 0)
				(type default)
			)
			(fill no)
			(layer "F.CrtYd")
		)
		(fp_poly
			(pts
				(arc
					(start 0.6096 0)
					(mid -0.6096 0)
					(end 0.6096 0)
				)
			)
			(stroke
				(width 0)
				(type default)
			)
			(fill no)
			(layer "F.Fab")
		)
		(pad "1" smd circle
			(at 0 0)
			(size 0.7112 0.7112)
			(layers "F.Cu" "F.Mask" "F.Paste")
			(net "I2C_M2_2_SDA")
		)
	)
	(footprint ""
		(layer "F.Cu")
		(at 98.9076 -155.0162 90)
		(property "Reference" "R23"
			(at 0 0 90)
			(layer "F.SilkS")
			(hide yes)
			(effects
				(font
					(size 1.27 1.27)
				)
			)
		)
		(property "Value" "4K7R2F-GP"
			(at 0.064008 -3.993896 90)
			(unlocked yes)
			(layer "F.Fab")
			(hide yes)
			(effects
				(font
					(size 1.016 1.016)
					(thickness 0.1524)
				)
			)
		)
		(property "Device Type" "R402H16"
			(at 0.064008 -5.517896 90)
			(unlocked yes)
			(layer "F.Fab")
			(hide yes)
			(effects
				(font
					(size 1.016 1.016)
					(thickness 0.1524)
				)
			)
		)
		(duplicate_pad_numbers_are_jumpers no)
		(fp_line
			(start 0.508 -0.9398)
			(end -0.508 -0.9398)
			(stroke
				(width 0.1524)
				(type default)
			)
			(layer "F.SilkS")
		)
		(fp_line
			(start -0.508 -0.9398)
			(end -0.508 0.9398)
			(stroke
				(width 0.1524)
				(type default)
			)
			(layer "F.SilkS")
		)
		(fp_rect
			(start -0.508 0.9398)
			(end 0.508 -0.9398)
			(stroke
				(width 0)
				(type default)
			)
			(fill no)
			(layer "F.CrtYd")
		)
		(fp_rect
			(start -0.508 0.9398)
			(end 0.508 -0.9398)
			(stroke
				(width 0)
				(type default)
			)
			(fill no)
			(layer "F.Fab")
		)
		(pad "1" smd custom
			(at 0 -0.4445 90)
			(size 0.1397 0.1397)
			(layers "F.Cu" "F.Mask" "F.Paste")
			(net "CFG_SEL0")
			(options
				(clearance outline)
				(anchor circle)
			)
			(primitives
				(gr_poly
					(pts
						(arc
							(start -0.1778 -0.2794)
							(mid -0.249642 -0.249642)
							(end -0.2794 -0.1778)
						)
						(arc
							(start -0.2794 0.1778)
							(mid -0.249642 0.249642)
							(end -0.1778 0.2794)
						)
						(arc
							(start 0.1778 0.2794)
							(mid 0.249642 0.249642)
							(end 0.2794 0.1778)
						)
						(arc
							(start 0.2794 -0.1778)
							(mid 0.249642 -0.249642)
							(end 0.1778 -0.2794)
						)
					)
					(width 0)
					(fill yes)
				)
			)
		)
		(pad "2" smd custom
			(at 0 0.4445 90)
			(size 0.1397 0.1397)
			(layers "F.Cu" "F.Mask" "F.Paste")
			(net "GND")
			(options
				(clearance outline)
				(anchor circle)
			)
			(primitives
				(gr_poly
					(pts
						(arc
							(start -0.1778 -0.2794)
							(mid -0.249642 -0.249642)
							(end -0.2794 -0.1778)
						)
						(arc
							(start -0.2794 0.1778)
							(mid -0.249642 0.249642)
							(end -0.1778 0.2794)
						)
						(arc
							(start 0.1778 0.2794)
							(mid 0.249642 0.249642)
							(end 0.2794 0.1778)
						)
						(arc
							(start 0.2794 -0.1778)
							(mid 0.249642 -0.249642)
							(end 0.1778 -0.2794)
						)
					)
					(width 0)
					(fill yes)
				)
			)
		)
	)
	(footprint ""
		(layer "F.Cu")
		(at 161.835338 -101.218238)
		(property "Reference" "R626"
			(at 0 0 0)
			(layer "F.SilkS")
			(hide yes)
			(effects
				(font
					(size 1.27 1.27)
				)
			)
		)
		(property "Value" "10KR2F-2-GP"
			(at 0.064008 -3.993896 0)
			(unlocked yes)
			(layer "F.Fab")
			(hide yes)
			(effects
				(font
					(size 1.016 1.016)
					(thickness 0.1524)
				)
			)
		)
		(property "Device Type" "R402H16"
			(at 0.064008 -5.517896 0)
			(unlocked yes)
			(layer "F.Fab")
			(hide yes)
			(effects
				(font
					(size 1.016 1.016)
					(thickness 0.1524)
				)
			)
		)
		(duplicate_pad_numbers_are_jumpers no)
		(fp_line
			(start -0.508 -0.9398)
			(end -0.508 0.9398)
			(stroke
				(width 0.1524)
				(type default)
			)
			(layer "F.SilkS")
		)
		(fp_line
			(start 0.508 -0.9398)
			(end -0.508 -0.9398)
			(stroke
				(width 0.1524)
				(type default)
			)
			(layer "F.SilkS")
		)
		(fp_rect
			(start -0.508 0.9398)
			(end 0.508 -0.9398)
			(stroke
				(width 0)
				(type default)
			)
			(fill no)
			(layer "F.CrtYd")
		)
		(fp_rect
			(start -0.508 0.9398)
			(end 0.508 -0.9398)
			(stroke
				(width 0)
				(type default)
			)
			(fill no)
			(layer "F.Fab")
		)
		(pad "1" smd custom
			(at 0 -0.4445)
			(size 0.1397 0.1397)
			(layers "F.Cu" "F.Mask" "F.Paste")
			(net "P1V8")
			(options
				(clearance outline)
				(anchor circle)
			)
			(primitives
				(gr_poly
					(pts
						(arc
							(start -0.1778 -0.2794)
							(mid -0.249642 -0.249642)
							(end -0.2794 -0.1778)
						)
						(arc
							(start -0.2794 0.1778)
							(mid -0.249642 0.249642)
							(end -0.1778 0.2794)
						)
						(arc
							(start 0.1778 0.2794)
							(mid 0.249642 0.249642)
							(end 0.2794 0.1778)
						)
						(arc
							(start 0.2794 -0.1778)
							(mid 0.249642 -0.249642)
							(end 0.1778 -0.2794)
						)
					)
					(width 0)
					(fill yes)
				)
			)
		)
		(pad "2" smd custom
			(at 0 0.4445)
			(size 0.1397 0.1397)
			(layers "F.Cu" "F.Mask" "F.Paste")
			(net "SYS_HB_LED")
			(options
				(clearance outline)
				(anchor circle)
			)
			(primitives
				(gr_poly
					(pts
						(arc
							(start -0.1778 -0.2794)
							(mid -0.249642 -0.249642)
							(end -0.2794 -0.1778)
						)
						(arc
							(start -0.2794 0.1778)
							(mid -0.249642 0.249642)
							(end -0.1778 0.2794)
						)
						(arc
							(start 0.1778 0.2794)
							(mid 0.249642 0.249642)
							(end 0.2794 0.1778)
						)
						(arc
							(start 0.2794 -0.1778)
							(mid 0.249642 -0.249642)
							(end 0.1778 -0.2794)
						)
					)
					(width 0)
					(fill yes)
				)
			)
		)
	)
	(footprint ""
		(layer "F.Cu")
		(at 184.1246 -124.714 180)
		(property "Reference" "C277"
			(at 0 0 180)
			(layer "F.SilkS")
			(hide yes)
			(effects
				(font
					(size 1.27 1.27)
				)
			)
		)
		(property "Value" "SC1U25V3KX-GP"
			(at 0 -2.8194 180)
			(unlocked yes)
			(layer "F.Fab")
			(hide yes)
			(effects
				(font
					(size 1.016 1.016)
					(thickness 0.1524)
				)
			)
		)
		(property "Device Type" "C603H36"
			(at 0 -4.3434 180)
			(unlocked yes)
			(layer "F.Fab")
			(hide yes)
			(effects
				(font
					(size 1.016 1.016)
					(thickness 0.1524)
				)
			)
		)
		(duplicate_pad_numbers_are_jumpers no)
		(fp_line
			(start 0.508 0)
			(end -0.508 0)
			(stroke
				(width 0.2032)
				(type default)
			)
			(layer "F.SilkS")
		)
		(fp_rect
			(start -0.5842 1.3335)
			(end 0.5842 -1.3335)
			(stroke
				(width 0)
				(type default)
			)
			(fill no)
			(layer "F.CrtYd")
		)
		(fp_rect
			(start -0.5842 1.3335)
			(end 0.5842 -1.3335)
			(stroke
				(width 0)
				(type default)
			)
			(fill no)
			(layer "F.Fab")
		)
		(pad "1" smd custom
			(at 0 -0.762 180)
			(size 0.2159 0.2159)
			(layers "F.Cu" "F.Mask" "F.Paste")
			(net "VT235_AVDD")
			(options
				(clearance outline)
				(anchor circle)
			)
			(primitives
				(gr_poly
					(pts
						(arc
							(start -0.3302 -0.4318)
							(mid -0.402042 -0.402042)
							(end -0.4318 -0.3302)
						)
						(arc
							(start -0.4318 0.3302)
							(mid -0.402042 0.402042)
							(end -0.3302 0.4318)
						)
						(arc
							(start 0.3302 0.4318)
							(mid 0.402042 0.402042)
							(end 0.4318 0.3302)
						)
						(arc
							(start 0.4318 -0.3302)
							(mid 0.402042 -0.402042)
							(end 0.3302 -0.4318)
						)
					)
					(width 0)
					(fill yes)
				)
			)
		)
		(pad "2" smd custom
			(at 0 0.762 180)
			(size 0.2159 0.2159)
			(layers "F.Cu" "F.Mask" "F.Paste")
			(net "AGND_P0V975")
			(options
				(clearance outline)
				(anchor circle)
			)
			(primitives
				(gr_poly
					(pts
						(arc
							(start -0.3302 -0.4318)
							(mid -0.402042 -0.402042)
							(end -0.4318 -0.3302)
						)
						(arc
							(start -0.4318 0.3302)
							(mid -0.402042 0.402042)
							(end -0.3302 0.4318)
						)
						(arc
							(start 0.3302 0.4318)
							(mid 0.402042 0.402042)
							(end 0.4318 0.3302)
						)
						(arc
							(start 0.4318 -0.3302)
							(mid 0.402042 -0.402042)
							(end 0.3302 -0.4318)
						)
					)
					(width 0)
					(fill yes)
				)
			)
		)
	)
	(footprint ""
		(layer "F.Cu")
		(at 61.29274 -136.433306 90)
		(property "Reference" "R354"
			(at 0 0 90)
			(layer "F.SilkS")
			(hide yes)
			(effects
				(font
					(size 1.27 1.27)
				)
			)
		)
		(property "Value" "4K7R2F-GP"
			(at 0.064008 -3.993896 90)
			(unlocked yes)
			(layer "F.Fab")
			(hide yes)
			(effects
				(font
					(size 1.016 1.016)
					(thickness 0.1524)
				)
			)
		)
		(property "Device Type" "R402H16"
			(at 0.064008 -5.517896 90)
			(unlocked yes)
			(layer "F.Fab")
			(hide yes)
			(effects
				(font
					(size 1.016 1.016)
					(thickness 0.1524)
				)
			)
		)
		(duplicate_pad_numbers_are_jumpers no)
		(fp_line
			(start 0.508 -0.9398)
			(end -0.508 -0.9398)
			(stroke
				(width 0.1524)
				(type default)
			)
			(layer "F.SilkS")
		)
		(fp_line
			(start -0.508 -0.9398)
			(end -0.508 0.9398)
			(stroke
				(width 0.1524)
				(type default)
			)
			(layer "F.SilkS")
		)
		(fp_rect
			(start -0.508 0.9398)
			(end 0.508 -0.9398)
			(stroke
				(width 0)
				(type default)
			)
			(fill no)
			(layer "F.CrtYd")
		)
		(fp_rect
			(start -0.508 0.9398)
			(end 0.508 -0.9398)
			(stroke
				(width 0)
				(type default)
			)
			(fill no)
			(layer "F.Fab")
		)
		(pad "1" smd custom
			(at 0 -0.4445 90)
			(size 0.1397 0.1397)
			(layers "F.Cu" "F.Mask" "F.Paste")
			(net "SLOTID_0")
			(options
				(clearance outline)
				(anchor circle)
			)
			(primitives
				(gr_poly
					(pts
						(arc
							(start -0.1778 -0.2794)
							(mid -0.249642 -0.249642)
							(end -0.2794 -0.1778)
						)
						(arc
							(start -0.2794 0.1778)
							(mid -0.249642 0.249642)
							(end -0.1778 0.2794)
						)
						(arc
							(start 0.1778 0.2794)
							(mid 0.249642 0.249642)
							(end 0.2794 0.1778)
						)
						(arc
							(start 0.2794 -0.1778)
							(mid 0.249642 -0.249642)
							(end 0.1778 -0.2794)
						)
					)
					(width 0)
					(fill yes)
				)
			)
		)
		(pad "2" smd custom
			(at 0 0.4445 90)
			(size 0.1397 0.1397)
			(layers "F.Cu" "F.Mask" "F.Paste")
			(net "GND")
			(options
				(clearance outline)
				(anchor circle)
			)
			(primitives
				(gr_poly
					(pts
						(arc
							(start -0.1778 -0.2794)
							(mid -0.249642 -0.249642)
							(end -0.2794 -0.1778)
						)
						(arc
							(start -0.2794 0.1778)
							(mid -0.249642 0.249642)
							(end -0.1778 0.2794)
						)
						(arc
							(start 0.1778 0.2794)
							(mid 0.249642 0.249642)
							(end 0.2794 0.1778)
						)
						(arc
							(start 0.2794 -0.1778)
							(mid 0.249642 -0.249642)
							(end 0.1778 -0.2794)
						)
					)
					(width 0)
					(fill yes)
				)
			)
		)
	)
	(footprint ""
		(layer "F.Cu")
		(at 199.7964 -106.172)
		(property "Reference" "C262"
			(at 0 0 0)
			(layer "F.SilkS")
			(hide yes)
			(effects
				(font
					(size 1.27 1.27)
				)
			)
		)
		(property "Value" "SC6K8P50V2KX-GP"
			(at 1.1811 -2.7051 0)
			(unlocked yes)
			(layer "F.Fab")
			(hide yes)
			(effects
				(font
					(size 1.016 1.016)
					(thickness 0.1524)
				)
			)
		)
		(property "Device Type" "C402H22"
			(at 1.1811 -4.2291 0)
			(unlocked yes)
			(layer "F.Fab")
			(hide yes)
			(effects
				(font
					(size 1.016 1.016)
					(thickness 0.1524)
				)
			)
		)
		(duplicate_pad_numbers_are_jumpers no)
		(fp_rect
			(start -0.4318 0.9525)
			(end 0.4318 -0.9525)
			(stroke
				(width 0)
				(type default)
			)
			(fill no)
			(layer "F.CrtYd")
		)
		(fp_rect
			(start -0.4318 0.9525)
			(end 0.4318 -0.9525)
			(stroke
				(width 0)
				(type default)
			)
			(fill no)
			(layer "F.Fab")
		)
		(pad "1" smd custom
			(at 0 -0.4445)
			(size 0.1524 0.1524)
			(layers "F.Cu" "F.Mask" "F.Paste")
			(net "P0V975")
			(options
				(clearance outline)
				(anchor circle)
			)
			(primitives
				(gr_poly
					(pts
						(arc
							(start 0.3048 -0.2032)
							(mid 0.275042 -0.275042)
							(end 0.2032 -0.3048)
						)
						(arc
							(start -0.2032 -0.3048)
							(mid -0.275042 -0.275042)
							(end -0.3048 -0.2032)
						)
						(arc
							(start -0.3048 0.2032)
							(mid -0.275042 0.275042)
							(end -0.2032 0.3048)
						)
						(arc
							(start 0.2032 0.3048)
							(mid 0.275042 0.275042)
							(end 0.3048 0.2032)
						)
					)
					(width 0)
					(fill yes)
				)
			)
		)
		(pad "2" smd custom
			(at 0 0.4445)
			(size 0.1524 0.1524)
			(layers "F.Cu" "F.Mask" "F.Paste")
			(net "GND")
			(options
				(clearance outline)
				(anchor circle)
			)
			(primitives
				(gr_poly
					(pts
						(arc
							(start 0.3048 -0.2032)
							(mid 0.275042 -0.275042)
							(end 0.2032 -0.3048)
						)
						(arc
							(start -0.2032 -0.3048)
							(mid -0.275042 -0.275042)
							(end -0.3048 -0.2032)
						)
						(arc
							(start -0.3048 0.2032)
							(mid -0.275042 0.275042)
							(end -0.2032 0.3048)
						)
						(arc
							(start 0.2032 0.3048)
							(mid 0.275042 0.275042)
							(end 0.3048 0.2032)
						)
					)
					(width 0)
					(fill yes)
				)
			)
		)
	)
	(footprint ""
		(layer "F.Cu")
		(at 183.035702 -81.670906)
		(property "Reference" "TP157"
			(at 0 0 0)
			(layer "F.SilkS")
			(hide yes)
			(effects
				(font
					(size 1.27 1.27)
				)
			)
		)
		(property "Value" "TPAD28-2-GP"
			(at -0.0127 -1.6637 0)
			(unlocked yes)
			(layer "F.Fab")
			(hide yes)
			(effects
				(font
					(size 1.016 1.016)
					(thickness 0.1524)
				)
			)
		)
		(property "Device Type" "TPAD28"
			(at -0.0127 -3.1877 0)
			(unlocked yes)
			(layer "F.Fab")
			(hide yes)
			(effects
				(font
					(size 1.016 1.016)
					(thickness 0.1524)
				)
			)
		)
		(duplicate_pad_numbers_are_jumpers no)
		(fp_poly
			(pts
				(arc
					(start 0.3556 0)
					(mid -0.3556 0)
					(end 0.3556 0)
				)
			)
			(stroke
				(width 0)
				(type default)
			)
			(fill no)
			(layer "F.CrtYd")
		)
		(fp_poly
			(pts
				(arc
					(start 0.6096 0)
					(mid -0.6096 0)
					(end 0.6096 0)
				)
			)
			(stroke
				(width 0)
				(type default)
			)
			(fill no)
			(layer "F.Fab")
		)
		(pad "1" smd circle
			(at 0 0)
			(size 0.7112 0.7112)
			(layers "F.Cu" "F.Mask" "F.Paste")
			(net "SPARE1")
		)
	)
	(footprint ""
		(layer "F.Cu")
		(at 204.6224 -48.2854 180)
		(property "Reference" "R629"
			(at 0 0 180)
			(layer "F.SilkS")
			(hide yes)
			(effects
				(font
					(size 1.27 1.27)
				)
			)
		)
		(property "Value" "4K7R2F-GP"
			(at 0.064008 -3.993896 180)
			(unlocked yes)
			(layer "F.Fab")
			(hide yes)
			(effects
				(font
					(size 1.016 1.016)
					(thickness 0.1524)
				)
			)
		)
		(property "Device Type" "R402H16"
			(at 0.064008 -5.517896 180)
			(unlocked yes)
			(layer "F.Fab")
			(hide yes)
			(effects
				(font
					(size 1.016 1.016)
					(thickness 0.1524)
				)
			)
		)
		(duplicate_pad_numbers_are_jumpers no)
		(fp_line
			(start 0.508 -0.9398)
			(end -0.508 -0.9398)
			(stroke
				(width 0.1524)
				(type default)
			)
			(layer "F.SilkS")
		)
		(fp_line
			(start -0.508 -0.9398)
			(end -0.508 0.9398)
			(stroke
				(width 0.1524)
				(type default)
			)
			(layer "F.SilkS")
		)
		(fp_rect
			(start -0.508 0.9398)
			(end 0.508 -0.9398)
			(stroke
				(width 0)
				(type default)
			)
			(fill no)
			(layer "F.CrtYd")
		)
		(fp_rect
			(start -0.508 0.9398)
			(end 0.508 -0.9398)
			(stroke
				(width 0)
				(type default)
			)
			(fill no)
			(layer "F.Fab")
		)
		(pad "1" smd custom
			(at 0 -0.4445 180)
			(size 0.1397 0.1397)
			(layers "F.Cu" "F.Mask" "F.Paste")
			(net "P1V8")
			(options
				(clearance outline)
				(anchor circle)
			)
			(primitives
				(gr_poly
					(pts
						(arc
							(start -0.1778 -0.2794)
							(mid -0.249642 -0.249642)
							(end -0.2794 -0.1778)
						)
						(arc
							(start -0.2794 0.1778)
							(mid -0.249642 0.249642)
							(end -0.1778 0.2794)
						)
						(arc
							(start 0.1778 0.2794)
							(mid 0.249642 0.249642)
							(end 0.2794 0.1778)
						)
						(arc
							(start 0.2794 -0.1778)
							(mid 0.249642 -0.249642)
							(end 0.1778 -0.2794)
						)
					)
					(width 0)
					(fill yes)
				)
			)
		)
		(pad "2" smd custom
			(at 0 0.4445 180)
			(size 0.1397 0.1397)
			(layers "F.Cu" "F.Mask" "F.Paste")
			(net "ICE1_TRST#")
			(options
				(clearance outline)
				(anchor circle)
			)
			(primitives
				(gr_poly
					(pts
						(arc
							(start -0.1778 -0.2794)
							(mid -0.249642 -0.249642)
							(end -0.2794 -0.1778)
						)
						(arc
							(start -0.2794 0.1778)
							(mid -0.249642 0.249642)
							(end -0.1778 0.2794)
						)
						(arc
							(start 0.1778 0.2794)
							(mid 0.249642 0.249642)
							(end 0.2794 0.1778)
						)
						(arc
							(start 0.2794 -0.1778)
							(mid 0.249642 -0.249642)
							(end 0.1778 -0.2794)
						)
					)
					(width 0)
					(fill yes)
				)
			)
		)
	)
	(footprint ""
		(layer "F.Cu")
		(at 186.0804 -88.1126)
		(property "Reference" "TP158"
			(at 0 0 0)
			(layer "F.SilkS")
			(hide yes)
			(effects
				(font
					(size 1.27 1.27)
				)
			)
		)
		(property "Value" "TPAD28-2-GP"
			(at -0.0127 -1.6637 0)
			(unlocked yes)
			(layer "F.Fab")
			(hide yes)
			(effects
				(font
					(size 1.016 1.016)
					(thickness 0.1524)
				)
			)
		)
		(property "Device Type" "TPAD28"
			(at -0.0127 -3.1877 0)
			(unlocked yes)
			(layer "F.Fab")
			(hide yes)
			(effects
				(font
					(size 1.016 1.016)
					(thickness 0.1524)
				)
			)
		)
		(duplicate_pad_numbers_are_jumpers no)
		(fp_poly
			(pts
				(arc
					(start 0.3556 0)
					(mid -0.3556 0)
					(end 0.3556 0)
				)
			)
			(stroke
				(width 0)
				(type default)
			)
			(fill no)
			(layer "F.CrtYd")
		)
		(fp_poly
			(pts
				(arc
					(start 0.6096 0)
					(mid -0.6096 0)
					(end 0.6096 0)
				)
			)
			(stroke
				(width 0)
				(type default)
			)
			(fill no)
			(layer "F.Fab")
		)
		(pad "1" smd circle
			(at 0 0)
			(size 0.7112 0.7112)
			(layers "F.Cu" "F.Mask" "F.Paste")
			(net "SPARE2")
		)
	)
	(footprint ""
		(layer "F.Cu")
		(at 111.450374 -14.464538 -90)
		(property "Reference" "R458"
			(at 0 0 270)
			(layer "F.SilkS")
			(hide yes)
			(effects
				(font
					(size 1.27 1.27)
				)
			)
		)
		(property "Value" "86K6R2F-GP"
			(at 0.064008 -3.993896 270)
			(unlocked yes)
			(layer "F.Fab")
			(hide yes)
			(effects
				(font
					(size 1.016 1.016)
					(thickness 0.1524)
				)
			)
		)
		(property "Device Type" "R402H16"
			(at 0.064008 -5.517896 270)
			(unlocked yes)
			(layer "F.Fab")
			(hide yes)
			(effects
				(font
					(size 1.016 1.016)
					(thickness 0.1524)
				)
			)
		)
		(duplicate_pad_numbers_are_jumpers no)
		(fp_line
			(start -0.508 -0.9398)
			(end -0.508 0.9398)
			(stroke
				(width 0.1524)
				(type default)
			)
			(layer "F.SilkS")
		)
		(fp_line
			(start 0.508 -0.9398)
			(end -0.508 -0.9398)
			(stroke
				(width 0.1524)
				(type default)
			)
			(layer "F.SilkS")
		)
		(fp_rect
			(start -0.508 0.9398)
			(end 0.508 -0.9398)
			(stroke
				(width 0)
				(type default)
			)
			(fill no)
			(layer "F.CrtYd")
		)
		(fp_rect
			(start -0.508 0.9398)
			(end 0.508 -0.9398)
			(stroke
				(width 0)
				(type default)
			)
			(fill no)
			(layer "F.Fab")
		)
		(pad "1" smd custom
			(at 0 -0.4445 270)
			(size 0.1397 0.1397)
			(layers "F.Cu" "F.Mask" "F.Paste")
			(net "MB0_PSET_R")
			(options
				(clearance outline)
				(anchor circle)
			)
			(primitives
				(gr_poly
					(pts
						(arc
							(start -0.1778 -0.2794)
							(mid -0.249642 -0.249642)
							(end -0.2794 -0.1778)
						)
						(arc
							(start -0.2794 0.1778)
							(mid -0.249642 0.249642)
							(end -0.1778 0.2794)
						)
						(arc
							(start 0.1778 0.2794)
							(mid 0.249642 0.249642)
							(end 0.2794 0.1778)
						)
						(arc
							(start 0.2794 -0.1778)
							(mid 0.249642 -0.249642)
							(end 0.1778 -0.2794)
						)
					)
					(width 0)
					(fill yes)
				)
			)
		)
		(pad "2" smd custom
			(at 0 0.4445 270)
			(size 0.1397 0.1397)
			(layers "F.Cu" "F.Mask" "F.Paste")
			(net "AGND_CURRENT_MON")
			(options
				(clearance outline)
				(anchor circle)
			)
			(primitives
				(gr_poly
					(pts
						(arc
							(start -0.1778 -0.2794)
							(mid -0.249642 -0.249642)
							(end -0.2794 -0.1778)
						)
						(arc
							(start -0.2794 0.1778)
							(mid -0.249642 0.249642)
							(end -0.1778 0.2794)
						)
						(arc
							(start 0.1778 0.2794)
							(mid 0.249642 0.249642)
							(end 0.2794 0.1778)
						)
						(arc
							(start 0.2794 -0.1778)
							(mid 0.249642 -0.249642)
							(end 0.1778 -0.2794)
						)
					)
					(width 0)
					(fill yes)
				)
			)
		)
	)
	(footprint ""
		(layer "F.Cu")
		(at 198.755 -49.9872)
		(property "Reference" "TP139"
			(at 0 0 0)
			(layer "F.SilkS")
			(hide yes)
			(effects
				(font
					(size 1.27 1.27)
				)
			)
		)
		(property "Value" "TPAD28-2-GP"
			(at -0.0127 -1.6637 0)
			(unlocked yes)
			(layer "F.Fab")
			(hide yes)
			(effects
				(font
					(size 1.016 1.016)
					(thickness 0.1524)
				)
			)
		)
		(property "Device Type" "TPAD28"
			(at -0.0127 -3.1877 0)
			(unlocked yes)
			(layer "F.Fab")
			(hide yes)
			(effects
				(font
					(size 1.016 1.016)
					(thickness 0.1524)
				)
			)
		)
		(duplicate_pad_numbers_are_jumpers no)
		(fp_poly
			(pts
				(arc
					(start 0.3556 0)
					(mid -0.3556 0)
					(end 0.3556 0)
				)
			)
			(stroke
				(width 0)
				(type default)
			)
			(fill no)
			(layer "F.CrtYd")
		)
		(fp_poly
			(pts
				(arc
					(start 0.6096 0)
					(mid -0.6096 0)
					(end 0.6096 0)
				)
			)
			(stroke
				(width 0)
				(type default)
			)
			(fill no)
			(layer "F.Fab")
		)
		(pad "1" smd circle
			(at 0 0)
			(size 0.7112 0.7112)
			(layers "F.Cu" "F.Mask" "F.Paste")
			(net "ICE0_TRST#")
		)
	)
	(footprint ""
		(layer "F.Cu")
		(at 22.014942 -129.1082 180)
		(property "Reference" "R213"
			(at 0 0 180)
			(layer "F.SilkS")
			(hide yes)
			(effects
				(font
					(size 1.27 1.27)
				)
			)
		)
		(property "Value" "120R2F-GP"
			(at 0.064008 -3.993896 180)
			(unlocked yes)
			(layer "F.Fab")
			(hide yes)
			(effects
				(font
					(size 1.016 1.016)
					(thickness 0.1524)
				)
			)
		)
		(property "Device Type" "R402H16"
			(at 0.064008 -5.517896 180)
			(unlocked yes)
			(layer "F.Fab")
			(hide yes)
			(effects
				(font
					(size 1.016 1.016)
					(thickness 0.1524)
				)
			)
		)
		(duplicate_pad_numbers_are_jumpers no)
		(fp_line
			(start 0.508 -0.9398)
			(end -0.508 -0.9398)
			(stroke
				(width 0.1524)
				(type default)
			)
			(layer "F.SilkS")
		)
		(fp_line
			(start -0.508 -0.9398)
			(end -0.508 0.9398)
			(stroke
				(width 0.1524)
				(type default)
			)
			(layer "F.SilkS")
		)
		(fp_rect
			(start -0.508 0.9398)
			(end 0.508 -0.9398)
			(stroke
				(width 0)
				(type default)
			)
			(fill no)
			(layer "F.CrtYd")
		)
		(fp_rect
			(start -0.508 0.9398)
			(end 0.508 -0.9398)
			(stroke
				(width 0)
				(type default)
			)
			(fill no)
			(layer "F.Fab")
		)
		(pad "1" smd custom
			(at 0 -0.4445 180)
			(size 0.1397 0.1397)
			(layers "F.Cu" "F.Mask" "F.Paste")
			(net "GND")
			(options
				(clearance outline)
				(anchor circle)
			)
			(primitives
				(gr_poly
					(pts
						(arc
							(start -0.1778 -0.2794)
							(mid -0.249642 -0.249642)
							(end -0.2794 -0.1778)
						)
						(arc
							(start -0.2794 0.1778)
							(mid -0.249642 0.249642)
							(end -0.1778 0.2794)
						)
						(arc
							(start 0.1778 0.2794)
							(mid 0.249642 0.249642)
							(end 0.2794 0.1778)
						)
						(arc
							(start 0.2794 -0.1778)
							(mid 0.249642 -0.249642)
							(end 0.1778 -0.2794)
						)
					)
					(width 0)
					(fill yes)
				)
			)
		)
		(pad "2" smd custom
			(at 0 0.4445 180)
			(size 0.1397 0.1397)
			(layers "F.Cu" "F.Mask" "F.Paste")
			(net "DDR4_ALERT")
			(options
				(clearance outline)
				(anchor circle)
			)
			(primitives
				(gr_poly
					(pts
						(arc
							(start -0.1778 -0.2794)
							(mid -0.249642 -0.249642)
							(end -0.2794 -0.1778)
						)
						(arc
							(start -0.2794 0.1778)
							(mid -0.249642 0.249642)
							(end -0.1778 0.2794)
						)
						(arc
							(start 0.1778 0.2794)
							(mid 0.249642 0.249642)
							(end 0.2794 0.1778)
						)
						(arc
							(start 0.2794 -0.1778)
							(mid 0.249642 -0.249642)
							(end 0.1778 -0.2794)
						)
					)
					(width 0)
					(fill yes)
				)
			)
		)
	)
	(footprint ""
		(layer "F.Cu")
		(at 78.122018 -83.779868 90)
		(property "Reference" "VIA5"
			(at 0 0 90)
			(layer "F.SilkS")
			(hide yes)
			(effects
				(font
					(size 1.27 1.27)
				)
			)
		)
		(property "Value" "85OHM-8L-1D6MM-L16L18-GP"
			(at 4.064 0.6096 90)
			(unlocked yes)
			(layer "F.Fab")
			(hide yes)
			(effects
				(font
					(size 1.016 1.016)
					(thickness 0.1524)
				)
			)
		)
		(property "Device Type" "VIA-PCIE-4P-368076"
			(at 4.064 -0.9144 90)
			(unlocked yes)
			(layer "F.Fab")
			(hide yes)
			(effects
				(font
					(size 1.016 1.016)
					(thickness 0.1524)
				)
			)
		)
		(duplicate_pad_numbers_are_jumpers no)
		(fp_rect
			(start -1.8415 0.381)
			(end 1.8415 -0.381)
			(stroke
				(width 0)
				(type default)
			)
			(fill no)
			(layer "F.CrtYd")
		)
		(fp_rect
			(start -1.8415 0.381)
			(end 1.8415 -0.381)
			(stroke
				(width 0)
				(type default)
			)
			(fill no)
			(layer "F.Fab")
		)
		(pad "1" thru_hole circle
			(at -1.4605 0 90)
			(size 0.508 0.508)
			(drill 0.254)
			(layers "*.Cu" "*.Mask")
			(remove_unused_layers no)
			(net "GND")
			(clearance 0.127)
			(thermal_gap 0.127)
		)
		(pad "2" thru_hole circle
			(at -0.4445 0 90)
			(size 0.508 0.508)
			(drill 0.254)
			(layers "*.Cu" "*.Mask")
			(remove_unused_layers no)
			(net "PCIE_COMP_TO_IOM_20_DP")
			(clearance 0.127)
			(thermal_gap 0.127)
		)
		(pad "3" thru_hole circle
			(at 0.4445 0 90)
			(size 0.508 0.508)
			(drill 0.254)
			(layers "*.Cu" "*.Mask")
			(remove_unused_layers no)
			(net "PCIE_COMP_TO_IOM_20_DN")
			(clearance 0.127)
			(thermal_gap 0.127)
		)
		(pad "4" thru_hole circle
			(at 1.4605 0 90)
			(size 0.508 0.508)
			(drill 0.254)
			(layers "*.Cu" "*.Mask")
			(remove_unused_layers no)
			(net "GND")
			(clearance 0.127)
			(thermal_gap 0.127)
		)
	)
	(footprint ""
		(layer "F.Cu")
		(at 34.2138 -176.8094 180)
		(property "Reference" "G3"
			(at 0 0 180)
			(layer "F.SilkS")
			(hide yes)
			(effects
				(font
					(size 1.27 1.27)
				)
			)
		)
		(property "Value" "COPPER-CLOSE-GP-U"
			(at 0.0762 -2.8702 180)
			(unlocked yes)
			(layer "F.Fab")
			(hide yes)
			(effects
				(font
					(size 1.016 1.016)
					(thickness 0.1524)
				)
			)
		)
		(property "Device Type" "CON2C-U"
			(at 0.0762 -4.3942 180)
			(unlocked yes)
			(layer "F.Fab")
			(hide yes)
			(effects
				(font
					(size 1.016 1.016)
					(thickness 0.1524)
				)
			)
		)
		(duplicate_pad_numbers_are_jumpers no)
		(fp_rect
			(start -0.9398 0.9652)
			(end 0.9398 -0.9652)
			(stroke
				(width 0)
				(type default)
			)
			(fill no)
			(layer "F.CrtYd")
		)
		(fp_rect
			(start -0.9398 0.9652)
			(end 0.9398 -0.9652)
			(stroke
				(width 0)
				(type default)
			)
			(fill no)
			(layer "F.Fab")
		)
		(pad "1" smd custom
			(at 0 -0.5334 180)
			(size 0.17145 0.17145)
			(layers "F.Cu" "F.Mask" "F.Paste")
			(net "AGND_P3V3_STBY")
			(options
				(clearance outline)
				(anchor circle)
			)
			(primitives
				(gr_poly
					(pts
						(xy -0.127 0.3429) (xy -0.127 0.1651) (xy -0.635 -0.3429) (xy 0.635 -0.3429) (xy 0.127 0.1651)
						(xy 0.127 0.3429)
					)
					(width 0)
					(fill yes)
				)
			)
		)
		(pad "2" smd custom
			(at 0 0.5334 180)
			(size 0.17145 0.17145)
			(layers "F.Cu" "F.Mask" "F.Paste")
			(net "GND")
			(options
				(clearance outline)
				(anchor circle)
			)
			(primitives
				(gr_poly
					(pts
						(xy -0.635 0.3429) (xy -0.127 -0.1651) (xy -0.127 -0.3429) (xy 0.127 -0.3429) (xy 0.127 -0.1651)
						(xy 0.635 0.3429)
					)
					(width 0)
					(fill yes)
				)
			)
		)
	)
	(footprint ""
		(layer "F.Cu")
		(at 184.404 -81.788 90)
		(property "Reference" "TP98"
			(at 0 0 90)
			(layer "F.SilkS")
			(hide yes)
			(effects
				(font
					(size 1.27 1.27)
				)
			)
		)
		(property "Value" "TPAD28-2-GP"
			(at -0.0127 -1.6637 90)
			(unlocked yes)
			(layer "F.Fab")
			(hide yes)
			(effects
				(font
					(size 1.016 1.016)
					(thickness 0.1524)
				)
			)
		)
		(property "Device Type" "TPAD28"
			(at -0.0127 -3.1877 90)
			(unlocked yes)
			(layer "F.Fab")
			(hide yes)
			(effects
				(font
					(size 1.016 1.016)
					(thickness 0.1524)
				)
			)
		)
		(duplicate_pad_numbers_are_jumpers no)
		(fp_poly
			(pts
				(arc
					(start 0 0.3556)
					(mid 0 -0.3556)
					(end 0 0.3556)
				)
			)
			(stroke
				(width 0)
				(type default)
			)
			(fill no)
			(layer "F.CrtYd")
		)
		(fp_poly
			(pts
				(arc
					(start 0 0.6096)
					(mid 0 -0.6096)
					(end 0 0.6096)
				)
			)
			(stroke
				(width 0)
				(type default)
			)
			(fill no)
			(layer "F.Fab")
		)
		(pad "1" smd circle
			(at 0 0 90)
			(size 0.7112 0.7112)
			(layers "F.Cu" "F.Mask" "F.Paste")
			(net "IOC_GPIO_13")
		)
	)
	(footprint ""
		(layer "F.Cu")
		(at 57.3786 -158.8516)
		(property "Reference" "R390"
			(at 0 0 0)
			(layer "F.SilkS")
			(hide yes)
			(effects
				(font
					(size 1.27 1.27)
				)
			)
		)
		(property "Value" "4K7R2F-GP"
			(at 0.064008 -3.993896 0)
			(unlocked yes)
			(layer "F.Fab")
			(hide yes)
			(effects
				(font
					(size 1.016 1.016)
					(thickness 0.1524)
				)
			)
		)
		(property "Device Type" "R402H16"
			(at 0.064008 -5.517896 0)
			(unlocked yes)
			(layer "F.Fab")
			(hide yes)
			(effects
				(font
					(size 1.016 1.016)
					(thickness 0.1524)
				)
			)
		)
		(duplicate_pad_numbers_are_jumpers no)
		(fp_line
			(start -0.508 -0.9398)
			(end -0.508 0.9398)
			(stroke
				(width 0.1524)
				(type default)
			)
			(layer "F.SilkS")
		)
		(fp_line
			(start 0.508 -0.9398)
			(end -0.508 -0.9398)
			(stroke
				(width 0.1524)
				(type default)
			)
			(layer "F.SilkS")
		)
		(fp_rect
			(start -0.508 0.9398)
			(end 0.508 -0.9398)
			(stroke
				(width 0)
				(type default)
			)
			(fill no)
			(layer "F.CrtYd")
		)
		(fp_rect
			(start -0.508 0.9398)
			(end 0.508 -0.9398)
			(stroke
				(width 0)
				(type default)
			)
			(fill no)
			(layer "F.Fab")
		)
		(pad "1" smd custom
			(at 0 -0.4445)
			(size 0.1397 0.1397)
			(layers "F.Cu" "F.Mask" "F.Paste")
			(net "P3V3_STBY")
			(options
				(clearance outline)
				(anchor circle)
			)
			(primitives
				(gr_poly
					(pts
						(arc
							(start -0.1778 -0.2794)
							(mid -0.249642 -0.249642)
							(end -0.2794 -0.1778)
						)
						(arc
							(start -0.2794 0.1778)
							(mid -0.249642 0.249642)
							(end -0.1778 0.2794)
						)
						(arc
							(start 0.1778 0.2794)
							(mid 0.249642 0.249642)
							(end 0.2794 0.1778)
						)
						(arc
							(start 0.2794 -0.1778)
							(mid 0.249642 -0.249642)
							(end 0.1778 -0.2794)
						)
					)
					(width 0)
					(fill yes)
				)
			)
		)
		(pad "2" smd custom
			(at 0 0.4445)
			(size 0.1397 0.1397)
			(layers "F.Cu" "F.Mask" "F.Paste")
			(net "MAC2_TXCTL")
			(options
				(clearance outline)
				(anchor circle)
			)
			(primitives
				(gr_poly
					(pts
						(arc
							(start -0.1778 -0.2794)
							(mid -0.249642 -0.249642)
							(end -0.2794 -0.1778)
						)
						(arc
							(start -0.2794 0.1778)
							(mid -0.249642 0.249642)
							(end -0.1778 0.2794)
						)
						(arc
							(start 0.1778 0.2794)
							(mid 0.249642 0.249642)
							(end 0.2794 0.1778)
						)
						(arc
							(start 0.2794 -0.1778)
							(mid 0.249642 -0.249642)
							(end 0.1778 -0.2794)
						)
					)
					(width 0)
					(fill yes)
				)
			)
		)
	)
	(footprint ""
		(layer "F.Cu")
		(at 194.991736 -134.1755 180)
		(property "Reference" "Q9"
			(at 0 0 180)
			(layer "F.SilkS")
			(hide yes)
			(effects
				(font
					(size 1.27 1.27)
				)
			)
		)
		(property "Value" "SSM3K324R-GP"
			(at 0.127 -8.9662 180)
			(unlocked yes)
			(layer "F.Fab")
			(hide yes)
			(effects
				(font
					(size 1.016 1.016)
					(thickness 0.1524)
				)
			)
		)
		(property "Device Type" "SOT23DGS2D4H35"
			(at 0.127 -10.4902 180)
			(unlocked yes)
			(layer "F.Fab")
			(hide yes)
			(effects
				(font
					(size 1.016 1.016)
					(thickness 0.1524)
				)
			)
		)
		(duplicate_pad_numbers_are_jumpers no)
		(fp_line
			(start 1.651 1.778)
			(end 1.651 -1.778)
			(stroke
				(width 0.1524)
				(type default)
			)
			(layer "F.SilkS")
		)
		(fp_line
			(start 1.651 -1.778)
			(end -1.651 -1.778)
			(stroke
				(width 0.1524)
				(type default)
			)
			(layer "F.SilkS")
		)
		(fp_line
			(start -1.651 1.778)
			(end 1.651 1.778)
			(stroke
				(width 0.1524)
				(type default)
			)
			(layer "F.SilkS")
		)
		(fp_line
			(start -1.651 -1.778)
			(end -1.651 1.778)
			(stroke
				(width 0.1524)
				(type default)
			)
			(layer "F.SilkS")
		)
		(fp_poly
			(pts
				(xy -1.778 1.8796) (xy -1.778 -1.8796) (xy 1.778 -1.8796) (xy 1.778 1.8796)
			)
			(stroke
				(width 0)
				(type default)
			)
			(fill no)
			(layer "F.CrtYd")
		)
		(fp_poly
			(pts
				(xy -1.778 1.8796) (xy -1.778 -1.8796) (xy 1.778 -1.8796) (xy 1.778 1.8796)
			)
			(stroke
				(width 0)
				(type default)
			)
			(fill no)
			(layer "F.Fab")
		)
		(pad "D" smd custom
			(at 0 -0.9525 180)
			(size 0.1905 0.1905)
			(layers "F.Cu" "F.Mask" "F.Paste")
			(net "Q8_G")
			(options
				(clearance outline)
				(anchor circle)
			)
			(primitives
				(gr_poly
					(pts
						(arc
							(start -0.1778 0.5715)
							(mid -0.321484 0.511984)
							(end -0.381 0.3683)
						)
						(arc
							(start -0.381 -0.3683)
							(mid -0.321484 -0.511984)
							(end -0.1778 -0.5715)
						)
						(arc
							(start 0.1778 -0.5715)
							(mid 0.321484 -0.511984)
							(end 0.381 -0.3683)
						)
						(arc
							(start 0.381 0.3683)
							(mid 0.321484 0.511984)
							(end 0.1778 0.5715)
						)
					)
					(width 0)
					(fill yes)
				)
			)
		)
		(pad "G" smd custom
			(at -0.98425 0.9525 180)
			(size 0.1905 0.1905)
			(layers "F.Cu" "F.Mask" "F.Paste")
			(net "Q9_G")
			(options
				(clearance outline)
				(anchor circle)
			)
			(primitives
				(gr_poly
					(pts
						(arc
							(start -0.1778 0.5715)
							(mid -0.321484 0.511984)
							(end -0.381 0.3683)
						)
						(arc
							(start -0.381 -0.3683)
							(mid -0.321484 -0.511984)
							(end -0.1778 -0.5715)
						)
						(arc
							(start 0.1778 -0.5715)
							(mid 0.321484 -0.511984)
							(end 0.381 -0.3683)
						)
						(arc
							(start 0.381 0.3683)
							(mid 0.321484 0.511984)
							(end 0.1778 0.5715)
						)
					)
					(width 0)
					(fill yes)
				)
			)
		)
		(pad "S" smd custom
			(at 0.98425 0.9525 180)
			(size 0.1905 0.1905)
			(layers "F.Cu" "F.Mask" "F.Paste")
			(net "GND")
			(options
				(clearance outline)
				(anchor circle)
			)
			(primitives
				(gr_poly
					(pts
						(arc
							(start -0.1778 0.5715)
							(mid -0.321484 0.511984)
							(end -0.381 0.3683)
						)
						(arc
							(start -0.381 -0.3683)
							(mid -0.321484 -0.511984)
							(end -0.1778 -0.5715)
						)
						(arc
							(start 0.1778 -0.5715)
							(mid 0.321484 -0.511984)
							(end 0.381 -0.3683)
						)
						(arc
							(start 0.381 0.3683)
							(mid 0.321484 0.511984)
							(end 0.1778 0.5715)
						)
					)
					(width 0)
					(fill yes)
				)
			)
		)
	)
	(footprint ""
		(layer "F.Cu")
		(at 163.23564 -143.520922)
		(property "Reference" "R514"
			(at 0 0 0)
			(layer "F.SilkS")
			(hide yes)
			(effects
				(font
					(size 1.27 1.27)
				)
			)
		)
		(property "Value" "10R3F-GP"
			(at -0.0254 -2.5146 0)
			(unlocked yes)
			(layer "F.Fab")
			(hide yes)
			(effects
				(font
					(size 1.016 1.016)
					(thickness 0.1524)
				)
			)
		)
		(property "Device Type" "R603H22"
			(at -0.0254 -4.0386 0)
			(unlocked yes)
			(layer "F.Fab")
			(hide yes)
			(effects
				(font
					(size 1.016 1.016)
					(thickness 0.1524)
				)
			)
		)
		(duplicate_pad_numbers_are_jumpers no)
		(fp_line
			(start -0.4826 0)
			(end -0.2032 0)
			(stroke
				(width 0.2032)
				(type default)
			)
			(layer "F.SilkS")
		)
		(fp_line
			(start 0.2032 0)
			(end 0.4826 0)
			(stroke
				(width 0.2032)
				(type default)
			)
			(layer "F.SilkS")
		)
		(fp_rect
			(start -0.5842 1.3335)
			(end 0.5842 -1.3335)
			(stroke
				(width 0)
				(type default)
			)
			(fill no)
			(layer "F.CrtYd")
		)
		(fp_rect
			(start -0.5842 1.3335)
			(end 0.5842 -1.3335)
			(stroke
				(width 0)
				(type default)
			)
			(fill no)
			(layer "F.Fab")
		)
		(pad "1" smd custom
			(at 0 -0.762)
			(size 0.2159 0.2159)
			(layers "F.Cu" "F.Mask" "F.Paste")
			(net "P1V8_STBY_CC")
			(options
				(clearance outline)
				(anchor circle)
			)
			(primitives
				(gr_poly
					(pts
						(arc
							(start -0.3302 -0.4318)
							(mid -0.402042 -0.402042)
							(end -0.4318 -0.3302)
						)
						(arc
							(start -0.4318 0.3302)
							(mid -0.402042 0.402042)
							(end -0.3302 0.4318)
						)
						(arc
							(start 0.3302 0.4318)
							(mid 0.402042 0.402042)
							(end 0.4318 0.3302)
						)
						(arc
							(start 0.4318 -0.3302)
							(mid 0.402042 -0.402042)
							(end 0.3302 -0.4318)
						)
					)
					(width 0)
					(fill yes)
				)
			)
		)
		(pad "2" smd custom
			(at 0 0.762)
			(size 0.2159 0.2159)
			(layers "F.Cu" "F.Mask" "F.Paste")
			(net "P1V8_STBY_CC_R")
			(options
				(clearance outline)
				(anchor circle)
			)
			(primitives
				(gr_poly
					(pts
						(arc
							(start -0.3302 -0.4318)
							(mid -0.402042 -0.402042)
							(end -0.4318 -0.3302)
						)
						(arc
							(start -0.4318 0.3302)
							(mid -0.402042 0.402042)
							(end -0.3302 0.4318)
						)
						(arc
							(start 0.3302 0.4318)
							(mid 0.402042 0.402042)
							(end 0.4318 0.3302)
						)
						(arc
							(start 0.4318 -0.3302)
							(mid 0.402042 -0.402042)
							(end 0.3302 -0.4318)
						)
					)
					(width 0)
					(fill yes)
				)
			)
		)
	)
	(footprint ""
		(layer "F.Cu")
		(at 184.658 -88.392 180)
		(property "Reference" "R653"
			(at 0 0 180)
			(layer "F.SilkS")
			(hide yes)
			(effects
				(font
					(size 1.27 1.27)
				)
			)
		)
		(property "Value" "10KR2F-2-GP"
			(at 0.064008 -3.993896 180)
			(unlocked yes)
			(layer "F.Fab")
			(hide yes)
			(effects
				(font
					(size 1.016 1.016)
					(thickness 0.1524)
				)
			)
		)
		(property "Device Type" "R402H16"
			(at 0.064008 -5.517896 180)
			(unlocked yes)
			(layer "F.Fab")
			(hide yes)
			(effects
				(font
					(size 1.016 1.016)
					(thickness 0.1524)
				)
			)
		)
		(duplicate_pad_numbers_are_jumpers no)
		(fp_line
			(start 0.508 -0.9398)
			(end -0.508 -0.9398)
			(stroke
				(width 0.1524)
				(type default)
			)
			(layer "F.SilkS")
		)
		(fp_line
			(start -0.508 -0.9398)
			(end -0.508 0.9398)
			(stroke
				(width 0.1524)
				(type default)
			)
			(layer "F.SilkS")
		)
		(fp_rect
			(start -0.508 0.9398)
			(end 0.508 -0.9398)
			(stroke
				(width 0)
				(type default)
			)
			(fill no)
			(layer "F.CrtYd")
		)
		(fp_rect
			(start -0.508 0.9398)
			(end 0.508 -0.9398)
			(stroke
				(width 0)
				(type default)
			)
			(fill no)
			(layer "F.Fab")
		)
		(pad "1" smd custom
			(at 0 -0.4445 180)
			(size 0.1397 0.1397)
			(layers "F.Cu" "F.Mask" "F.Paste")
			(net "SYS_DBMODE3")
			(options
				(clearance outline)
				(anchor circle)
			)
			(primitives
				(gr_poly
					(pts
						(arc
							(start -0.1778 -0.2794)
							(mid -0.249642 -0.249642)
							(end -0.2794 -0.1778)
						)
						(arc
							(start -0.2794 0.1778)
							(mid -0.249642 0.249642)
							(end -0.1778 0.2794)
						)
						(arc
							(start 0.1778 0.2794)
							(mid 0.249642 0.249642)
							(end 0.2794 0.1778)
						)
						(arc
							(start 0.2794 -0.1778)
							(mid 0.249642 -0.249642)
							(end 0.1778 -0.2794)
						)
					)
					(width 0)
					(fill yes)
				)
			)
		)
		(pad "2" smd custom
			(at 0 0.4445 180)
			(size 0.1397 0.1397)
			(layers "F.Cu" "F.Mask" "F.Paste")
			(net "GND")
			(options
				(clearance outline)
				(anchor circle)
			)
			(primitives
				(gr_poly
					(pts
						(arc
							(start -0.1778 -0.2794)
							(mid -0.249642 -0.249642)
							(end -0.2794 -0.1778)
						)
						(arc
							(start -0.2794 0.1778)
							(mid -0.249642 0.249642)
							(end -0.1778 0.2794)
						)
						(arc
							(start 0.1778 0.2794)
							(mid 0.249642 0.249642)
							(end 0.2794 0.1778)
						)
						(arc
							(start 0.2794 -0.1778)
							(mid 0.249642 -0.249642)
							(end 0.1778 -0.2794)
						)
					)
					(width 0)
					(fill yes)
				)
			)
		)
	)
	(footprint ""
		(layer "F.Cu")
		(at 20.582128 -131.007358 180)
		(property "Reference" "R226"
			(at 0 0 180)
			(layer "F.SilkS")
			(hide yes)
			(effects
				(font
					(size 1.27 1.27)
				)
			)
		)
		(property "Value" "120R2F-GP"
			(at 0.064008 -3.993896 180)
			(unlocked yes)
			(layer "F.Fab")
			(hide yes)
			(effects
				(font
					(size 1.016 1.016)
					(thickness 0.1524)
				)
			)
		)
		(property "Device Type" "R402H16"
			(at 0.064008 -5.517896 180)
			(unlocked yes)
			(layer "F.Fab")
			(hide yes)
			(effects
				(font
					(size 1.016 1.016)
					(thickness 0.1524)
				)
			)
		)
		(duplicate_pad_numbers_are_jumpers no)
		(fp_line
			(start 0.508 -0.9398)
			(end -0.508 -0.9398)
			(stroke
				(width 0.1524)
				(type default)
			)
			(layer "F.SilkS")
		)
		(fp_line
			(start -0.508 -0.9398)
			(end -0.508 0.9398)
			(stroke
				(width 0.1524)
				(type default)
			)
			(layer "F.SilkS")
		)
		(fp_rect
			(start -0.508 0.9398)
			(end 0.508 -0.9398)
			(stroke
				(width 0)
				(type default)
			)
			(fill no)
			(layer "F.CrtYd")
		)
		(fp_rect
			(start -0.508 0.9398)
			(end 0.508 -0.9398)
			(stroke
				(width 0)
				(type default)
			)
			(fill no)
			(layer "F.Fab")
		)
		(pad "1" smd custom
			(at 0 -0.4445 180)
			(size 0.1397 0.1397)
			(layers "F.Cu" "F.Mask" "F.Paste")
			(net "MEMCASN")
			(options
				(clearance outline)
				(anchor circle)
			)
			(primitives
				(gr_poly
					(pts
						(arc
							(start -0.1778 -0.2794)
							(mid -0.249642 -0.249642)
							(end -0.2794 -0.1778)
						)
						(arc
							(start -0.2794 0.1778)
							(mid -0.249642 0.249642)
							(end -0.1778 0.2794)
						)
						(arc
							(start 0.1778 0.2794)
							(mid 0.249642 0.249642)
							(end 0.2794 0.1778)
						)
						(arc
							(start 0.2794 -0.1778)
							(mid 0.249642 -0.249642)
							(end 0.1778 -0.2794)
						)
					)
					(width 0)
					(fill yes)
				)
			)
		)
		(pad "2" smd custom
			(at 0 0.4445 180)
			(size 0.1397 0.1397)
			(layers "F.Cu" "F.Mask" "F.Paste")
			(net "P1V2_STBY")
			(options
				(clearance outline)
				(anchor circle)
			)
			(primitives
				(gr_poly
					(pts
						(arc
							(start -0.1778 -0.2794)
							(mid -0.249642 -0.249642)
							(end -0.2794 -0.1778)
						)
						(arc
							(start -0.2794 0.1778)
							(mid -0.249642 0.249642)
							(end -0.1778 0.2794)
						)
						(arc
							(start 0.1778 0.2794)
							(mid 0.249642 0.249642)
							(end 0.2794 0.1778)
						)
						(arc
							(start 0.2794 -0.1778)
							(mid 0.249642 -0.249642)
							(end 0.1778 -0.2794)
						)
					)
					(width 0)
					(fill yes)
				)
			)
		)
	)
	(footprint ""
		(layer "F.Cu")
		(at 158.06674 -39.99738)
		(property "Reference" "TP183"
			(at 0 0 0)
			(layer "F.SilkS")
			(hide yes)
			(effects
				(font
					(size 1.27 1.27)
				)
			)
		)
		(property "Value" "TPAD28-2-GP"
			(at -0.0127 -1.6637 0)
			(unlocked yes)
			(layer "F.Fab")
			(hide yes)
			(effects
				(font
					(size 1.016 1.016)
					(thickness 0.1524)
				)
			)
		)
		(property "Device Type" "TPAD28"
			(at -0.0127 -3.1877 0)
			(unlocked yes)
			(layer "F.Fab")
			(hide yes)
			(effects
				(font
					(size 1.016 1.016)
					(thickness 0.1524)
				)
			)
		)
		(duplicate_pad_numbers_are_jumpers no)
		(fp_poly
			(pts
				(arc
					(start 0.3556 0)
					(mid -0.3556 0)
					(end 0.3556 0)
				)
			)
			(stroke
				(width 0)
				(type default)
			)
			(fill no)
			(layer "F.CrtYd")
		)
		(fp_poly
			(pts
				(arc
					(start 0.6096 0)
					(mid -0.6096 0)
					(end 0.6096 0)
				)
			)
			(stroke
				(width 0)
				(type default)
			)
			(fill no)
			(layer "F.Fab")
		)
		(pad "1" smd circle
			(at 0 0)
			(size 0.7112 0.7112)
			(layers "F.Cu" "F.Mask" "F.Paste")
			(net "ZDEF_EXTB_TP_D1")
		)
	)
	(footprint ""
		(layer "F.Cu")
		(at 189.357 -129.1844 90)
		(property "Reference" "R566"
			(at 0 0 90)
			(layer "F.SilkS")
			(hide yes)
			(effects
				(font
					(size 1.27 1.27)
				)
			)
		)
		(property "Value" "453R2F-1-GP"
			(at 0.064008 -3.993896 90)
			(unlocked yes)
			(layer "F.Fab")
			(hide yes)
			(effects
				(font
					(size 1.016 1.016)
					(thickness 0.1524)
				)
			)
		)
		(property "Device Type" "R402H16"
			(at 0.064008 -5.517896 90)
			(unlocked yes)
			(layer "F.Fab")
			(hide yes)
			(effects
				(font
					(size 1.016 1.016)
					(thickness 0.1524)
				)
			)
		)
		(duplicate_pad_numbers_are_jumpers no)
		(fp_line
			(start 0.508 -0.9398)
			(end -0.508 -0.9398)
			(stroke
				(width 0.1524)
				(type default)
			)
			(layer "F.SilkS")
		)
		(fp_line
			(start -0.508 -0.9398)
			(end -0.508 0.9398)
			(stroke
				(width 0.1524)
				(type default)
			)
			(layer "F.SilkS")
		)
		(fp_rect
			(start -0.508 0.9398)
			(end 0.508 -0.9398)
			(stroke
				(width 0)
				(type default)
			)
			(fill no)
			(layer "F.CrtYd")
		)
		(fp_rect
			(start -0.508 0.9398)
			(end 0.508 -0.9398)
			(stroke
				(width 0)
				(type default)
			)
			(fill no)
			(layer "F.Fab")
		)
		(pad "1" smd custom
			(at 0 -0.4445 90)
			(size 0.1397 0.1397)
			(layers "F.Cu" "F.Mask" "F.Paste")
			(net "VT235_VDES_RR")
			(options
				(clearance outline)
				(anchor circle)
			)
			(primitives
				(gr_poly
					(pts
						(arc
							(start -0.1778 -0.2794)
							(mid -0.249642 -0.249642)
							(end -0.2794 -0.1778)
						)
						(arc
							(start -0.2794 0.1778)
							(mid -0.249642 0.249642)
							(end -0.1778 0.2794)
						)
						(arc
							(start 0.1778 0.2794)
							(mid 0.249642 0.249642)
							(end 0.2794 0.1778)
						)
						(arc
							(start 0.2794 -0.1778)
							(mid 0.249642 -0.249642)
							(end 0.1778 -0.2794)
						)
					)
					(width 0)
					(fill yes)
				)
			)
		)
		(pad "2" smd custom
			(at 0 0.4445 90)
			(size 0.1397 0.1397)
			(layers "F.Cu" "F.Mask" "F.Paste")
			(net "VT235_VDES_RCC")
			(options
				(clearance outline)
				(anchor circle)
			)
			(primitives
				(gr_poly
					(pts
						(arc
							(start -0.1778 -0.2794)
							(mid -0.249642 -0.249642)
							(end -0.2794 -0.1778)
						)
						(arc
							(start -0.2794 0.1778)
							(mid -0.249642 0.249642)
							(end -0.1778 0.2794)
						)
						(arc
							(start 0.1778 0.2794)
							(mid 0.249642 0.249642)
							(end 0.2794 0.1778)
						)
						(arc
							(start 0.2794 -0.1778)
							(mid 0.249642 -0.249642)
							(end 0.1778 -0.2794)
						)
					)
					(width 0)
					(fill yes)
				)
			)
		)
	)
	(footprint ""
		(layer "F.Cu")
		(at 203.298552 -132.119624 180)
		(property "Reference" "C253"
			(at 0 0 180)
			(layer "F.SilkS")
			(hide yes)
			(effects
				(font
					(size 1.27 1.27)
				)
			)
		)
		(property "Value" "SC1U16V3KX-5GP"
			(at 0 -2.8194 180)
			(unlocked yes)
			(layer "F.Fab")
			(hide yes)
			(effects
				(font
					(size 1.016 1.016)
					(thickness 0.1524)
				)
			)
		)
		(property "Device Type" "C603H36"
			(at 0 -4.3434 180)
			(unlocked yes)
			(layer "F.Fab")
			(hide yes)
			(effects
				(font
					(size 1.016 1.016)
					(thickness 0.1524)
				)
			)
		)
		(duplicate_pad_numbers_are_jumpers no)
		(fp_line
			(start 0.508 0)
			(end -0.508 0)
			(stroke
				(width 0.2032)
				(type default)
			)
			(layer "F.SilkS")
		)
		(fp_rect
			(start -0.5842 1.3335)
			(end 0.5842 -1.3335)
			(stroke
				(width 0)
				(type default)
			)
			(fill no)
			(layer "F.CrtYd")
		)
		(fp_rect
			(start -0.5842 1.3335)
			(end 0.5842 -1.3335)
			(stroke
				(width 0)
				(type default)
			)
			(fill no)
			(layer "F.Fab")
		)
		(pad "1" smd custom
			(at 0 -0.762 180)
			(size 0.2159 0.2159)
			(layers "F.Cu" "F.Mask" "F.Paste")
			(net "TPS74801_1V5_BIAS")
			(options
				(clearance outline)
				(anchor circle)
			)
			(primitives
				(gr_poly
					(pts
						(arc
							(start -0.3302 -0.4318)
							(mid -0.402042 -0.402042)
							(end -0.4318 -0.3302)
						)
						(arc
							(start -0.4318 0.3302)
							(mid -0.402042 0.402042)
							(end -0.3302 0.4318)
						)
						(arc
							(start 0.3302 0.4318)
							(mid 0.402042 0.402042)
							(end 0.4318 0.3302)
						)
						(arc
							(start 0.4318 -0.3302)
							(mid 0.402042 -0.402042)
							(end 0.3302 -0.4318)
						)
					)
					(width 0)
					(fill yes)
				)
			)
		)
		(pad "2" smd custom
			(at 0 0.762 180)
			(size 0.2159 0.2159)
			(layers "F.Cu" "F.Mask" "F.Paste")
			(net "GND")
			(options
				(clearance outline)
				(anchor circle)
			)
			(primitives
				(gr_poly
					(pts
						(arc
							(start -0.3302 -0.4318)
							(mid -0.402042 -0.402042)
							(end -0.4318 -0.3302)
						)
						(arc
							(start -0.4318 0.3302)
							(mid -0.402042 0.402042)
							(end -0.3302 0.4318)
						)
						(arc
							(start 0.3302 0.4318)
							(mid 0.402042 0.402042)
							(end 0.4318 0.3302)
						)
						(arc
							(start 0.4318 -0.3302)
							(mid 0.402042 -0.402042)
							(end 0.3302 -0.4318)
						)
					)
					(width 0)
					(fill yes)
				)
			)
		)
	)
	(footprint ""
		(layer "F.Cu")
		(at 174.5742 -67.3354 90)
		(property "Reference" "R647"
			(at 0 0 90)
			(layer "F.SilkS")
			(hide yes)
			(effects
				(font
					(size 1.27 1.27)
				)
			)
		)
		(property "Value" "10KR2F-2-GP"
			(at 0.064008 -3.993896 90)
			(unlocked yes)
			(layer "F.Fab")
			(hide yes)
			(effects
				(font
					(size 1.016 1.016)
					(thickness 0.1524)
				)
			)
		)
		(property "Device Type" "R402H16"
			(at 0.064008 -5.517896 90)
			(unlocked yes)
			(layer "F.Fab")
			(hide yes)
			(effects
				(font
					(size 1.016 1.016)
					(thickness 0.1524)
				)
			)
		)
		(duplicate_pad_numbers_are_jumpers no)
		(fp_line
			(start 0.508 -0.9398)
			(end -0.508 -0.9398)
			(stroke
				(width 0.1524)
				(type default)
			)
			(layer "F.SilkS")
		)
		(fp_line
			(start -0.508 -0.9398)
			(end -0.508 0.9398)
			(stroke
				(width 0.1524)
				(type default)
			)
			(layer "F.SilkS")
		)
		(fp_rect
			(start -0.508 0.9398)
			(end 0.508 -0.9398)
			(stroke
				(width 0)
				(type default)
			)
			(fill no)
			(layer "F.CrtYd")
		)
		(fp_rect
			(start -0.508 0.9398)
			(end 0.508 -0.9398)
			(stroke
				(width 0)
				(type default)
			)
			(fill no)
			(layer "F.Fab")
		)
		(pad "1" smd custom
			(at 0 -0.4445 90)
			(size 0.1397 0.1397)
			(layers "F.Cu" "F.Mask" "F.Paste")
			(net "P1V8")
			(options
				(clearance outline)
				(anchor circle)
			)
			(primitives
				(gr_poly
					(pts
						(arc
							(start -0.1778 -0.2794)
							(mid -0.249642 -0.249642)
							(end -0.2794 -0.1778)
						)
						(arc
							(start -0.2794 0.1778)
							(mid -0.249642 0.249642)
							(end -0.1778 0.2794)
						)
						(arc
							(start 0.1778 0.2794)
							(mid 0.249642 0.249642)
							(end 0.2794 0.1778)
						)
						(arc
							(start 0.2794 -0.1778)
							(mid 0.249642 -0.249642)
							(end 0.1778 -0.2794)
						)
					)
					(width 0)
					(fill yes)
				)
			)
		)
		(pad "2" smd custom
			(at 0 0.4445 90)
			(size 0.1397 0.1397)
			(layers "F.Cu" "F.Mask" "F.Paste")
			(net "CP_DONE")
			(options
				(clearance outline)
				(anchor circle)
			)
			(primitives
				(gr_poly
					(pts
						(arc
							(start -0.1778 -0.2794)
							(mid -0.249642 -0.249642)
							(end -0.2794 -0.1778)
						)
						(arc
							(start -0.2794 0.1778)
							(mid -0.249642 0.249642)
							(end -0.1778 0.2794)
						)
						(arc
							(start 0.1778 0.2794)
							(mid 0.249642 0.249642)
							(end 0.2794 0.1778)
						)
						(arc
							(start 0.2794 -0.1778)
							(mid 0.249642 -0.249642)
							(end 0.1778 -0.2794)
						)
					)
					(width 0)
					(fill yes)
				)
			)
		)
	)
	(footprint ""
		(layer "F.Cu")
		(at 184.912 -147.8153)
		(property "Reference" "R478"
			(at 0 0 0)
			(layer "F.SilkS")
			(hide yes)
			(effects
				(font
					(size 1.27 1.27)
				)
			)
		)
		(property "Value" "10KR2F-2-GP"
			(at 0.064008 -3.993896 0)
			(unlocked yes)
			(layer "F.Fab")
			(hide yes)
			(effects
				(font
					(size 1.016 1.016)
					(thickness 0.1524)
				)
			)
		)
		(property "Device Type" "R402H16"
			(at 0.064008 -5.517896 0)
			(unlocked yes)
			(layer "F.Fab")
			(hide yes)
			(effects
				(font
					(size 1.016 1.016)
					(thickness 0.1524)
				)
			)
		)
		(duplicate_pad_numbers_are_jumpers no)
		(fp_line
			(start -0.508 -0.9398)
			(end -0.508 0.9398)
			(stroke
				(width 0.1524)
				(type default)
			)
			(layer "F.SilkS")
		)
		(fp_line
			(start 0.508 -0.9398)
			(end -0.508 -0.9398)
			(stroke
				(width 0.1524)
				(type default)
			)
			(layer "F.SilkS")
		)
		(fp_rect
			(start -0.508 0.9398)
			(end 0.508 -0.9398)
			(stroke
				(width 0)
				(type default)
			)
			(fill no)
			(layer "F.CrtYd")
		)
		(fp_rect
			(start -0.508 0.9398)
			(end 0.508 -0.9398)
			(stroke
				(width 0)
				(type default)
			)
			(fill no)
			(layer "F.Fab")
		)
		(pad "1" smd custom
			(at 0 -0.4445)
			(size 0.1397 0.1397)
			(layers "F.Cu" "F.Mask" "F.Paste")
			(net "P5V_VFB")
			(options
				(clearance outline)
				(anchor circle)
			)
			(primitives
				(gr_poly
					(pts
						(arc
							(start -0.1778 -0.2794)
							(mid -0.249642 -0.249642)
							(end -0.2794 -0.1778)
						)
						(arc
							(start -0.2794 0.1778)
							(mid -0.249642 0.249642)
							(end -0.1778 0.2794)
						)
						(arc
							(start 0.1778 0.2794)
							(mid 0.249642 0.249642)
							(end 0.2794 0.1778)
						)
						(arc
							(start 0.2794 -0.1778)
							(mid 0.249642 -0.249642)
							(end 0.1778 -0.2794)
						)
					)
					(width 0)
					(fill yes)
				)
			)
		)
		(pad "2" smd custom
			(at 0 0.4445)
			(size 0.1397 0.1397)
			(layers "F.Cu" "F.Mask" "F.Paste")
			(net "AGND_P5V")
			(options
				(clearance outline)
				(anchor circle)
			)
			(primitives
				(gr_poly
					(pts
						(arc
							(start -0.1778 -0.2794)
							(mid -0.249642 -0.249642)
							(end -0.2794 -0.1778)
						)
						(arc
							(start -0.2794 0.1778)
							(mid -0.249642 0.249642)
							(end -0.1778 0.2794)
						)
						(arc
							(start 0.1778 0.2794)
							(mid 0.249642 0.249642)
							(end 0.2794 0.1778)
						)
						(arc
							(start 0.2794 -0.1778)
							(mid 0.249642 -0.249642)
							(end 0.1778 -0.2794)
						)
					)
					(width 0)
					(fill yes)
				)
			)
		)
	)
	(footprint ""
		(layer "F.Cu")
		(at 63.422784 -141.417294 90)
		(property "Reference" "R198"
			(at 0 0 90)
			(layer "F.SilkS")
			(hide yes)
			(effects
				(font
					(size 1.27 1.27)
				)
			)
		)
		(property "Value" "1KR2F-3-GP"
			(at 0.064008 -3.993896 90)
			(unlocked yes)
			(layer "F.Fab")
			(hide yes)
			(effects
				(font
					(size 1.016 1.016)
					(thickness 0.1524)
				)
			)
		)
		(property "Device Type" "R402H16"
			(at 0.064008 -5.517896 90)
			(unlocked yes)
			(layer "F.Fab")
			(hide yes)
			(effects
				(font
					(size 1.016 1.016)
					(thickness 0.1524)
				)
			)
		)
		(duplicate_pad_numbers_are_jumpers no)
		(fp_line
			(start 0.508 -0.9398)
			(end -0.508 -0.9398)
			(stroke
				(width 0.1524)
				(type default)
			)
			(layer "F.SilkS")
		)
		(fp_line
			(start -0.508 -0.9398)
			(end -0.508 0.9398)
			(stroke
				(width 0.1524)
				(type default)
			)
			(layer "F.SilkS")
		)
		(fp_rect
			(start -0.508 0.9398)
			(end 0.508 -0.9398)
			(stroke
				(width 0)
				(type default)
			)
			(fill no)
			(layer "F.CrtYd")
		)
		(fp_rect
			(start -0.508 0.9398)
			(end 0.508 -0.9398)
			(stroke
				(width 0)
				(type default)
			)
			(fill no)
			(layer "F.Fab")
		)
		(pad "1" smd custom
			(at 0 -0.4445 90)
			(size 0.1397 0.1397)
			(layers "F.Cu" "F.Mask" "F.Paste")
			(net "I2C_EXP_RMT_SCL_OUT")
			(options
				(clearance outline)
				(anchor circle)
			)
			(primitives
				(gr_poly
					(pts
						(arc
							(start -0.1778 -0.2794)
							(mid -0.249642 -0.249642)
							(end -0.2794 -0.1778)
						)
						(arc
							(start -0.2794 0.1778)
							(mid -0.249642 0.249642)
							(end -0.1778 0.2794)
						)
						(arc
							(start 0.1778 0.2794)
							(mid 0.249642 0.249642)
							(end 0.2794 0.1778)
						)
						(arc
							(start 0.2794 -0.1778)
							(mid 0.249642 -0.249642)
							(end 0.1778 -0.2794)
						)
					)
					(width 0)
					(fill yes)
				)
			)
		)
		(pad "2" smd custom
			(at 0 0.4445 90)
			(size 0.1397 0.1397)
			(layers "F.Cu" "F.Mask" "F.Paste")
			(net "P3V3_STBY")
			(options
				(clearance outline)
				(anchor circle)
			)
			(primitives
				(gr_poly
					(pts
						(arc
							(start -0.1778 -0.2794)
							(mid -0.249642 -0.249642)
							(end -0.2794 -0.1778)
						)
						(arc
							(start -0.2794 0.1778)
							(mid -0.249642 0.249642)
							(end -0.1778 0.2794)
						)
						(arc
							(start 0.1778 0.2794)
							(mid 0.249642 0.249642)
							(end 0.2794 0.1778)
						)
						(arc
							(start 0.2794 -0.1778)
							(mid 0.249642 -0.249642)
							(end 0.1778 -0.2794)
						)
					)
					(width 0)
					(fill yes)
				)
			)
		)
	)
	(footprint ""
		(layer "F.Cu")
		(at 65.51168 -135.34898 -90)
		(property "Reference" "R731"
			(at 0 0 270)
			(layer "F.SilkS")
			(hide yes)
			(effects
				(font
					(size 1.27 1.27)
				)
			)
		)
		(property "Value" "0R2J-2-GP"
			(at 0.064008 -3.993896 270)
			(unlocked yes)
			(layer "F.Fab")
			(hide yes)
			(effects
				(font
					(size 1.016 1.016)
					(thickness 0.1524)
				)
			)
		)
		(property "Device Type" "R402H16"
			(at 0.064008 -5.517896 270)
			(unlocked yes)
			(layer "F.Fab")
			(hide yes)
			(effects
				(font
					(size 1.016 1.016)
					(thickness 0.1524)
				)
			)
		)
		(duplicate_pad_numbers_are_jumpers no)
		(fp_line
			(start -0.508 -0.9398)
			(end -0.508 0.9398)
			(stroke
				(width 0.1524)
				(type default)
			)
			(layer "F.SilkS")
		)
		(fp_line
			(start 0.508 -0.9398)
			(end -0.508 -0.9398)
			(stroke
				(width 0.1524)
				(type default)
			)
			(layer "F.SilkS")
		)
		(fp_rect
			(start -0.508 0.9398)
			(end 0.508 -0.9398)
			(stroke
				(width 0)
				(type default)
			)
			(fill no)
			(layer "F.CrtYd")
		)
		(fp_rect
			(start -0.508 0.9398)
			(end 0.508 -0.9398)
			(stroke
				(width 0)
				(type default)
			)
			(fill no)
			(layer "F.Fab")
		)
		(pad "1" smd custom
			(at 0 -0.4445 270)
			(size 0.1397 0.1397)
			(layers "F.Cu" "F.Mask" "F.Paste")
			(net "COMP_SPARE_1")
			(options
				(clearance outline)
				(anchor circle)
			)
			(primitives
				(gr_poly
					(pts
						(arc
							(start -0.1778 -0.2794)
							(mid -0.249642 -0.249642)
							(end -0.2794 -0.1778)
						)
						(arc
							(start -0.2794 0.1778)
							(mid -0.249642 0.249642)
							(end -0.1778 0.2794)
						)
						(arc
							(start 0.1778 0.2794)
							(mid 0.249642 0.249642)
							(end 0.2794 0.1778)
						)
						(arc
							(start 0.2794 -0.1778)
							(mid 0.249642 -0.249642)
							(end 0.1778 -0.2794)
						)
					)
					(width 0)
					(fill yes)
				)
			)
		)
		(pad "2" smd custom
			(at 0 0.4445 270)
			(size 0.1397 0.1397)
			(layers "F.Cu" "F.Mask" "F.Paste")
			(net "COMP_SPARE_1_R")
			(options
				(clearance outline)
				(anchor circle)
			)
			(primitives
				(gr_poly
					(pts
						(arc
							(start -0.1778 -0.2794)
							(mid -0.249642 -0.249642)
							(end -0.2794 -0.1778)
						)
						(arc
							(start -0.2794 0.1778)
							(mid -0.249642 0.249642)
							(end -0.1778 0.2794)
						)
						(arc
							(start 0.1778 0.2794)
							(mid 0.249642 0.249642)
							(end 0.2794 0.1778)
						)
						(arc
							(start 0.2794 -0.1778)
							(mid 0.249642 -0.249642)
							(end 0.1778 -0.2794)
						)
					)
					(width 0)
					(fill yes)
				)
			)
		)
	)
	(footprint ""
		(layer "F.Cu")
		(at 222.499936 -109.99978)
		(property "Reference" ""
			(at 0 0 0)
			(layer "F.SilkS")
			(hide yes)
			(effects
				(font
					(size 1.27 1.27)
				)
			)
		)
		(property "Value" "*"
			(at -6.38175 0.19685 0)
			(unlocked yes)
			(layer "F.Fab")
			(hide yes)
			(effects
				(font
					(size 1.016 1.016)
					(thickness 0.1524)
				)
			)
		)
		(duplicate_pad_numbers_are_jumpers no)
		(fp_poly
			(pts
				(arc
					(start 5.0673 0)
					(mid -5.0673 0)
					(end 5.0673 0)
				)
			)
			(stroke
				(width 0)
				(type default)
			)
			(fill no)
			(layer "B.CrtYd")
		)
		(fp_poly
			(pts
				(arc
					(start 5.0673 0)
					(mid -5.0673 0)
					(end 5.0673 0)
				)
			)
			(stroke
				(width 0)
				(type default)
			)
			(fill no)
			(layer "F.CrtYd")
		)
		(fp_poly
			(pts
				(arc
					(start 5.0673 0)
					(mid -5.0673 0)
					(end 5.0673 0)
				)
			)
			(stroke
				(width 0)
				(type default)
			)
			(fill no)
			(layer "B.Fab")
		)
		(fp_poly
			(pts
				(arc
					(start 5.0673 0)
					(mid -5.0673 0)
					(end 5.0673 0)
				)
			)
			(stroke
				(width 0)
				(type default)
			)
			(fill no)
			(layer "F.Fab")
		)
		(pad "1" thru_hole circle
			(at 0 0)
			(size 9.525 9.525)
			(drill 3.5052)
			(layers "*.Cu" "*.Mask")
			(remove_unused_layers no)
			(net "Net_12")
			(clearance -2.5019)
			(thermal_gap 0.3048)
			(padstack
				(mode front_inner_back)
				(layer "Inner"
					(shape circle)
					(size 3.9116 3.9116)
					(clearance 0.3048)
				)
				(layer "B.Cu"
					(shape circle)
					(size 9.525 9.525)
					(clearance -2.5019)
				)
			)
		)
	)
	(footprint ""
		(layer "F.Cu")
		(at 42.2656 -179.451)
		(property "Reference" "R488"
			(at 0 0 0)
			(layer "F.SilkS")
			(hide yes)
			(effects
				(font
					(size 1.27 1.27)
				)
			)
		)
		(property "Value" "2K7R2F-GP"
			(at 0.064008 -3.993896 0)
			(unlocked yes)
			(layer "F.Fab")
			(hide yes)
			(effects
				(font
					(size 1.016 1.016)
					(thickness 0.1524)
				)
			)
		)
		(property "Device Type" "R402H16"
			(at 0.064008 -5.517896 0)
			(unlocked yes)
			(layer "F.Fab")
			(hide yes)
			(effects
				(font
					(size 1.016 1.016)
					(thickness 0.1524)
				)
			)
		)
		(duplicate_pad_numbers_are_jumpers no)
		(fp_line
			(start -0.508 -0.9398)
			(end -0.508 0.9398)
			(stroke
				(width 0.1524)
				(type default)
			)
			(layer "F.SilkS")
		)
		(fp_line
			(start 0.508 -0.9398)
			(end -0.508 -0.9398)
			(stroke
				(width 0.1524)
				(type default)
			)
			(layer "F.SilkS")
		)
		(fp_rect
			(start -0.508 0.9398)
			(end 0.508 -0.9398)
			(stroke
				(width 0)
				(type default)
			)
			(fill no)
			(layer "F.CrtYd")
		)
		(fp_rect
			(start -0.508 0.9398)
			(end 0.508 -0.9398)
			(stroke
				(width 0)
				(type default)
			)
			(fill no)
			(layer "F.Fab")
		)
		(pad "1" smd custom
			(at 0 -0.4445)
			(size 0.1397 0.1397)
			(layers "F.Cu" "F.Mask" "F.Paste")
			(net "P3V3_STBY_LL")
			(options
				(clearance outline)
				(anchor circle)
			)
			(primitives
				(gr_poly
					(pts
						(arc
							(start -0.1778 -0.2794)
							(mid -0.249642 -0.249642)
							(end -0.2794 -0.1778)
						)
						(arc
							(start -0.2794 0.1778)
							(mid -0.249642 0.249642)
							(end -0.1778 0.2794)
						)
						(arc
							(start 0.1778 0.2794)
							(mid 0.249642 0.249642)
							(end 0.2794 0.1778)
						)
						(arc
							(start 0.2794 -0.1778)
							(mid 0.249642 -0.249642)
							(end 0.1778 -0.2794)
						)
					)
					(width 0)
					(fill yes)
				)
			)
		)
		(pad "2" smd custom
			(at 0 0.4445)
			(size 0.1397 0.1397)
			(layers "F.Cu" "F.Mask" "F.Paste")
			(net "P3V3_STBY_LL_R")
			(options
				(clearance outline)
				(anchor circle)
			)
			(primitives
				(gr_poly
					(pts
						(arc
							(start -0.1778 -0.2794)
							(mid -0.249642 -0.249642)
							(end -0.2794 -0.1778)
						)
						(arc
							(start -0.2794 0.1778)
							(mid -0.249642 0.249642)
							(end -0.1778 0.2794)
						)
						(arc
							(start 0.1778 0.2794)
							(mid 0.249642 0.249642)
							(end 0.2794 0.1778)
						)
						(arc
							(start 0.2794 -0.1778)
							(mid 0.249642 -0.249642)
							(end 0.1778 -0.2794)
						)
					)
					(width 0)
					(fill yes)
				)
			)
		)
	)
	(footprint ""
		(layer "F.Cu")
		(at 51.689 -131.7244)
		(property "Reference" "R148"
			(at 0 0 0)
			(layer "F.SilkS")
			(hide yes)
			(effects
				(font
					(size 1.27 1.27)
				)
			)
		)
		(property "Value" "100KR2F-L1-GP"
			(at 0.064008 -3.993896 0)
			(unlocked yes)
			(layer "F.Fab")
			(hide yes)
			(effects
				(font
					(size 1.016 1.016)
					(thickness 0.1524)
				)
			)
		)
		(property "Device Type" "R402H16"
			(at 0.064008 -5.517896 0)
			(unlocked yes)
			(layer "F.Fab")
			(hide yes)
			(effects
				(font
					(size 1.016 1.016)
					(thickness 0.1524)
				)
			)
		)
		(duplicate_pad_numbers_are_jumpers no)
		(fp_line
			(start -0.508 -0.9398)
			(end -0.508 0.9398)
			(stroke
				(width 0.1524)
				(type default)
			)
			(layer "F.SilkS")
		)
		(fp_line
			(start 0.508 -0.9398)
			(end -0.508 -0.9398)
			(stroke
				(width 0.1524)
				(type default)
			)
			(layer "F.SilkS")
		)
		(fp_rect
			(start -0.508 0.9398)
			(end 0.508 -0.9398)
			(stroke
				(width 0)
				(type default)
			)
			(fill no)
			(layer "F.CrtYd")
		)
		(fp_rect
			(start -0.508 0.9398)
			(end 0.508 -0.9398)
			(stroke
				(width 0)
				(type default)
			)
			(fill no)
			(layer "F.Fab")
		)
		(pad "1" smd custom
			(at 0 -0.4445)
			(size 0.1397 0.1397)
			(layers "F.Cu" "F.Mask" "F.Paste")
			(net "IRQ_CPU_SERIAL")
			(options
				(clearance outline)
				(anchor circle)
			)
			(primitives
				(gr_poly
					(pts
						(arc
							(start -0.1778 -0.2794)
							(mid -0.249642 -0.249642)
							(end -0.2794 -0.1778)
						)
						(arc
							(start -0.2794 0.1778)
							(mid -0.249642 0.249642)
							(end -0.1778 0.2794)
						)
						(arc
							(start 0.1778 0.2794)
							(mid 0.249642 0.249642)
							(end 0.2794 0.1778)
						)
						(arc
							(start 0.2794 -0.1778)
							(mid 0.249642 -0.249642)
							(end 0.1778 -0.2794)
						)
					)
					(width 0)
					(fill yes)
				)
			)
		)
		(pad "2" smd custom
			(at 0 0.4445)
			(size 0.1397 0.1397)
			(layers "F.Cu" "F.Mask" "F.Paste")
			(net "GND")
			(options
				(clearance outline)
				(anchor circle)
			)
			(primitives
				(gr_poly
					(pts
						(arc
							(start -0.1778 -0.2794)
							(mid -0.249642 -0.249642)
							(end -0.2794 -0.1778)
						)
						(arc
							(start -0.2794 0.1778)
							(mid -0.249642 0.249642)
							(end -0.1778 0.2794)
						)
						(arc
							(start 0.1778 0.2794)
							(mid 0.249642 0.249642)
							(end 0.2794 0.1778)
						)
						(arc
							(start 0.2794 -0.1778)
							(mid 0.249642 -0.249642)
							(end 0.1778 -0.2794)
						)
					)
					(width 0)
					(fill yes)
				)
			)
		)
	)
	(footprint ""
		(layer "F.Cu")
		(at 128.859788 -6.399022)
		(property "Reference" "R455"
			(at 0 0 0)
			(layer "F.SilkS")
			(hide yes)
			(effects
				(font
					(size 1.27 1.27)
				)
			)
		)
		(property "Value" "1MR3J-L-GP"
			(at -0.0254 -2.5146 0)
			(unlocked yes)
			(layer "F.Fab")
			(hide yes)
			(effects
				(font
					(size 1.016 1.016)
					(thickness 0.1524)
				)
			)
		)
		(property "Device Type" "R603H22"
			(at -0.0254 -4.0386 0)
			(unlocked yes)
			(layer "F.Fab")
			(hide yes)
			(effects
				(font
					(size 1.016 1.016)
					(thickness 0.1524)
				)
			)
		)
		(duplicate_pad_numbers_are_jumpers no)
		(fp_line
			(start -0.4826 0)
			(end -0.2032 0)
			(stroke
				(width 0.2032)
				(type default)
			)
			(layer "F.SilkS")
		)
		(fp_line
			(start 0.2032 0)
			(end 0.4826 0)
			(stroke
				(width 0.2032)
				(type default)
			)
			(layer "F.SilkS")
		)
		(fp_rect
			(start -0.5842 1.3335)
			(end 0.5842 -1.3335)
			(stroke
				(width 0)
				(type default)
			)
			(fill no)
			(layer "F.CrtYd")
		)
		(fp_rect
			(start -0.5842 1.3335)
			(end 0.5842 -1.3335)
			(stroke
				(width 0)
				(type default)
			)
			(fill no)
			(layer "F.Fab")
		)
		(pad "1" smd custom
			(at 0 -0.762)
			(size 0.2159 0.2159)
			(layers "F.Cu" "F.Mask" "F.Paste")
			(net "MB0_CM_GATE_R")
			(options
				(clearance outline)
				(anchor circle)
			)
			(primitives
				(gr_poly
					(pts
						(arc
							(start -0.3302 -0.4318)
							(mid -0.402042 -0.402042)
							(end -0.4318 -0.3302)
						)
						(arc
							(start -0.4318 0.3302)
							(mid -0.402042 0.402042)
							(end -0.3302 0.4318)
						)
						(arc
							(start 0.3302 0.4318)
							(mid 0.402042 0.402042)
							(end 0.4318 0.3302)
						)
						(arc
							(start 0.4318 -0.3302)
							(mid 0.402042 -0.402042)
							(end 0.3302 -0.4318)
						)
					)
					(width 0)
					(fill yes)
				)
			)
		)
		(pad "2" smd custom
			(at 0 0.762)
			(size 0.2159 0.2159)
			(layers "F.Cu" "F.Mask" "F.Paste")
			(net "GND")
			(options
				(clearance outline)
				(anchor circle)
			)
			(primitives
				(gr_poly
					(pts
						(arc
							(start -0.3302 -0.4318)
							(mid -0.402042 -0.402042)
							(end -0.4318 -0.3302)
						)
						(arc
							(start -0.4318 0.3302)
							(mid -0.402042 0.402042)
							(end -0.3302 0.4318)
						)
						(arc
							(start 0.3302 0.4318)
							(mid 0.402042 0.402042)
							(end 0.4318 0.3302)
						)
						(arc
							(start 0.4318 -0.3302)
							(mid 0.402042 -0.402042)
							(end 0.3302 -0.4318)
						)
					)
					(width 0)
					(fill yes)
				)
			)
		)
	)
	(footprint ""
		(layer "F.Cu")
		(at 159.952436 -89.9668)
		(property "Reference" "U43"
			(at 0 0 0)
			(layer "F.SilkS")
			(hide yes)
			(effects
				(font
					(size 1.27 1.27)
				)
			)
		)
		(property "Value" "PCA9306DCTT-GP"
			(at 0 -11.6332 0)
			(unlocked yes)
			(layer "F.Fab")
			(hide yes)
			(effects
				(font
					(size 1.016 1.016)
					(thickness 0.1524)
				)
			)
		)
		(property "Device Type" "SSOIC8H52"
			(at 0 -13.1572 0)
			(unlocked yes)
			(layer "F.Fab")
			(hide yes)
			(effects
				(font
					(size 1.016 1.016)
					(thickness 0.1524)
				)
			)
		)
		(duplicate_pad_numbers_are_jumpers no)
		(fp_line
			(start -1.7018 -0.5842)
			(end -1.7018 2.286)
			(stroke
				(width 0.1524)
				(type default)
			)
			(layer "F.SilkS")
		)
		(fp_line
			(start -1.7018 -0.5842)
			(end 1.0668 -0.5842)
			(stroke
				(width 0.1524)
				(type default)
			)
			(layer "F.SilkS")
		)
		(fp_line
			(start -1.524 0.5842)
			(end -1.524 2.286)
			(stroke
				(width 0.508)
				(type default)
			)
			(layer "F.SilkS")
		)
		(fp_line
			(start -1.397 0)
			(end -1.7018 -0.3048)
			(stroke
				(width 0.1524)
				(type default)
			)
			(layer "F.SilkS")
		)
		(fp_line
			(start -1.397 0)
			(end -1.7018 0.3048)
			(stroke
				(width 0.1524)
				(type default)
			)
			(layer "F.SilkS")
		)
		(fp_line
			(start 1.0668 -0.5842)
			(end 1.0668 0.5842)
			(stroke
				(width 0.1524)
				(type default)
			)
			(layer "F.SilkS")
		)
		(fp_line
			(start 1.0668 0.5842)
			(end -1.524 0.5842)
			(stroke
				(width 0.1524)
				(type default)
			)
			(layer "F.SilkS")
		)
		(fp_poly
			(pts
				(xy -1.1684 -0.5842) (xy 1.0668 -0.5842) (xy 1.0668 0.5842) (xy -1.1684 0.5842)
			)
			(stroke
				(width 0)
				(type default)
			)
			(fill yes)
			(layer "F.SilkS")
		)
		(fp_poly
			(pts
				(xy -1.778 2.54) (xy 1.778 2.54) (xy 1.778 -2.54) (xy -1.778 -2.54)
			)
			(stroke
				(width 0)
				(type default)
			)
			(fill no)
			(layer "F.CrtYd")
		)
		(fp_poly
			(pts
				(xy -1.778 -2.54) (xy 1.778 -2.54) (xy 1.778 2.54) (xy -1.778 2.54)
			)
			(stroke
				(width 0)
				(type default)
			)
			(fill no)
			(layer "F.Fab")
		)
		(pad "1" smd rect
			(at -0.97536 1.6256)
			(size 0.3556 1.524)
			(layers "F.Cu" "F.Mask" "F.Paste")
			(net "GND")
		)
		(pad "2" smd rect
			(at -0.32512 1.6256)
			(size 0.3556 1.524)
			(layers "F.Cu" "F.Mask" "F.Paste")
			(net "P1V8")
		)
		(pad "3" smd rect
			(at 0.32512 1.6256)
			(size 0.3556 1.524)
			(layers "F.Cu" "F.Mask" "F.Paste")
			(net "IOC_SCL_4")
		)
		(pad "4" smd rect
			(at 0.97536 1.6256)
			(size 0.3556 1.524)
			(layers "F.Cu" "F.Mask" "F.Paste")
			(net "IOC_SDA_4")
		)
		(pad "5" smd rect
			(at 0.97536 -1.6256)
			(size 0.3556 1.524)
			(layers "F.Cu" "F.Mask" "F.Paste")
			(net "I2C_IOC_SDA")
		)
		(pad "6" smd rect
			(at 0.32512 -1.6256)
			(size 0.3556 1.524)
			(layers "F.Cu" "F.Mask" "F.Paste")
			(net "I2C_IOC_SCL")
		)
		(pad "7" smd rect
			(at -0.32512 -1.6256)
			(size 0.3556 1.524)
			(layers "F.Cu" "F.Mask" "F.Paste")
			(net "U43_VREF2")
		)
		(pad "8" smd rect
			(at -0.97536 -1.6256)
			(size 0.3556 1.524)
			(layers "F.Cu" "F.Mask" "F.Paste")
			(net "U43_VREF2")
		)
	)
	(footprint ""
		(layer "F.Cu")
		(at 50.673 -131.7498)
		(property "Reference" "R149"
			(at 0 0 0)
			(layer "F.SilkS")
			(hide yes)
			(effects
				(font
					(size 1.27 1.27)
				)
			)
		)
		(property "Value" "100KR2F-L1-GP"
			(at 0.064008 -3.993896 0)
			(unlocked yes)
			(layer "F.Fab")
			(hide yes)
			(effects
				(font
					(size 1.016 1.016)
					(thickness 0.1524)
				)
			)
		)
		(property "Device Type" "R402H16"
			(at 0.064008 -5.517896 0)
			(unlocked yes)
			(layer "F.Fab")
			(hide yes)
			(effects
				(font
					(size 1.016 1.016)
					(thickness 0.1524)
				)
			)
		)
		(duplicate_pad_numbers_are_jumpers no)
		(fp_line
			(start -0.508 -0.9398)
			(end -0.508 0.9398)
			(stroke
				(width 0.1524)
				(type default)
			)
			(layer "F.SilkS")
		)
		(fp_line
			(start 0.508 -0.9398)
			(end -0.508 -0.9398)
			(stroke
				(width 0.1524)
				(type default)
			)
			(layer "F.SilkS")
		)
		(fp_rect
			(start -0.508 0.9398)
			(end 0.508 -0.9398)
			(stroke
				(width 0)
				(type default)
			)
			(fill no)
			(layer "F.CrtYd")
		)
		(fp_rect
			(start -0.508 0.9398)
			(end 0.508 -0.9398)
			(stroke
				(width 0)
				(type default)
			)
			(fill no)
			(layer "F.Fab")
		)
		(pad "1" smd custom
			(at 0 -0.4445)
			(size 0.1397 0.1397)
			(layers "F.Cu" "F.Mask" "F.Paste")
			(net "LPCRST0_N")
			(options
				(clearance outline)
				(anchor circle)
			)
			(primitives
				(gr_poly
					(pts
						(arc
							(start -0.1778 -0.2794)
							(mid -0.249642 -0.249642)
							(end -0.2794 -0.1778)
						)
						(arc
							(start -0.2794 0.1778)
							(mid -0.249642 0.249642)
							(end -0.1778 0.2794)
						)
						(arc
							(start 0.1778 0.2794)
							(mid 0.249642 0.249642)
							(end 0.2794 0.1778)
						)
						(arc
							(start 0.2794 -0.1778)
							(mid 0.249642 -0.249642)
							(end 0.1778 -0.2794)
						)
					)
					(width 0)
					(fill yes)
				)
			)
		)
		(pad "2" smd custom
			(at 0 0.4445)
			(size 0.1397 0.1397)
			(layers "F.Cu" "F.Mask" "F.Paste")
			(net "GND")
			(options
				(clearance outline)
				(anchor circle)
			)
			(primitives
				(gr_poly
					(pts
						(arc
							(start -0.1778 -0.2794)
							(mid -0.249642 -0.249642)
							(end -0.2794 -0.1778)
						)
						(arc
							(start -0.2794 0.1778)
							(mid -0.249642 0.249642)
							(end -0.1778 0.2794)
						)
						(arc
							(start 0.1778 0.2794)
							(mid 0.249642 0.249642)
							(end 0.2794 0.1778)
						)
						(arc
							(start 0.2794 -0.1778)
							(mid 0.249642 -0.249642)
							(end 0.1778 -0.2794)
						)
					)
					(width 0)
					(fill yes)
				)
			)
		)
	)
	(footprint ""
		(layer "F.Cu")
		(at 189.865 -84.201 135)
		(property "Reference" "VIA24"
			(at 0 0 135)
			(layer "F.SilkS")
			(hide yes)
			(effects
				(font
					(size 1.27 1.27)
				)
			)
		)
		(property "Value" "85OHM-8L-1D6MM-L16L18-GP"
			(at 4.064105 0.609655 135)
			(unlocked yes)
			(layer "F.Fab")
			(hide yes)
			(effects
				(font
					(size 1.016 1.016)
					(thickness 0.1524)
				)
			)
		)
		(property "Device Type" "VIA-PCIE-4P-368076"
			(at 4.064105 -0.914474 135)
			(unlocked yes)
			(layer "F.Fab")
			(hide yes)
			(effects
				(font
					(size 1.016 1.016)
					(thickness 0.1524)
				)
			)
		)
		(duplicate_pad_numbers_are_jumpers no)
		(fp_poly
			(pts
				(xy -1.841491 -0.381057) (xy 1.841509 -0.381058) (xy 1.841508 0.380942) (xy -1.841491 0.380942)
			)
			(stroke
				(width 0)
				(type default)
			)
			(fill no)
			(layer "F.CrtYd")
		)
		(fp_poly
			(pts
				(xy -1.841491 -0.381057) (xy 1.841509 -0.381058) (xy 1.841508 0.380942) (xy -1.841491 0.380942)
			)
			(stroke
				(width 0)
				(type default)
			)
			(fill no)
			(layer "F.Fab")
		)
		(pad "1" thru_hole circle
			(at -1.460499 0 135)
			(size 0.508 0.508)
			(drill 0.254)
			(layers "*.Cu" "*.Mask")
			(remove_unused_layers no)
			(net "GND")
			(clearance 0.127)
			(thermal_gap 0.127)
		)
		(pad "2" thru_hole circle
			(at -0.4445 0 135)
			(size 0.508 0.508)
			(drill 0.254)
			(layers "*.Cu" "*.Mask")
			(remove_unused_layers no)
			(net "PCIE_COMP_TO_IOM_15_DP")
			(clearance 0.127)
			(thermal_gap 0.127)
		)
		(pad "3" thru_hole circle
			(at 0.4445 0 135)
			(size 0.508 0.508)
			(drill 0.254)
			(layers "*.Cu" "*.Mask")
			(remove_unused_layers no)
			(net "PCIE_COMP_TO_IOM_15_DN")
			(clearance 0.127)
			(thermal_gap 0.127)
		)
		(pad "4" thru_hole circle
			(at 1.460499 0 135)
			(size 0.508 0.508)
			(drill 0.254)
			(layers "*.Cu" "*.Mask")
			(remove_unused_layers no)
			(net "GND")
			(clearance 0.127)
			(thermal_gap 0.127)
		)
	)
	(footprint ""
		(layer "F.Cu")
		(at 117.6528 -14.5796)
		(property "Reference" "R431"
			(at 0 0 0)
			(layer "F.SilkS")
			(hide yes)
			(effects
				(font
					(size 1.27 1.27)
				)
			)
		)
		(property "Value" "10R2F-L-GP"
			(at 0.064008 -3.993896 0)
			(unlocked yes)
			(layer "F.Fab")
			(hide yes)
			(effects
				(font
					(size 1.016 1.016)
					(thickness 0.1524)
				)
			)
		)
		(property "Device Type" "R402H14"
			(at 0.064008 -5.517896 0)
			(unlocked yes)
			(layer "F.Fab")
			(hide yes)
			(effects
				(font
					(size 1.016 1.016)
					(thickness 0.1524)
				)
			)
		)
		(duplicate_pad_numbers_are_jumpers no)
		(fp_line
			(start -0.508 -0.9398)
			(end -0.508 0.9398)
			(stroke
				(width 0.1524)
				(type default)
			)
			(layer "F.SilkS")
		)
		(fp_line
			(start 0.508 -0.9398)
			(end -0.508 -0.9398)
			(stroke
				(width 0.1524)
				(type default)
			)
			(layer "F.SilkS")
		)
		(fp_rect
			(start -0.508 0.9398)
			(end 0.508 -0.9398)
			(stroke
				(width 0)
				(type default)
			)
			(fill no)
			(layer "F.CrtYd")
		)
		(fp_rect
			(start -0.508 0.9398)
			(end 0.508 -0.9398)
			(stroke
				(width 0)
				(type default)
			)
			(fill no)
			(layer "F.Fab")
		)
		(pad "1" smd custom
			(at 0 -0.4445)
			(size 0.1397 0.1397)
			(layers "F.Cu" "F.Mask" "F.Paste")
			(net "P12V_IOM")
			(options
				(clearance outline)
				(anchor circle)
			)
			(primitives
				(gr_poly
					(pts
						(arc
							(start -0.1778 -0.2794)
							(mid -0.249642 -0.249642)
							(end -0.2794 -0.1778)
						)
						(arc
							(start -0.2794 0.1778)
							(mid -0.249642 0.249642)
							(end -0.1778 0.2794)
						)
						(arc
							(start 0.1778 0.2794)
							(mid 0.249642 0.249642)
							(end 0.2794 0.1778)
						)
						(arc
							(start 0.2794 -0.1778)
							(mid 0.249642 -0.249642)
							(end 0.1778 -0.2794)
						)
					)
					(width 0)
					(fill yes)
				)
			)
		)
		(pad "2" smd custom
			(at 0 0.4445)
			(size 0.1397 0.1397)
			(layers "F.Cu" "F.Mask" "F.Paste")
			(net "MB0_VCC")
			(options
				(clearance outline)
				(anchor circle)
			)
			(primitives
				(gr_poly
					(pts
						(arc
							(start -0.1778 -0.2794)
							(mid -0.249642 -0.249642)
							(end -0.2794 -0.1778)
						)
						(arc
							(start -0.2794 0.1778)
							(mid -0.249642 0.249642)
							(end -0.1778 0.2794)
						)
						(arc
							(start 0.1778 0.2794)
							(mid 0.249642 0.249642)
							(end 0.2794 0.1778)
						)
						(arc
							(start 0.2794 -0.1778)
							(mid 0.249642 -0.249642)
							(end 0.1778 -0.2794)
						)
					)
					(width 0)
					(fill yes)
				)
			)
		)
	)
	(footprint ""
		(layer "F.Cu")
		(at 71.189342 -161.96437 90)
		(property "Reference" "C240"
			(at 0 0 90)
			(layer "F.SilkS")
			(hide yes)
			(effects
				(font
					(size 1.27 1.27)
				)
			)
		)
		(property "Value" "SC470P50V2KX-3GP"
			(at 1.1811 -2.7051 90)
			(unlocked yes)
			(layer "F.Fab")
			(hide yes)
			(effects
				(font
					(size 1.016 1.016)
					(thickness 0.1524)
				)
			)
		)
		(property "Device Type" "C402H22"
			(at 1.1811 -4.2291 90)
			(unlocked yes)
			(layer "F.Fab")
			(hide yes)
			(effects
				(font
					(size 1.016 1.016)
					(thickness 0.1524)
				)
			)
		)
		(duplicate_pad_numbers_are_jumpers no)
		(fp_rect
			(start -0.4318 0.9525)
			(end 0.4318 -0.9525)
			(stroke
				(width 0)
				(type default)
			)
			(fill no)
			(layer "F.CrtYd")
		)
		(fp_rect
			(start -0.4318 0.9525)
			(end 0.4318 -0.9525)
			(stroke
				(width 0)
				(type default)
			)
			(fill no)
			(layer "F.Fab")
		)
		(pad "1" smd custom
			(at 0 -0.4445 90)
			(size 0.1524 0.1524)
			(layers "F.Cu" "F.Mask" "F.Paste")
			(net "GND")
			(options
				(clearance outline)
				(anchor circle)
			)
			(primitives
				(gr_poly
					(pts
						(arc
							(start 0.3048 -0.2032)
							(mid 0.275042 -0.275042)
							(end 0.2032 -0.3048)
						)
						(arc
							(start -0.2032 -0.3048)
							(mid -0.275042 -0.275042)
							(end -0.3048 -0.2032)
						)
						(arc
							(start -0.3048 0.2032)
							(mid -0.275042 0.275042)
							(end -0.2032 0.3048)
						)
						(arc
							(start 0.2032 0.3048)
							(mid 0.275042 0.275042)
							(end 0.3048 0.2032)
						)
					)
					(width 0)
					(fill yes)
				)
			)
		)
		(pad "2" smd custom
			(at 0 0.4445 90)
			(size 0.1524 0.1524)
			(layers "F.Cu" "F.Mask" "F.Paste")
			(net "TPS74801_P1V15_STBY_SS")
			(options
				(clearance outline)
				(anchor circle)
			)
			(primitives
				(gr_poly
					(pts
						(arc
							(start 0.3048 -0.2032)
							(mid 0.275042 -0.275042)
							(end 0.2032 -0.3048)
						)
						(arc
							(start -0.2032 -0.3048)
							(mid -0.275042 -0.275042)
							(end -0.3048 -0.2032)
						)
						(arc
							(start -0.3048 0.2032)
							(mid -0.275042 0.275042)
							(end -0.2032 0.3048)
						)
						(arc
							(start 0.2032 0.3048)
							(mid 0.275042 0.275042)
							(end 0.3048 0.2032)
						)
					)
					(width 0)
					(fill yes)
				)
			)
		)
	)
	(footprint ""
		(layer "F.Cu")
		(at 66.439542 -161.123122 90)
		(property "Reference" "R775"
			(at 0 0 90)
			(layer "F.SilkS")
			(hide yes)
			(effects
				(font
					(size 1.27 1.27)
				)
			)
		)
		(property "Value" "1KR2F-3-GP"
			(at 0.064008 -3.993896 90)
			(unlocked yes)
			(layer "F.Fab")
			(hide yes)
			(effects
				(font
					(size 1.016 1.016)
					(thickness 0.1524)
				)
			)
		)
		(property "Device Type" "R402H16"
			(at 0.064008 -5.517896 90)
			(unlocked yes)
			(layer "F.Fab")
			(hide yes)
			(effects
				(font
					(size 1.016 1.016)
					(thickness 0.1524)
				)
			)
		)
		(duplicate_pad_numbers_are_jumpers no)
		(fp_line
			(start 0.508 -0.9398)
			(end -0.508 -0.9398)
			(stroke
				(width 0.1524)
				(type default)
			)
			(layer "F.SilkS")
		)
		(fp_line
			(start -0.508 -0.9398)
			(end -0.508 0.9398)
			(stroke
				(width 0.1524)
				(type default)
			)
			(layer "F.SilkS")
		)
		(fp_rect
			(start -0.508 0.9398)
			(end 0.508 -0.9398)
			(stroke
				(width 0)
				(type default)
			)
			(fill no)
			(layer "F.CrtYd")
		)
		(fp_rect
			(start -0.508 0.9398)
			(end 0.508 -0.9398)
			(stroke
				(width 0)
				(type default)
			)
			(fill no)
			(layer "F.Fab")
		)
		(pad "1" smd custom
			(at 0 -0.4445 90)
			(size 0.1397 0.1397)
			(layers "F.Cu" "F.Mask" "F.Paste")
			(net "ADC_P1V15_STBY")
			(options
				(clearance outline)
				(anchor circle)
			)
			(primitives
				(gr_poly
					(pts
						(arc
							(start -0.1778 -0.2794)
							(mid -0.249642 -0.249642)
							(end -0.2794 -0.1778)
						)
						(arc
							(start -0.2794 0.1778)
							(mid -0.249642 0.249642)
							(end -0.1778 0.2794)
						)
						(arc
							(start 0.1778 0.2794)
							(mid 0.249642 0.249642)
							(end 0.2794 0.1778)
						)
						(arc
							(start 0.2794 -0.1778)
							(mid 0.249642 -0.249642)
							(end 0.1778 -0.2794)
						)
					)
					(width 0)
					(fill yes)
				)
			)
		)
		(pad "2" smd custom
			(at 0 0.4445 90)
			(size 0.1397 0.1397)
			(layers "F.Cu" "F.Mask" "F.Paste")
			(net "GND")
			(options
				(clearance outline)
				(anchor circle)
			)
			(primitives
				(gr_poly
					(pts
						(arc
							(start -0.1778 -0.2794)
							(mid -0.249642 -0.249642)
							(end -0.2794 -0.1778)
						)
						(arc
							(start -0.2794 0.1778)
							(mid -0.249642 0.249642)
							(end -0.1778 0.2794)
						)
						(arc
							(start 0.1778 0.2794)
							(mid 0.249642 0.249642)
							(end 0.2794 0.1778)
						)
						(arc
							(start 0.2794 -0.1778)
							(mid 0.249642 -0.249642)
							(end 0.1778 -0.2794)
						)
					)
					(width 0)
					(fill yes)
				)
			)
		)
	)
	(footprint ""
		(layer "F.Cu")
		(at 46.778418 -128.189736)
		(property "Reference" "R200"
			(at 0 0 0)
			(layer "F.SilkS")
			(hide yes)
			(effects
				(font
					(size 1.27 1.27)
				)
			)
		)
		(property "Value" "2K2R2F-GP"
			(at 0.064008 -3.993896 0)
			(unlocked yes)
			(layer "F.Fab")
			(hide yes)
			(effects
				(font
					(size 1.016 1.016)
					(thickness 0.1524)
				)
			)
		)
		(property "Device Type" "R402H16"
			(at 0.064008 -5.517896 0)
			(unlocked yes)
			(layer "F.Fab")
			(hide yes)
			(effects
				(font
					(size 1.016 1.016)
					(thickness 0.1524)
				)
			)
		)
		(duplicate_pad_numbers_are_jumpers no)
		(fp_line
			(start -0.508 -0.9398)
			(end -0.508 0.9398)
			(stroke
				(width 0.1524)
				(type default)
			)
			(layer "F.SilkS")
		)
		(fp_line
			(start 0.508 -0.9398)
			(end -0.508 -0.9398)
			(stroke
				(width 0.1524)
				(type default)
			)
			(layer "F.SilkS")
		)
		(fp_rect
			(start -0.508 0.9398)
			(end 0.508 -0.9398)
			(stroke
				(width 0)
				(type default)
			)
			(fill no)
			(layer "F.CrtYd")
		)
		(fp_rect
			(start -0.508 0.9398)
			(end 0.508 -0.9398)
			(stroke
				(width 0)
				(type default)
			)
			(fill no)
			(layer "F.Fab")
		)
		(pad "1" smd custom
			(at 0 -0.4445)
			(size 0.1397 0.1397)
			(layers "F.Cu" "F.Mask" "F.Paste")
			(net "I2C_TPM_SCL")
			(options
				(clearance outline)
				(anchor circle)
			)
			(primitives
				(gr_poly
					(pts
						(arc
							(start -0.1778 -0.2794)
							(mid -0.249642 -0.249642)
							(end -0.2794 -0.1778)
						)
						(arc
							(start -0.2794 0.1778)
							(mid -0.249642 0.249642)
							(end -0.1778 0.2794)
						)
						(arc
							(start 0.1778 0.2794)
							(mid 0.249642 0.249642)
							(end 0.2794 0.1778)
						)
						(arc
							(start 0.2794 -0.1778)
							(mid 0.249642 -0.249642)
							(end 0.1778 -0.2794)
						)
					)
					(width 0)
					(fill yes)
				)
			)
		)
		(pad "2" smd custom
			(at 0 0.4445)
			(size 0.1397 0.1397)
			(layers "F.Cu" "F.Mask" "F.Paste")
			(net "P3V3_STBY")
			(options
				(clearance outline)
				(anchor circle)
			)
			(primitives
				(gr_poly
					(pts
						(arc
							(start -0.1778 -0.2794)
							(mid -0.249642 -0.249642)
							(end -0.2794 -0.1778)
						)
						(arc
							(start -0.2794 0.1778)
							(mid -0.249642 0.249642)
							(end -0.1778 0.2794)
						)
						(arc
							(start 0.1778 0.2794)
							(mid 0.249642 0.249642)
							(end 0.2794 0.1778)
						)
						(arc
							(start 0.2794 -0.1778)
							(mid 0.249642 -0.249642)
							(end 0.1778 -0.2794)
						)
					)
					(width 0)
					(fill yes)
				)
			)
		)
	)
	(footprint ""
		(layer "F.Cu")
		(at 208.055972 -71.12 90)
		(property "Reference" "C314"
			(at 0 0 90)
			(layer "F.SilkS")
			(hide yes)
			(effects
				(font
					(size 1.27 1.27)
				)
			)
		)
		(property "Value" "SCD01U16V1KX-GP"
			(at -2.8321 -1.7399 90)
			(unlocked yes)
			(layer "F.Fab")
			(hide yes)
			(effects
				(font
					(size 1.016 1.016)
					(thickness 0.1524)
				)
			)
		)
		(property "Device Type" "C0201H13"
			(at -2.8321 -3.2639 90)
			(unlocked yes)
			(layer "F.Fab")
			(hide yes)
			(effects
				(font
					(size 1.016 1.016)
					(thickness 0.1524)
				)
			)
		)
		(duplicate_pad_numbers_are_jumpers no)
		(fp_rect
			(start -0.2794 0.6477)
			(end 0.2794 -0.6477)
			(stroke
				(width 0)
				(type default)
			)
			(fill no)
			(layer "F.CrtYd")
		)
		(fp_rect
			(start -0.2794 0.6477)
			(end 0.2794 -0.6477)
			(stroke
				(width 0)
				(type default)
			)
			(fill no)
			(layer "F.Fab")
		)
		(pad "1" smd custom
			(at 0 -0.2794 90)
			(size 0.0762 0.0762)
			(layers "F.Cu" "F.Mask" "F.Paste")
			(net "PHY_IOC_TO_CON_A_3_DN_C")
			(options
				(clearance outline)
				(anchor circle)
			)
			(primitives
				(gr_poly
					(pts
						(arc
							(start 0.1524 -0.127)
							(mid 0.137521 -0.162921)
							(end 0.1016 -0.1778)
						)
						(arc
							(start -0.1016 -0.1778)
							(mid -0.137521 -0.162921)
							(end -0.1524 -0.127)
						)
						(arc
							(start -0.1524 0.127)
							(mid -0.137521 0.162921)
							(end -0.1016 0.1778)
						)
						(arc
							(start 0.1016 0.1778)
							(mid 0.137521 0.162921)
							(end 0.1524 0.127)
						)
					)
					(width 0)
					(fill yes)
				)
			)
		)
		(pad "2" smd custom
			(at 0 0.2794 90)
			(size 0.0762 0.0762)
			(layers "F.Cu" "F.Mask" "F.Paste")
			(net "PHY_IOC_TO_CON_A_3_DN")
			(options
				(clearance outline)
				(anchor circle)
			)
			(primitives
				(gr_poly
					(pts
						(arc
							(start 0.1524 -0.127)
							(mid 0.137521 -0.162921)
							(end 0.1016 -0.1778)
						)
						(arc
							(start -0.1016 -0.1778)
							(mid -0.137521 -0.162921)
							(end -0.1524 -0.127)
						)
						(arc
							(start -0.1524 0.127)
							(mid -0.137521 0.162921)
							(end -0.1016 0.1778)
						)
						(arc
							(start 0.1016 0.1778)
							(mid 0.137521 0.162921)
							(end 0.1524 0.127)
						)
					)
					(width 0)
					(fill yes)
				)
			)
		)
	)
	(footprint ""
		(layer "F.Cu")
		(at 208.055972 -76.1492 90)
		(property "Reference" "C308"
			(at 0 0 90)
			(layer "F.SilkS")
			(hide yes)
			(effects
				(font
					(size 1.27 1.27)
				)
			)
		)
		(property "Value" "SCD01U16V1KX-GP"
			(at -2.8321 -1.7399 90)
			(unlocked yes)
			(layer "F.Fab")
			(hide yes)
			(effects
				(font
					(size 1.016 1.016)
					(thickness 0.1524)
				)
			)
		)
		(property "Device Type" "C0201H13"
			(at -2.8321 -3.2639 90)
			(unlocked yes)
			(layer "F.Fab")
			(hide yes)
			(effects
				(font
					(size 1.016 1.016)
					(thickness 0.1524)
				)
			)
		)
		(duplicate_pad_numbers_are_jumpers no)
		(fp_rect
			(start -0.2794 0.6477)
			(end 0.2794 -0.6477)
			(stroke
				(width 0)
				(type default)
			)
			(fill no)
			(layer "F.CrtYd")
		)
		(fp_rect
			(start -0.2794 0.6477)
			(end 0.2794 -0.6477)
			(stroke
				(width 0)
				(type default)
			)
			(fill no)
			(layer "F.Fab")
		)
		(pad "1" smd custom
			(at 0 -0.2794 90)
			(size 0.0762 0.0762)
			(layers "F.Cu" "F.Mask" "F.Paste")
			(net "PHY_IOC_TO_CON_A_0_DN_C")
			(options
				(clearance outline)
				(anchor circle)
			)
			(primitives
				(gr_poly
					(pts
						(arc
							(start 0.1524 -0.127)
							(mid 0.137521 -0.162921)
							(end 0.1016 -0.1778)
						)
						(arc
							(start -0.1016 -0.1778)
							(mid -0.137521 -0.162921)
							(end -0.1524 -0.127)
						)
						(arc
							(start -0.1524 0.127)
							(mid -0.137521 0.162921)
							(end -0.1016 0.1778)
						)
						(arc
							(start 0.1016 0.1778)
							(mid 0.137521 0.162921)
							(end 0.1524 0.127)
						)
					)
					(width 0)
					(fill yes)
				)
			)
		)
		(pad "2" smd custom
			(at 0 0.2794 90)
			(size 0.0762 0.0762)
			(layers "F.Cu" "F.Mask" "F.Paste")
			(net "PHY_IOC_TO_CON_A_0_DN")
			(options
				(clearance outline)
				(anchor circle)
			)
			(primitives
				(gr_poly
					(pts
						(arc
							(start 0.1524 -0.127)
							(mid 0.137521 -0.162921)
							(end 0.1016 -0.1778)
						)
						(arc
							(start -0.1016 -0.1778)
							(mid -0.137521 -0.162921)
							(end -0.1524 -0.127)
						)
						(arc
							(start -0.1524 0.127)
							(mid -0.137521 0.162921)
							(end -0.1016 0.1778)
						)
						(arc
							(start 0.1016 0.1778)
							(mid 0.137521 0.162921)
							(end 0.1524 0.127)
						)
					)
					(width 0)
					(fill yes)
				)
			)
		)
	)
	(footprint ""
		(layer "F.Cu")
		(at 223.576642 -98.454718)
		(property "Reference" "R687"
			(at 0 0 0)
			(layer "F.SilkS")
			(hide yes)
			(effects
				(font
					(size 1.27 1.27)
				)
			)
		)
		(property "Value" "D51R3F-2-GP"
			(at -0.0254 -2.5146 0)
			(unlocked yes)
			(layer "F.Fab")
			(hide yes)
			(effects
				(font
					(size 1.016 1.016)
					(thickness 0.1524)
				)
			)
		)
		(property "Device Type" "R603H22"
			(at -0.0254 -4.0386 0)
			(unlocked yes)
			(layer "F.Fab")
			(hide yes)
			(effects
				(font
					(size 1.016 1.016)
					(thickness 0.1524)
				)
			)
		)
		(duplicate_pad_numbers_are_jumpers no)
		(fp_line
			(start -0.4826 0)
			(end -0.2032 0)
			(stroke
				(width 0.2032)
				(type default)
			)
			(layer "F.SilkS")
		)
		(fp_line
			(start 0.2032 0)
			(end 0.4826 0)
			(stroke
				(width 0.2032)
				(type default)
			)
			(layer "F.SilkS")
		)
		(fp_rect
			(start -0.5842 1.3335)
			(end 0.5842 -1.3335)
			(stroke
				(width 0)
				(type default)
			)
			(fill no)
			(layer "F.CrtYd")
		)
		(fp_rect
			(start -0.5842 1.3335)
			(end 0.5842 -1.3335)
			(stroke
				(width 0)
				(type default)
			)
			(fill no)
			(layer "F.Fab")
		)
		(pad "1" smd custom
			(at 0 -0.762)
			(size 0.2159 0.2159)
			(layers "F.Cu" "F.Mask" "F.Paste")
			(net "P0V975")
			(options
				(clearance outline)
				(anchor circle)
			)
			(primitives
				(gr_poly
					(pts
						(arc
							(start -0.3302 -0.4318)
							(mid -0.402042 -0.402042)
							(end -0.4318 -0.3302)
						)
						(arc
							(start -0.4318 0.3302)
							(mid -0.402042 0.402042)
							(end -0.3302 0.4318)
						)
						(arc
							(start 0.3302 0.4318)
							(mid 0.402042 0.402042)
							(end 0.4318 0.3302)
						)
						(arc
							(start 0.4318 -0.3302)
							(mid 0.402042 -0.402042)
							(end 0.3302 -0.4318)
						)
					)
					(width 0)
					(fill yes)
				)
			)
		)
		(pad "2" smd custom
			(at 0 0.762)
			(size 0.2159 0.2159)
			(layers "F.Cu" "F.Mask" "F.Paste")
			(net "SAS0_AVDD")
			(options
				(clearance outline)
				(anchor circle)
			)
			(primitives
				(gr_poly
					(pts
						(arc
							(start -0.3302 -0.4318)
							(mid -0.402042 -0.402042)
							(end -0.4318 -0.3302)
						)
						(arc
							(start -0.4318 0.3302)
							(mid -0.402042 0.402042)
							(end -0.3302 0.4318)
						)
						(arc
							(start 0.3302 0.4318)
							(mid 0.402042 0.402042)
							(end 0.4318 0.3302)
						)
						(arc
							(start 0.4318 -0.3302)
							(mid 0.402042 -0.402042)
							(end 0.3302 -0.4318)
						)
					)
					(width 0)
					(fill yes)
				)
			)
		)
	)
	(footprint ""
		(layer "F.Cu")
		(at 128.917446 -8.750808 90)
		(property "Reference" "R709"
			(at 0 0 90)
			(layer "F.SilkS")
			(hide yes)
			(effects
				(font
					(size 1.27 1.27)
				)
			)
		)
		(property "Value" "0R5J-5-GP"
			(at 0 -8.9535 90)
			(unlocked yes)
			(layer "F.Fab")
			(hide yes)
			(effects
				(font
					(size 1.27 1.016)
					(thickness 0.1524)
				)
			)
		)
		(property "Device Type" "R805H24"
			(at 0 -10.6299 90)
			(unlocked yes)
			(layer "F.Fab")
			(hide yes)
			(effects
				(font
					(size 1.27 1.016)
					(thickness 0.1524)
				)
			)
		)
		(duplicate_pad_numbers_are_jumpers no)
		(fp_line
			(start 0.889 -1.7018)
			(end -0.889 -1.7018)
			(stroke
				(width 0.1524)
				(type default)
			)
			(layer "F.SilkS")
		)
		(fp_line
			(start 0.889 -1.7018)
			(end 0.889 -0.381)
			(stroke
				(width 0.1524)
				(type default)
			)
			(layer "F.SilkS")
		)
		(fp_line
			(start -0.889 -1.7018)
			(end -0.889 0.2794)
			(stroke
				(width 0.1524)
				(type default)
			)
			(layer "F.SilkS")
		)
		(fp_line
			(start -0.889 0.0762)
			(end -0.889 1.7018)
			(stroke
				(width 0.1524)
				(type default)
			)
			(layer "F.SilkS")
		)
		(fp_line
			(start 0.889 1.7018)
			(end 0.889 -0.508)
			(stroke
				(width 0.1524)
				(type default)
			)
			(layer "F.SilkS")
		)
		(fp_line
			(start -0.889 1.7018)
			(end 0.889 1.7018)
			(stroke
				(width 0.1524)
				(type default)
			)
			(layer "F.SilkS")
		)
		(fp_poly
			(pts
				(xy 0.9652 -1.778) (xy 0.9652 1.778) (xy -0.9652 1.778) (xy -0.9652 -1.778)
			)
			(stroke
				(width 0)
				(type default)
			)
			(fill no)
			(layer "F.CrtYd")
		)
		(fp_rect
			(start -0.9652 1.778)
			(end 0.9652 -1.778)
			(stroke
				(width 0)
				(type default)
			)
			(fill no)
			(layer "F.Fab")
		)
		(pad "1" smd rect
			(at 0 -0.9652 90)
			(size 1.397 1.143)
			(layers "F.Cu" "F.Mask" "F.Paste")
			(net "MB0_CM_GATE_2")
		)
		(pad "2" smd rect
			(at 0 0.9652 90)
			(size 1.397 1.143)
			(layers "F.Cu" "F.Mask" "F.Paste")
			(net "MB0_CM_GATE_R")
		)
	)
	(footprint ""
		(layer "F.Cu")
		(at 17.7546 -129.1082 180)
		(property "Reference" "R220"
			(at 0 0 180)
			(layer "F.SilkS")
			(hide yes)
			(effects
				(font
					(size 1.27 1.27)
				)
			)
		)
		(property "Value" "120R2F-GP"
			(at 0.064008 -3.993896 180)
			(unlocked yes)
			(layer "F.Fab")
			(hide yes)
			(effects
				(font
					(size 1.016 1.016)
					(thickness 0.1524)
				)
			)
		)
		(property "Device Type" "R402H16"
			(at 0.064008 -5.517896 180)
			(unlocked yes)
			(layer "F.Fab")
			(hide yes)
			(effects
				(font
					(size 1.016 1.016)
					(thickness 0.1524)
				)
			)
		)
		(duplicate_pad_numbers_are_jumpers no)
		(fp_line
			(start 0.508 -0.9398)
			(end -0.508 -0.9398)
			(stroke
				(width 0.1524)
				(type default)
			)
			(layer "F.SilkS")
		)
		(fp_line
			(start -0.508 -0.9398)
			(end -0.508 0.9398)
			(stroke
				(width 0.1524)
				(type default)
			)
			(layer "F.SilkS")
		)
		(fp_rect
			(start -0.508 0.9398)
			(end 0.508 -0.9398)
			(stroke
				(width 0)
				(type default)
			)
			(fill no)
			(layer "F.CrtYd")
		)
		(fp_rect
			(start -0.508 0.9398)
			(end 0.508 -0.9398)
			(stroke
				(width 0)
				(type default)
			)
			(fill no)
			(layer "F.Fab")
		)
		(pad "1" smd custom
			(at 0 -0.4445 180)
			(size 0.1397 0.1397)
			(layers "F.Cu" "F.Mask" "F.Paste")
			(net "GND")
			(options
				(clearance outline)
				(anchor circle)
			)
			(primitives
				(gr_poly
					(pts
						(arc
							(start -0.1778 -0.2794)
							(mid -0.249642 -0.249642)
							(end -0.2794 -0.1778)
						)
						(arc
							(start -0.2794 0.1778)
							(mid -0.249642 0.249642)
							(end -0.1778 0.2794)
						)
						(arc
							(start 0.1778 0.2794)
							(mid 0.249642 0.249642)
							(end 0.2794 0.1778)
						)
						(arc
							(start 0.2794 -0.1778)
							(mid 0.249642 -0.249642)
							(end 0.1778 -0.2794)
						)
					)
					(width 0)
					(fill yes)
				)
			)
		)
		(pad "2" smd custom
			(at 0 0.4445 180)
			(size 0.1397 0.1397)
			(layers "F.Cu" "F.Mask" "F.Paste")
			(net "DDR4_ACT")
			(options
				(clearance outline)
				(anchor circle)
			)
			(primitives
				(gr_poly
					(pts
						(arc
							(start -0.1778 -0.2794)
							(mid -0.249642 -0.249642)
							(end -0.2794 -0.1778)
						)
						(arc
							(start -0.2794 0.1778)
							(mid -0.249642 0.249642)
							(end -0.1778 0.2794)
						)
						(arc
							(start 0.1778 0.2794)
							(mid 0.249642 0.249642)
							(end 0.2794 0.1778)
						)
						(arc
							(start 0.2794 -0.1778)
							(mid 0.249642 -0.249642)
							(end 0.1778 -0.2794)
						)
					)
					(width 0)
					(fill yes)
				)
			)
		)
	)
	(footprint ""
		(layer "F.Cu")
		(at 92.548456 -161.52368 90)
		(property "Reference" "R27"
			(at 0 0 90)
			(layer "F.SilkS")
			(hide yes)
			(effects
				(font
					(size 1.27 1.27)
				)
			)
		)
		(property "Value" "1MR2F-GP"
			(at 0.064008 -3.993896 90)
			(unlocked yes)
			(layer "F.Fab")
			(hide yes)
			(effects
				(font
					(size 1.016 1.016)
					(thickness 0.1524)
				)
			)
		)
		(property "Device Type" "R402H16"
			(at 0.064008 -5.517896 90)
			(unlocked yes)
			(layer "F.Fab")
			(hide yes)
			(effects
				(font
					(size 1.016 1.016)
					(thickness 0.1524)
				)
			)
		)
		(duplicate_pad_numbers_are_jumpers no)
		(fp_line
			(start 0.508 -0.9398)
			(end -0.508 -0.9398)
			(stroke
				(width 0.1524)
				(type default)
			)
			(layer "F.SilkS")
		)
		(fp_line
			(start -0.508 -0.9398)
			(end -0.508 0.9398)
			(stroke
				(width 0.1524)
				(type default)
			)
			(layer "F.SilkS")
		)
		(fp_rect
			(start -0.508 0.9398)
			(end 0.508 -0.9398)
			(stroke
				(width 0)
				(type default)
			)
			(fill no)
			(layer "F.CrtYd")
		)
		(fp_rect
			(start -0.508 0.9398)
			(end 0.508 -0.9398)
			(stroke
				(width 0)
				(type default)
			)
			(fill no)
			(layer "F.Fab")
		)
		(pad "1" smd custom
			(at 0 -0.4445 90)
			(size 0.1397 0.1397)
			(layers "F.Cu" "F.Mask" "F.Paste")
			(net "USB_HUB_XTAL_IN")
			(options
				(clearance outline)
				(anchor circle)
			)
			(primitives
				(gr_poly
					(pts
						(arc
							(start -0.1778 -0.2794)
							(mid -0.249642 -0.249642)
							(end -0.2794 -0.1778)
						)
						(arc
							(start -0.2794 0.1778)
							(mid -0.249642 0.249642)
							(end -0.1778 0.2794)
						)
						(arc
							(start 0.1778 0.2794)
							(mid 0.249642 0.249642)
							(end 0.2794 0.1778)
						)
						(arc
							(start 0.2794 -0.1778)
							(mid 0.249642 -0.249642)
							(end 0.1778 -0.2794)
						)
					)
					(width 0)
					(fill yes)
				)
			)
		)
		(pad "2" smd custom
			(at 0 0.4445 90)
			(size 0.1397 0.1397)
			(layers "F.Cu" "F.Mask" "F.Paste")
			(net "USB_HUB_XTAL_OUT")
			(options
				(clearance outline)
				(anchor circle)
			)
			(primitives
				(gr_poly
					(pts
						(arc
							(start -0.1778 -0.2794)
							(mid -0.249642 -0.249642)
							(end -0.2794 -0.1778)
						)
						(arc
							(start -0.2794 0.1778)
							(mid -0.249642 0.249642)
							(end -0.1778 0.2794)
						)
						(arc
							(start 0.1778 0.2794)
							(mid 0.249642 0.249642)
							(end 0.2794 0.1778)
						)
						(arc
							(start 0.2794 -0.1778)
							(mid 0.249642 -0.249642)
							(end 0.1778 -0.2794)
						)
					)
					(width 0)
					(fill yes)
				)
			)
		)
	)
	(footprint ""
		(layer "F.Cu")
		(at 217.678 -102.8954)
		(property "Reference" "R600"
			(at 0 0 0)
			(layer "F.SilkS")
			(hide yes)
			(effects
				(font
					(size 1.27 1.27)
				)
			)
		)
		(property "Value" "4K7R2F-GP"
			(at 0.064008 -3.993896 0)
			(unlocked yes)
			(layer "F.Fab")
			(hide yes)
			(effects
				(font
					(size 1.016 1.016)
					(thickness 0.1524)
				)
			)
		)
		(property "Device Type" "R402H16"
			(at 0.064008 -5.517896 0)
			(unlocked yes)
			(layer "F.Fab")
			(hide yes)
			(effects
				(font
					(size 1.016 1.016)
					(thickness 0.1524)
				)
			)
		)
		(duplicate_pad_numbers_are_jumpers no)
		(fp_line
			(start -0.508 -0.9398)
			(end -0.508 0.9398)
			(stroke
				(width 0.1524)
				(type default)
			)
			(layer "F.SilkS")
		)
		(fp_line
			(start 0.508 -0.9398)
			(end -0.508 -0.9398)
			(stroke
				(width 0.1524)
				(type default)
			)
			(layer "F.SilkS")
		)
		(fp_rect
			(start -0.508 0.9398)
			(end 0.508 -0.9398)
			(stroke
				(width 0)
				(type default)
			)
			(fill no)
			(layer "F.CrtYd")
		)
		(fp_rect
			(start -0.508 0.9398)
			(end 0.508 -0.9398)
			(stroke
				(width 0)
				(type default)
			)
			(fill no)
			(layer "F.Fab")
		)
		(pad "1" smd custom
			(at 0 -0.4445)
			(size 0.1397 0.1397)
			(layers "F.Cu" "F.Mask" "F.Paste")
			(net "P1V8")
			(options
				(clearance outline)
				(anchor circle)
			)
			(primitives
				(gr_poly
					(pts
						(arc
							(start -0.1778 -0.2794)
							(mid -0.249642 -0.249642)
							(end -0.2794 -0.1778)
						)
						(arc
							(start -0.2794 0.1778)
							(mid -0.249642 0.249642)
							(end -0.1778 0.2794)
						)
						(arc
							(start 0.1778 0.2794)
							(mid 0.249642 0.249642)
							(end 0.2794 0.1778)
						)
						(arc
							(start 0.2794 -0.1778)
							(mid 0.249642 -0.249642)
							(end 0.1778 -0.2794)
						)
					)
					(width 0)
					(fill yes)
				)
			)
		)
		(pad "2" smd custom
			(at 0 0.4445)
			(size 0.1397 0.1397)
			(layers "F.Cu" "F.Mask" "F.Paste")
			(net "IOC_EEPROM_A2")
			(options
				(clearance outline)
				(anchor circle)
			)
			(primitives
				(gr_poly
					(pts
						(arc
							(start -0.1778 -0.2794)
							(mid -0.249642 -0.249642)
							(end -0.2794 -0.1778)
						)
						(arc
							(start -0.2794 0.1778)
							(mid -0.249642 0.249642)
							(end -0.1778 0.2794)
						)
						(arc
							(start 0.1778 0.2794)
							(mid 0.249642 0.249642)
							(end 0.2794 0.1778)
						)
						(arc
							(start 0.2794 -0.1778)
							(mid 0.249642 -0.249642)
							(end 0.1778 -0.2794)
						)
					)
					(width 0)
					(fill yes)
				)
			)
		)
	)
	(footprint ""
		(layer "F.Cu")
		(at 31.673038 -152.888442 90)
		(property "Reference" "R701"
			(at 0 0 90)
			(layer "F.SilkS")
			(hide yes)
			(effects
				(font
					(size 1.27 1.27)
				)
			)
		)
		(property "Value" "4K7R2F-GP"
			(at 0.064008 -3.993896 90)
			(unlocked yes)
			(layer "F.Fab")
			(hide yes)
			(effects
				(font
					(size 1.016 1.016)
					(thickness 0.1524)
				)
			)
		)
		(property "Device Type" "R402H16"
			(at 0.064008 -5.517896 90)
			(unlocked yes)
			(layer "F.Fab")
			(hide yes)
			(effects
				(font
					(size 1.016 1.016)
					(thickness 0.1524)
				)
			)
		)
		(duplicate_pad_numbers_are_jumpers no)
		(fp_line
			(start 0.508 -0.9398)
			(end -0.508 -0.9398)
			(stroke
				(width 0.1524)
				(type default)
			)
			(layer "F.SilkS")
		)
		(fp_line
			(start -0.508 -0.9398)
			(end -0.508 0.9398)
			(stroke
				(width 0.1524)
				(type default)
			)
			(layer "F.SilkS")
		)
		(fp_rect
			(start -0.508 0.9398)
			(end 0.508 -0.9398)
			(stroke
				(width 0)
				(type default)
			)
			(fill no)
			(layer "F.CrtYd")
		)
		(fp_rect
			(start -0.508 0.9398)
			(end 0.508 -0.9398)
			(stroke
				(width 0)
				(type default)
			)
			(fill no)
			(layer "F.Fab")
		)
		(pad "1" smd custom
			(at 0 -0.4445 90)
			(size 0.1397 0.1397)
			(layers "F.Cu" "F.Mask" "F.Paste")
			(net "P3V3_STBY")
			(options
				(clearance outline)
				(anchor circle)
			)
			(primitives
				(gr_poly
					(pts
						(arc
							(start -0.1778 -0.2794)
							(mid -0.249642 -0.249642)
							(end -0.2794 -0.1778)
						)
						(arc
							(start -0.2794 0.1778)
							(mid -0.249642 0.249642)
							(end -0.1778 0.2794)
						)
						(arc
							(start 0.1778 0.2794)
							(mid 0.249642 0.249642)
							(end 0.2794 0.1778)
						)
						(arc
							(start 0.2794 -0.1778)
							(mid 0.249642 -0.249642)
							(end 0.1778 -0.2794)
						)
					)
					(width 0)
					(fill yes)
				)
			)
		)
		(pad "2" smd custom
			(at 0 0.4445 90)
			(size 0.1397 0.1397)
			(layers "F.Cu" "F.Mask" "F.Paste")
			(net "COMP_FAST_THROTTLE_N")
			(options
				(clearance outline)
				(anchor circle)
			)
			(primitives
				(gr_poly
					(pts
						(arc
							(start -0.1778 -0.2794)
							(mid -0.249642 -0.249642)
							(end -0.2794 -0.1778)
						)
						(arc
							(start -0.2794 0.1778)
							(mid -0.249642 0.249642)
							(end -0.1778 0.2794)
						)
						(arc
							(start 0.1778 0.2794)
							(mid 0.249642 0.249642)
							(end 0.2794 0.1778)
						)
						(arc
							(start 0.2794 -0.1778)
							(mid 0.249642 -0.249642)
							(end 0.1778 -0.2794)
						)
					)
					(width 0)
					(fill yes)
				)
			)
		)
	)
	(footprint ""
		(layer "F.Cu")
		(at 56.7436 -162.4838)
		(property "Reference" "R402"
			(at 0 0 0)
			(layer "F.SilkS")
			(hide yes)
			(effects
				(font
					(size 1.27 1.27)
				)
			)
		)
		(property "Value" "330R2F-GP"
			(at 0.064008 -3.993896 0)
			(unlocked yes)
			(layer "F.Fab")
			(hide yes)
			(effects
				(font
					(size 1.016 1.016)
					(thickness 0.1524)
				)
			)
		)
		(property "Device Type" "R402H16"
			(at 0.064008 -5.517896 0)
			(unlocked yes)
			(layer "F.Fab")
			(hide yes)
			(effects
				(font
					(size 1.016 1.016)
					(thickness 0.1524)
				)
			)
		)
		(duplicate_pad_numbers_are_jumpers no)
		(fp_line
			(start -0.508 -0.9398)
			(end -0.508 0.9398)
			(stroke
				(width 0.1524)
				(type default)
			)
			(layer "F.SilkS")
		)
		(fp_line
			(start 0.508 -0.9398)
			(end -0.508 -0.9398)
			(stroke
				(width 0.1524)
				(type default)
			)
			(layer "F.SilkS")
		)
		(fp_rect
			(start -0.508 0.9398)
			(end 0.508 -0.9398)
			(stroke
				(width 0)
				(type default)
			)
			(fill no)
			(layer "F.CrtYd")
		)
		(fp_rect
			(start -0.508 0.9398)
			(end 0.508 -0.9398)
			(stroke
				(width 0)
				(type default)
			)
			(fill no)
			(layer "F.Fab")
		)
		(pad "1" smd custom
			(at 0 -0.4445)
			(size 0.1397 0.1397)
			(layers "F.Cu" "F.Mask" "F.Paste")
			(net "P1V8_STBY")
			(options
				(clearance outline)
				(anchor circle)
			)
			(primitives
				(gr_poly
					(pts
						(arc
							(start -0.1778 -0.2794)
							(mid -0.249642 -0.249642)
							(end -0.2794 -0.1778)
						)
						(arc
							(start -0.2794 0.1778)
							(mid -0.249642 0.249642)
							(end -0.1778 0.2794)
						)
						(arc
							(start 0.1778 0.2794)
							(mid 0.249642 0.249642)
							(end 0.2794 0.1778)
						)
						(arc
							(start 0.2794 -0.1778)
							(mid 0.249642 -0.249642)
							(end 0.1778 -0.2794)
						)
					)
					(width 0)
					(fill yes)
				)
			)
		)
		(pad "2" smd custom
			(at 0 0.4445)
			(size 0.1397 0.1397)
			(layers "F.Cu" "F.Mask" "F.Paste")
			(net "ADC_P1V8_STBY")
			(options
				(clearance outline)
				(anchor circle)
			)
			(primitives
				(gr_poly
					(pts
						(arc
							(start -0.1778 -0.2794)
							(mid -0.249642 -0.249642)
							(end -0.2794 -0.1778)
						)
						(arc
							(start -0.2794 0.1778)
							(mid -0.249642 0.249642)
							(end -0.1778 0.2794)
						)
						(arc
							(start 0.1778 0.2794)
							(mid 0.249642 0.249642)
							(end 0.2794 0.1778)
						)
						(arc
							(start 0.2794 -0.1778)
							(mid 0.249642 -0.249642)
							(end 0.1778 -0.2794)
						)
					)
					(width 0)
					(fill yes)
				)
			)
		)
	)
	(footprint ""
		(layer "F.Cu")
		(at 11.7094 -171.014136 180)
		(property "Reference" "R534"
			(at 0 0 180)
			(layer "F.SilkS")
			(hide yes)
			(effects
				(font
					(size 1.27 1.27)
				)
			)
		)
		(property "Value" "4K75R2F-1-GP"
			(at 0.064008 -3.993896 180)
			(unlocked yes)
			(layer "F.Fab")
			(hide yes)
			(effects
				(font
					(size 1.016 1.016)
					(thickness 0.1524)
				)
			)
		)
		(property "Device Type" "R402H16"
			(at 0.064008 -5.517896 180)
			(unlocked yes)
			(layer "F.Fab")
			(hide yes)
			(effects
				(font
					(size 1.016 1.016)
					(thickness 0.1524)
				)
			)
		)
		(duplicate_pad_numbers_are_jumpers no)
		(fp_line
			(start 0.508 -0.9398)
			(end -0.508 -0.9398)
			(stroke
				(width 0.1524)
				(type default)
			)
			(layer "F.SilkS")
		)
		(fp_line
			(start -0.508 -0.9398)
			(end -0.508 0.9398)
			(stroke
				(width 0.1524)
				(type default)
			)
			(layer "F.SilkS")
		)
		(fp_rect
			(start -0.508 0.9398)
			(end 0.508 -0.9398)
			(stroke
				(width 0)
				(type default)
			)
			(fill no)
			(layer "F.CrtYd")
		)
		(fp_rect
			(start -0.508 0.9398)
			(end 0.508 -0.9398)
			(stroke
				(width 0)
				(type default)
			)
			(fill no)
			(layer "F.Fab")
		)
		(pad "1" smd custom
			(at 0 -0.4445 180)
			(size 0.1397 0.1397)
			(layers "F.Cu" "F.Mask" "F.Paste")
			(net "P3V3_STBY")
			(options
				(clearance outline)
				(anchor circle)
			)
			(primitives
				(gr_poly
					(pts
						(arc
							(start -0.1778 -0.2794)
							(mid -0.249642 -0.249642)
							(end -0.2794 -0.1778)
						)
						(arc
							(start -0.2794 0.1778)
							(mid -0.249642 0.249642)
							(end -0.1778 0.2794)
						)
						(arc
							(start 0.1778 0.2794)
							(mid 0.249642 0.249642)
							(end 0.2794 0.1778)
						)
						(arc
							(start 0.2794 -0.1778)
							(mid 0.249642 -0.249642)
							(end 0.1778 -0.2794)
						)
					)
					(width 0)
					(fill yes)
				)
			)
		)
		(pad "2" smd custom
			(at 0 0.4445 180)
			(size 0.1397 0.1397)
			(layers "F.Cu" "F.Mask" "F.Paste")
			(net "TPS74801_P1V2_STBY_EN")
			(options
				(clearance outline)
				(anchor circle)
			)
			(primitives
				(gr_poly
					(pts
						(arc
							(start -0.1778 -0.2794)
							(mid -0.249642 -0.249642)
							(end -0.2794 -0.1778)
						)
						(arc
							(start -0.2794 0.1778)
							(mid -0.249642 0.249642)
							(end -0.1778 0.2794)
						)
						(arc
							(start 0.1778 0.2794)
							(mid 0.249642 0.249642)
							(end 0.2794 0.1778)
						)
						(arc
							(start 0.2794 -0.1778)
							(mid 0.249642 -0.249642)
							(end 0.1778 -0.2794)
						)
					)
					(width 0)
					(fill yes)
				)
			)
		)
	)
	(footprint ""
		(layer "F.Cu")
		(at 33.772348 -153.240994 -90)
		(property "Reference" "R319"
			(at 0 0 270)
			(layer "F.SilkS")
			(hide yes)
			(effects
				(font
					(size 1.27 1.27)
				)
			)
		)
		(property "Value" "0R2J-2-GP"
			(at 0.064008 -3.993896 270)
			(unlocked yes)
			(layer "F.Fab")
			(hide yes)
			(effects
				(font
					(size 1.016 1.016)
					(thickness 0.1524)
				)
			)
		)
		(property "Device Type" "R402H16"
			(at 0.064008 -5.517896 270)
			(unlocked yes)
			(layer "F.Fab")
			(hide yes)
			(effects
				(font
					(size 1.016 1.016)
					(thickness 0.1524)
				)
			)
		)
		(duplicate_pad_numbers_are_jumpers no)
		(fp_line
			(start -0.508 -0.9398)
			(end -0.508 0.9398)
			(stroke
				(width 0.1524)
				(type default)
			)
			(layer "F.SilkS")
		)
		(fp_line
			(start 0.508 -0.9398)
			(end -0.508 -0.9398)
			(stroke
				(width 0.1524)
				(type default)
			)
			(layer "F.SilkS")
		)
		(fp_rect
			(start -0.508 0.9398)
			(end 0.508 -0.9398)
			(stroke
				(width 0)
				(type default)
			)
			(fill no)
			(layer "F.CrtYd")
		)
		(fp_rect
			(start -0.508 0.9398)
			(end 0.508 -0.9398)
			(stroke
				(width 0)
				(type default)
			)
			(fill no)
			(layer "F.Fab")
		)
		(pad "1" smd custom
			(at 0 -0.4445 270)
			(size 0.1397 0.1397)
			(layers "F.Cu" "F.Mask" "F.Paste")
			(net "ENCL_FAULT_LED_R")
			(options
				(clearance outline)
				(anchor circle)
			)
			(primitives
				(gr_poly
					(pts
						(arc
							(start -0.1778 -0.2794)
							(mid -0.249642 -0.249642)
							(end -0.2794 -0.1778)
						)
						(arc
							(start -0.2794 0.1778)
							(mid -0.249642 0.249642)
							(end -0.1778 0.2794)
						)
						(arc
							(start 0.1778 0.2794)
							(mid 0.249642 0.249642)
							(end 0.2794 0.1778)
						)
						(arc
							(start 0.2794 -0.1778)
							(mid 0.249642 -0.249642)
							(end 0.1778 -0.2794)
						)
					)
					(width 0)
					(fill yes)
				)
			)
		)
		(pad "2" smd custom
			(at 0 0.4445 270)
			(size 0.1397 0.1397)
			(layers "F.Cu" "F.Mask" "F.Paste")
			(net "ENCL_FAULT_LED")
			(options
				(clearance outline)
				(anchor circle)
			)
			(primitives
				(gr_poly
					(pts
						(arc
							(start -0.1778 -0.2794)
							(mid -0.249642 -0.249642)
							(end -0.2794 -0.1778)
						)
						(arc
							(start -0.2794 0.1778)
							(mid -0.249642 0.249642)
							(end -0.1778 0.2794)
						)
						(arc
							(start 0.1778 0.2794)
							(mid 0.249642 0.249642)
							(end 0.2794 0.1778)
						)
						(arc
							(start 0.2794 -0.1778)
							(mid 0.249642 -0.249642)
							(end 0.1778 -0.2794)
						)
					)
					(width 0)
					(fill yes)
				)
			)
		)
	)
	(footprint ""
		(layer "F.Cu")
		(at 93.642688 -62.302136 90)
		(property "Reference" "R501"
			(at 0 0 90)
			(layer "F.SilkS")
			(hide yes)
			(effects
				(font
					(size 1.27 1.27)
				)
			)
		)
		(property "Value" "2K2R2J-2-GP"
			(at 0.064008 -3.993896 90)
			(unlocked yes)
			(layer "F.Fab")
			(hide yes)
			(effects
				(font
					(size 1.016 1.016)
					(thickness 0.1524)
				)
			)
		)
		(property "Device Type" "R402H16"
			(at 0.064008 -5.517896 90)
			(unlocked yes)
			(layer "F.Fab")
			(hide yes)
			(effects
				(font
					(size 1.016 1.016)
					(thickness 0.1524)
				)
			)
		)
		(duplicate_pad_numbers_are_jumpers no)
		(fp_line
			(start 0.508 -0.9398)
			(end -0.508 -0.9398)
			(stroke
				(width 0.1524)
				(type default)
			)
			(layer "F.SilkS")
		)
		(fp_line
			(start -0.508 -0.9398)
			(end -0.508 0.9398)
			(stroke
				(width 0.1524)
				(type default)
			)
			(layer "F.SilkS")
		)
		(fp_rect
			(start -0.508 0.9398)
			(end 0.508 -0.9398)
			(stroke
				(width 0)
				(type default)
			)
			(fill no)
			(layer "F.CrtYd")
		)
		(fp_rect
			(start -0.508 0.9398)
			(end 0.508 -0.9398)
			(stroke
				(width 0)
				(type default)
			)
			(fill no)
			(layer "F.Fab")
		)
		(pad "1" smd custom
			(at 0 -0.4445 90)
			(size 0.1397 0.1397)
			(layers "F.Cu" "F.Mask" "F.Paste")
			(net "P3V3_STBY")
			(options
				(clearance outline)
				(anchor circle)
			)
			(primitives
				(gr_poly
					(pts
						(arc
							(start -0.1778 -0.2794)
							(mid -0.249642 -0.249642)
							(end -0.2794 -0.1778)
						)
						(arc
							(start -0.2794 0.1778)
							(mid -0.249642 0.249642)
							(end -0.1778 0.2794)
						)
						(arc
							(start 0.1778 0.2794)
							(mid 0.249642 0.249642)
							(end 0.2794 0.1778)
						)
						(arc
							(start 0.2794 -0.1778)
							(mid 0.249642 -0.249642)
							(end 0.1778 -0.2794)
						)
					)
					(width 0)
					(fill yes)
				)
			)
		)
		(pad "2" smd custom
			(at 0 0.4445 90)
			(size 0.1397 0.1397)
			(layers "F.Cu" "F.Mask" "F.Paste")
			(net "IOM_FULL_PWR_EN")
			(options
				(clearance outline)
				(anchor circle)
			)
			(primitives
				(gr_poly
					(pts
						(arc
							(start -0.1778 -0.2794)
							(mid -0.249642 -0.249642)
							(end -0.2794 -0.1778)
						)
						(arc
							(start -0.2794 0.1778)
							(mid -0.249642 0.249642)
							(end -0.1778 0.2794)
						)
						(arc
							(start 0.1778 0.2794)
							(mid 0.249642 0.249642)
							(end 0.2794 0.1778)
						)
						(arc
							(start 0.2794 -0.1778)
							(mid 0.249642 -0.249642)
							(end 0.1778 -0.2794)
						)
					)
					(width 0)
					(fill yes)
				)
			)
		)
	)
	(footprint ""
		(layer "F.Cu")
		(at 75.311 -148.336 180)
		(property "Reference" "C76"
			(at 0 0 180)
			(layer "F.SilkS")
			(hide yes)
			(effects
				(font
					(size 1.27 1.27)
				)
			)
		)
		(property "Value" "SCD01U25V2KX-3GP"
			(at 1.1811 -2.7051 180)
			(unlocked yes)
			(layer "F.Fab")
			(hide yes)
			(effects
				(font
					(size 1.016 1.016)
					(thickness 0.1524)
				)
			)
		)
		(property "Device Type" "C402H22"
			(at 1.1811 -4.2291 180)
			(unlocked yes)
			(layer "F.Fab")
			(hide yes)
			(effects
				(font
					(size 1.016 1.016)
					(thickness 0.1524)
				)
			)
		)
		(duplicate_pad_numbers_are_jumpers no)
		(fp_rect
			(start -0.4318 0.9525)
			(end 0.4318 -0.9525)
			(stroke
				(width 0)
				(type default)
			)
			(fill no)
			(layer "F.CrtYd")
		)
		(fp_rect
			(start -0.4318 0.9525)
			(end 0.4318 -0.9525)
			(stroke
				(width 0)
				(type default)
			)
			(fill no)
			(layer "F.Fab")
		)
		(pad "1" smd custom
			(at 0 -0.4445 180)
			(size 0.1524 0.1524)
			(layers "F.Cu" "F.Mask" "F.Paste")
			(net "P3V3_STBY")
			(options
				(clearance outline)
				(anchor circle)
			)
			(primitives
				(gr_poly
					(pts
						(arc
							(start 0.3048 -0.2032)
							(mid 0.275042 -0.275042)
							(end 0.2032 -0.3048)
						)
						(arc
							(start -0.2032 -0.3048)
							(mid -0.275042 -0.275042)
							(end -0.3048 -0.2032)
						)
						(arc
							(start -0.3048 0.2032)
							(mid -0.275042 0.275042)
							(end -0.2032 0.3048)
						)
						(arc
							(start 0.2032 0.3048)
							(mid 0.275042 0.275042)
							(end 0.3048 0.2032)
						)
					)
					(width 0)
					(fill yes)
				)
			)
		)
		(pad "2" smd custom
			(at 0 0.4445 180)
			(size 0.1524 0.1524)
			(layers "F.Cu" "F.Mask" "F.Paste")
			(net "GND")
			(options
				(clearance outline)
				(anchor circle)
			)
			(primitives
				(gr_poly
					(pts
						(arc
							(start 0.3048 -0.2032)
							(mid 0.275042 -0.275042)
							(end 0.2032 -0.3048)
						)
						(arc
							(start -0.2032 -0.3048)
							(mid -0.275042 -0.275042)
							(end -0.3048 -0.2032)
						)
						(arc
							(start -0.3048 0.2032)
							(mid -0.275042 0.275042)
							(end -0.2032 0.3048)
						)
						(arc
							(start 0.2032 0.3048)
							(mid 0.275042 0.275042)
							(end 0.3048 0.2032)
						)
					)
					(width 0)
					(fill yes)
				)
			)
		)
	)
	(footprint ""
		(layer "F.Cu")
		(at 169.037 -178.8668 -90)
		(property "Reference" "C164"
			(at 0 0 270)
			(layer "F.SilkS")
			(hide yes)
			(effects
				(font
					(size 1.27 1.27)
				)
			)
		)
		(property "Value" "SC10U16V5KX-7-GP-U"
			(at -0.0762 -6.1214 270)
			(unlocked yes)
			(layer "F.Fab")
			(hide yes)
			(effects
				(font
					(size 1.016 1.016)
					(thickness 0.1524)
				)
			)
		)
		(property "Device Type" "C805H58"
			(at -0.0762 -8.1534 270)
			(unlocked yes)
			(layer "F.Fab")
			(hide yes)
			(effects
				(font
					(size 1.016 1.016)
					(thickness 0.1524)
				)
			)
		)
		(duplicate_pad_numbers_are_jumpers no)
		(fp_line
			(start 0.635 0)
			(end -0.635 0)
			(stroke
				(width 0.508)
				(type default)
			)
			(layer "F.SilkS")
		)
		(fp_rect
			(start -0.9652 1.778)
			(end 0.9652 -1.778)
			(stroke
				(width 0)
				(type default)
			)
			(fill no)
			(layer "F.CrtYd")
		)
		(fp_poly
			(pts
				(xy -0.9652 -1.778) (xy 0.9652 -1.778) (xy 0.9652 1.778) (xy -0.9652 1.778)
			)
			(stroke
				(width 0)
				(type default)
			)
			(fill no)
			(layer "F.Fab")
		)
		(pad "1" smd rect
			(at 0 -0.9652 270)
			(size 1.397 1.143)
			(layers "F.Cu" "F.Mask" "F.Paste")
			(net "P5V_STBY")
		)
		(pad "2" smd rect
			(at 0 0.9652 270)
			(size 1.397 1.143)
			(layers "F.Cu" "F.Mask" "F.Paste")
			(net "GND")
		)
	)
	(footprint ""
		(layer "F.Cu")
		(at 17.99971 -24.99995)
		(property "Reference" ""
			(at 0 0 0)
			(layer "F.SilkS")
			(hide yes)
			(effects
				(font
					(size 1.27 1.27)
				)
			)
		)
		(property "Value" "*"
			(at -6.38175 0.19685 0)
			(unlocked yes)
			(layer "F.Fab")
			(hide yes)
			(effects
				(font
					(size 1.016 1.016)
					(thickness 0.1524)
				)
			)
		)
		(duplicate_pad_numbers_are_jumpers no)
		(fp_poly
			(pts
				(arc
					(start 5.0673 0)
					(mid -5.0673 0)
					(end 5.0673 0)
				)
			)
			(stroke
				(width 0)
				(type default)
			)
			(fill no)
			(layer "B.CrtYd")
		)
		(fp_poly
			(pts
				(arc
					(start 5.0673 0)
					(mid -5.0673 0)
					(end 5.0673 0)
				)
			)
			(stroke
				(width 0)
				(type default)
			)
			(fill no)
			(layer "F.CrtYd")
		)
		(fp_poly
			(pts
				(arc
					(start 5.0673 0)
					(mid -5.0673 0)
					(end 5.0673 0)
				)
			)
			(stroke
				(width 0)
				(type default)
			)
			(fill no)
			(layer "B.Fab")
		)
		(fp_poly
			(pts
				(arc
					(start 5.0673 0)
					(mid -5.0673 0)
					(end 5.0673 0)
				)
			)
			(stroke
				(width 0)
				(type default)
			)
			(fill no)
			(layer "F.Fab")
		)
		(pad "1" thru_hole circle
			(at 0 0)
			(size 9.525 9.525)
			(drill 3.5052)
			(layers "*.Cu" "*.Mask")
			(remove_unused_layers no)
			(net "Net_6")
			(clearance -2.5019)
			(thermal_gap 0.3048)
			(padstack
				(mode front_inner_back)
				(layer "Inner"
					(shape circle)
					(size 3.9116 3.9116)
					(clearance 0.3048)
				)
				(layer "B.Cu"
					(shape circle)
					(size 9.525 9.525)
					(clearance -2.5019)
				)
			)
		)
	)
	(footprint ""
		(layer "F.Cu")
		(at 111.0742 -10.834878 -90)
		(property "Reference" "C148"
			(at 0 0 270)
			(layer "F.SilkS")
			(hide yes)
			(effects
				(font
					(size 1.27 1.27)
				)
			)
		)
		(property "Value" "SCD1U50V3KX-GP"
			(at 0 -2.8194 270)
			(unlocked yes)
			(layer "F.Fab")
			(hide yes)
			(effects
				(font
					(size 1.016 1.016)
					(thickness 0.1524)
				)
			)
		)
		(property "Device Type" "C603H36"
			(at 0 -4.3434 270)
			(unlocked yes)
			(layer "F.Fab")
			(hide yes)
			(effects
				(font
					(size 1.016 1.016)
					(thickness 0.1524)
				)
			)
		)
		(duplicate_pad_numbers_are_jumpers no)
		(fp_line
			(start 0.508 0)
			(end -0.508 0)
			(stroke
				(width 0.2032)
				(type default)
			)
			(layer "F.SilkS")
		)
		(fp_rect
			(start -0.5842 1.3335)
			(end 0.5842 -1.3335)
			(stroke
				(width 0)
				(type default)
			)
			(fill no)
			(layer "F.CrtYd")
		)
		(fp_rect
			(start -0.5842 1.3335)
			(end 0.5842 -1.3335)
			(stroke
				(width 0)
				(type default)
			)
			(fill no)
			(layer "F.Fab")
		)
		(pad "1" smd custom
			(at 0 -0.762 270)
			(size 0.2159 0.2159)
			(layers "F.Cu" "F.Mask" "F.Paste")
			(net "MB0_ISET_R")
			(options
				(clearance outline)
				(anchor circle)
			)
			(primitives
				(gr_poly
					(pts
						(arc
							(start -0.3302 -0.4318)
							(mid -0.402042 -0.402042)
							(end -0.4318 -0.3302)
						)
						(arc
							(start -0.4318 0.3302)
							(mid -0.402042 0.402042)
							(end -0.3302 0.4318)
						)
						(arc
							(start 0.3302 0.4318)
							(mid 0.402042 0.402042)
							(end 0.4318 0.3302)
						)
						(arc
							(start 0.4318 -0.3302)
							(mid 0.402042 -0.402042)
							(end 0.3302 -0.4318)
						)
					)
					(width 0)
					(fill yes)
				)
			)
		)
		(pad "2" smd custom
			(at 0 0.762 270)
			(size 0.2159 0.2159)
			(layers "F.Cu" "F.Mask" "F.Paste")
			(net "AGND_CURRENT_MON")
			(options
				(clearance outline)
				(anchor circle)
			)
			(primitives
				(gr_poly
					(pts
						(arc
							(start -0.3302 -0.4318)
							(mid -0.402042 -0.402042)
							(end -0.4318 -0.3302)
						)
						(arc
							(start -0.4318 0.3302)
							(mid -0.402042 0.402042)
							(end -0.3302 0.4318)
						)
						(arc
							(start 0.3302 0.4318)
							(mid 0.402042 0.402042)
							(end 0.4318 0.3302)
						)
						(arc
							(start 0.4318 -0.3302)
							(mid 0.402042 -0.402042)
							(end 0.3302 -0.4318)
						)
					)
					(width 0)
					(fill yes)
				)
			)
		)
	)
	(footprint ""
		(layer "F.Cu")
		(at 95.070168 -148.6154)
		(property "Reference" "R41"
			(at 0 0 0)
			(layer "F.SilkS")
			(hide yes)
			(effects
				(font
					(size 1.27 1.27)
				)
			)
		)
		(property "Value" "4K7R2F-GP"
			(at 0.064008 -3.993896 0)
			(unlocked yes)
			(layer "F.Fab")
			(hide yes)
			(effects
				(font
					(size 1.016 1.016)
					(thickness 0.1524)
				)
			)
		)
		(property "Device Type" "R402H16"
			(at 0.064008 -5.517896 0)
			(unlocked yes)
			(layer "F.Fab")
			(hide yes)
			(effects
				(font
					(size 1.016 1.016)
					(thickness 0.1524)
				)
			)
		)
		(duplicate_pad_numbers_are_jumpers no)
		(fp_line
			(start -0.508 -0.9398)
			(end -0.508 0.9398)
			(stroke
				(width 0.1524)
				(type default)
			)
			(layer "F.SilkS")
		)
		(fp_line
			(start 0.508 -0.9398)
			(end -0.508 -0.9398)
			(stroke
				(width 0.1524)
				(type default)
			)
			(layer "F.SilkS")
		)
		(fp_rect
			(start -0.508 0.9398)
			(end 0.508 -0.9398)
			(stroke
				(width 0)
				(type default)
			)
			(fill no)
			(layer "F.CrtYd")
		)
		(fp_rect
			(start -0.508 0.9398)
			(end 0.508 -0.9398)
			(stroke
				(width 0)
				(type default)
			)
			(fill no)
			(layer "F.Fab")
		)
		(pad "1" smd custom
			(at 0 -0.4445)
			(size 0.1397 0.1397)
			(layers "F.Cu" "F.Mask" "F.Paste")
			(net "USB_EN_2")
			(options
				(clearance outline)
				(anchor circle)
			)
			(primitives
				(gr_poly
					(pts
						(arc
							(start -0.1778 -0.2794)
							(mid -0.249642 -0.249642)
							(end -0.2794 -0.1778)
						)
						(arc
							(start -0.2794 0.1778)
							(mid -0.249642 0.249642)
							(end -0.1778 0.2794)
						)
						(arc
							(start 0.1778 0.2794)
							(mid 0.249642 0.249642)
							(end 0.2794 0.1778)
						)
						(arc
							(start 0.2794 -0.1778)
							(mid 0.249642 -0.249642)
							(end 0.1778 -0.2794)
						)
					)
					(width 0)
					(fill yes)
				)
			)
		)
		(pad "2" smd custom
			(at 0 0.4445)
			(size 0.1397 0.1397)
			(layers "F.Cu" "F.Mask" "F.Paste")
			(net "GND")
			(options
				(clearance outline)
				(anchor circle)
			)
			(primitives
				(gr_poly
					(pts
						(arc
							(start -0.1778 -0.2794)
							(mid -0.249642 -0.249642)
							(end -0.2794 -0.1778)
						)
						(arc
							(start -0.2794 0.1778)
							(mid -0.249642 0.249642)
							(end -0.1778 0.2794)
						)
						(arc
							(start 0.1778 0.2794)
							(mid 0.249642 0.249642)
							(end 0.2794 0.1778)
						)
						(arc
							(start 0.2794 -0.1778)
							(mid 0.249642 -0.249642)
							(end 0.1778 -0.2794)
						)
					)
					(width 0)
					(fill yes)
				)
			)
		)
	)
	(footprint ""
		(layer "F.Cu")
		(at 164.203126 -106.473244)
		(property "Reference" "R623"
			(at 0 0 0)
			(layer "F.SilkS")
			(hide yes)
			(effects
				(font
					(size 1.27 1.27)
				)
			)
		)
		(property "Value" "150R2F-1-GP"
			(at 0.064008 -3.993896 0)
			(unlocked yes)
			(layer "F.Fab")
			(hide yes)
			(effects
				(font
					(size 1.016 1.016)
					(thickness 0.1524)
				)
			)
		)
		(property "Device Type" "R402H16"
			(at 0.064008 -5.517896 0)
			(unlocked yes)
			(layer "F.Fab")
			(hide yes)
			(effects
				(font
					(size 1.016 1.016)
					(thickness 0.1524)
				)
			)
		)
		(duplicate_pad_numbers_are_jumpers no)
		(fp_line
			(start -0.508 -0.9398)
			(end -0.508 0.9398)
			(stroke
				(width 0.1524)
				(type default)
			)
			(layer "F.SilkS")
		)
		(fp_line
			(start 0.508 -0.9398)
			(end -0.508 -0.9398)
			(stroke
				(width 0.1524)
				(type default)
			)
			(layer "F.SilkS")
		)
		(fp_rect
			(start -0.508 0.9398)
			(end 0.508 -0.9398)
			(stroke
				(width 0)
				(type default)
			)
			(fill no)
			(layer "F.CrtYd")
		)
		(fp_rect
			(start -0.508 0.9398)
			(end 0.508 -0.9398)
			(stroke
				(width 0)
				(type default)
			)
			(fill no)
			(layer "F.Fab")
		)
		(pad "1" smd custom
			(at 0 -0.4445)
			(size 0.1397 0.1397)
			(layers "F.Cu" "F.Mask" "F.Paste")
			(net "P3V3")
			(options
				(clearance outline)
				(anchor circle)
			)
			(primitives
				(gr_poly
					(pts
						(arc
							(start -0.1778 -0.2794)
							(mid -0.249642 -0.249642)
							(end -0.2794 -0.1778)
						)
						(arc
							(start -0.2794 0.1778)
							(mid -0.249642 0.249642)
							(end -0.1778 0.2794)
						)
						(arc
							(start 0.1778 0.2794)
							(mid 0.249642 0.249642)
							(end 0.2794 0.1778)
						)
						(arc
							(start 0.2794 -0.1778)
							(mid 0.249642 -0.249642)
							(end 0.1778 -0.2794)
						)
					)
					(width 0)
					(fill yes)
				)
			)
		)
		(pad "2" smd custom
			(at 0 0.4445)
			(size 0.1397 0.1397)
			(layers "F.Cu" "F.Mask" "F.Paste")
			(net "SYS_HB_LED_R")
			(options
				(clearance outline)
				(anchor circle)
			)
			(primitives
				(gr_poly
					(pts
						(arc
							(start -0.1778 -0.2794)
							(mid -0.249642 -0.249642)
							(end -0.2794 -0.1778)
						)
						(arc
							(start -0.2794 0.1778)
							(mid -0.249642 0.249642)
							(end -0.1778 0.2794)
						)
						(arc
							(start 0.1778 0.2794)
							(mid 0.249642 0.249642)
							(end 0.2794 0.1778)
						)
						(arc
							(start 0.2794 -0.1778)
							(mid 0.249642 -0.249642)
							(end 0.1778 -0.2794)
						)
					)
					(width 0)
					(fill yes)
				)
			)
		)
	)
	(footprint ""
		(layer "F.Cu")
		(at 153.7716 -38.4556)
		(property "Reference" "TP182"
			(at 0 0 0)
			(layer "F.SilkS")
			(hide yes)
			(effects
				(font
					(size 1.27 1.27)
				)
			)
		)
		(property "Value" "TPAD28-2-GP"
			(at -0.0127 -1.6637 0)
			(unlocked yes)
			(layer "F.Fab")
			(hide yes)
			(effects
				(font
					(size 1.016 1.016)
					(thickness 0.1524)
				)
			)
		)
		(property "Device Type" "TPAD28"
			(at -0.0127 -3.1877 0)
			(unlocked yes)
			(layer "F.Fab")
			(hide yes)
			(effects
				(font
					(size 1.016 1.016)
					(thickness 0.1524)
				)
			)
		)
		(duplicate_pad_numbers_are_jumpers no)
		(fp_poly
			(pts
				(arc
					(start 0.3556 0)
					(mid -0.3556 0)
					(end 0.3556 0)
				)
			)
			(stroke
				(width 0)
				(type default)
			)
			(fill no)
			(layer "F.CrtYd")
		)
		(fp_poly
			(pts
				(arc
					(start 0.6096 0)
					(mid -0.6096 0)
					(end 0.6096 0)
				)
			)
			(stroke
				(width 0)
				(type default)
			)
			(fill no)
			(layer "F.Fab")
		)
		(pad "1" smd circle
			(at 0 0)
			(size 0.7112 0.7112)
			(layers "F.Cu" "F.Mask" "F.Paste")
			(net "ZDEF_EXTB_TP_B1")
		)
	)
	(footprint ""
		(layer "F.Cu")
		(at 224.249234 -60.455048 180)
		(property "Reference" "C305"
			(at 0 0 180)
			(layer "F.SilkS")
			(hide yes)
			(effects
				(font
					(size 1.27 1.27)
				)
			)
		)
		(property "Value" "SC12P50V2JN-3GP"
			(at 1.1811 -2.7051 180)
			(unlocked yes)
			(layer "F.Fab")
			(hide yes)
			(effects
				(font
					(size 1.016 1.016)
					(thickness 0.1524)
				)
			)
		)
		(property "Device Type" "C402H24"
			(at 1.1811 -4.2291 180)
			(unlocked yes)
			(layer "F.Fab")
			(hide yes)
			(effects
				(font
					(size 1.016 1.016)
					(thickness 0.1524)
				)
			)
		)
		(duplicate_pad_numbers_are_jumpers no)
		(fp_rect
			(start -0.4318 0.9525)
			(end 0.4318 -0.9525)
			(stroke
				(width 0)
				(type default)
			)
			(fill no)
			(layer "F.CrtYd")
		)
		(fp_rect
			(start -0.4318 0.9525)
			(end 0.4318 -0.9525)
			(stroke
				(width 0)
				(type default)
			)
			(fill no)
			(layer "F.Fab")
		)
		(pad "1" smd custom
			(at 0 -0.4445 180)
			(size 0.1524 0.1524)
			(layers "F.Cu" "F.Mask" "F.Paste")
			(net "IOC_REF_CLK_P")
			(options
				(clearance outline)
				(anchor circle)
			)
			(primitives
				(gr_poly
					(pts
						(arc
							(start 0.3048 -0.2032)
							(mid 0.275042 -0.275042)
							(end 0.2032 -0.3048)
						)
						(arc
							(start -0.2032 -0.3048)
							(mid -0.275042 -0.275042)
							(end -0.3048 -0.2032)
						)
						(arc
							(start -0.3048 0.2032)
							(mid -0.275042 0.275042)
							(end -0.2032 0.3048)
						)
						(arc
							(start 0.2032 0.3048)
							(mid 0.275042 0.275042)
							(end 0.3048 0.2032)
						)
					)
					(width 0)
					(fill yes)
				)
			)
		)
		(pad "2" smd custom
			(at 0 0.4445 180)
			(size 0.1524 0.1524)
			(layers "F.Cu" "F.Mask" "F.Paste")
			(net "GND")
			(options
				(clearance outline)
				(anchor circle)
			)
			(primitives
				(gr_poly
					(pts
						(arc
							(start 0.3048 -0.2032)
							(mid 0.275042 -0.275042)
							(end 0.2032 -0.3048)
						)
						(arc
							(start -0.2032 -0.3048)
							(mid -0.275042 -0.275042)
							(end -0.3048 -0.2032)
						)
						(arc
							(start -0.3048 0.2032)
							(mid -0.275042 0.275042)
							(end -0.2032 0.3048)
						)
						(arc
							(start 0.2032 0.3048)
							(mid 0.275042 0.275042)
							(end 0.3048 0.2032)
						)
					)
					(width 0)
					(fill yes)
				)
			)
		)
	)
	(footprint ""
		(layer "F.Cu")
		(at 19.752564 -160.971484 180)
		(property "Reference" "R529"
			(at 0 0 180)
			(layer "F.SilkS")
			(hide yes)
			(effects
				(font
					(size 1.27 1.27)
				)
			)
		)
		(property "Value" "0R5J-5-GP"
			(at 0 -8.9535 180)
			(unlocked yes)
			(layer "F.Fab")
			(hide yes)
			(effects
				(font
					(size 1.27 1.016)
					(thickness 0.1524)
				)
			)
		)
		(property "Device Type" "R805H24"
			(at 0 -10.6299 180)
			(unlocked yes)
			(layer "F.Fab")
			(hide yes)
			(effects
				(font
					(size 1.27 1.016)
					(thickness 0.1524)
				)
			)
		)
		(duplicate_pad_numbers_are_jumpers no)
		(fp_line
			(start 0.889 1.7018)
			(end 0.889 -0.508)
			(stroke
				(width 0.1524)
				(type default)
			)
			(layer "F.SilkS")
		)
		(fp_line
			(start 0.889 -1.7018)
			(end 0.889 -0.381)
			(stroke
				(width 0.1524)
				(type default)
			)
			(layer "F.SilkS")
		)
		(fp_line
			(start 0.889 -1.7018)
			(end -0.889 -1.7018)
			(stroke
				(width 0.1524)
				(type default)
			)
			(layer "F.SilkS")
		)
		(fp_line
			(start -0.889 1.7018)
			(end 0.889 1.7018)
			(stroke
				(width 0.1524)
				(type default)
			)
			(layer "F.SilkS")
		)
		(fp_line
			(start -0.889 0.0762)
			(end -0.889 1.7018)
			(stroke
				(width 0.1524)
				(type default)
			)
			(layer "F.SilkS")
		)
		(fp_line
			(start -0.889 -1.7018)
			(end -0.889 0.2794)
			(stroke
				(width 0.1524)
				(type default)
			)
			(layer "F.SilkS")
		)
		(fp_poly
			(pts
				(xy 0.9652 -1.778) (xy 0.9652 1.778) (xy -0.9652 1.778) (xy -0.9652 -1.778)
			)
			(stroke
				(width 0)
				(type default)
			)
			(fill no)
			(layer "F.CrtYd")
		)
		(fp_rect
			(start -0.9652 1.778)
			(end 0.9652 -1.778)
			(stroke
				(width 0)
				(type default)
			)
			(fill no)
			(layer "F.Fab")
		)
		(pad "1" smd rect
			(at 0 -0.9652 180)
			(size 1.397 1.143)
			(layers "F.Cu" "F.Mask" "F.Paste")
			(net "P1V2_STBY")
		)
		(pad "2" smd rect
			(at 0 0.9652 180)
			(size 1.397 1.143)
			(layers "F.Cu" "F.Mask" "F.Paste")
			(net "TPS74801_P1V2_STBY_OUT")
		)
	)
	(footprint ""
		(layer "F.Cu")
		(at 76.498704 -141.633194 90)
		(property "Reference" "R129"
			(at 0 0 90)
			(layer "F.SilkS")
			(hide yes)
			(effects
				(font
					(size 1.27 1.27)
				)
			)
		)
		(property "Value" "0R2J-2-GP"
			(at 0.064008 -3.993896 90)
			(unlocked yes)
			(layer "F.Fab")
			(hide yes)
			(effects
				(font
					(size 1.016 1.016)
					(thickness 0.1524)
				)
			)
		)
		(property "Device Type" "R402H16"
			(at 0.064008 -5.517896 90)
			(unlocked yes)
			(layer "F.Fab")
			(hide yes)
			(effects
				(font
					(size 1.016 1.016)
					(thickness 0.1524)
				)
			)
		)
		(duplicate_pad_numbers_are_jumpers no)
		(fp_line
			(start 0.508 -0.9398)
			(end -0.508 -0.9398)
			(stroke
				(width 0.1524)
				(type default)
			)
			(layer "F.SilkS")
		)
		(fp_line
			(start -0.508 -0.9398)
			(end -0.508 0.9398)
			(stroke
				(width 0.1524)
				(type default)
			)
			(layer "F.SilkS")
		)
		(fp_rect
			(start -0.508 0.9398)
			(end 0.508 -0.9398)
			(stroke
				(width 0)
				(type default)
			)
			(fill no)
			(layer "F.CrtYd")
		)
		(fp_rect
			(start -0.508 0.9398)
			(end 0.508 -0.9398)
			(stroke
				(width 0)
				(type default)
			)
			(fill no)
			(layer "F.Fab")
		)
		(pad "1" smd custom
			(at 0 -0.4445 90)
			(size 0.1397 0.1397)
			(layers "F.Cu" "F.Mask" "F.Paste")
			(net "I2C_EXP_RMT_SCL")
			(options
				(clearance outline)
				(anchor circle)
			)
			(primitives
				(gr_poly
					(pts
						(arc
							(start -0.1778 -0.2794)
							(mid -0.249642 -0.249642)
							(end -0.2794 -0.1778)
						)
						(arc
							(start -0.2794 0.1778)
							(mid -0.249642 0.249642)
							(end -0.1778 0.2794)
						)
						(arc
							(start 0.1778 0.2794)
							(mid 0.249642 0.249642)
							(end 0.2794 0.1778)
						)
						(arc
							(start 0.2794 -0.1778)
							(mid 0.249642 -0.249642)
							(end 0.1778 -0.2794)
						)
					)
					(width 0)
					(fill yes)
				)
			)
		)
		(pad "2" smd custom
			(at 0 0.4445 90)
			(size 0.1397 0.1397)
			(layers "F.Cu" "F.Mask" "F.Paste")
			(net "I2C_EXP_RMT_SCL_R")
			(options
				(clearance outline)
				(anchor circle)
			)
			(primitives
				(gr_poly
					(pts
						(arc
							(start -0.1778 -0.2794)
							(mid -0.249642 -0.249642)
							(end -0.2794 -0.1778)
						)
						(arc
							(start -0.2794 0.1778)
							(mid -0.249642 0.249642)
							(end -0.1778 0.2794)
						)
						(arc
							(start 0.1778 0.2794)
							(mid 0.249642 0.249642)
							(end 0.2794 0.1778)
						)
						(arc
							(start 0.2794 -0.1778)
							(mid 0.249642 -0.249642)
							(end 0.1778 -0.2794)
						)
					)
					(width 0)
					(fill yes)
				)
			)
		)
	)
	(footprint ""
		(layer "F.Cu")
		(at 33.7693 -152.2095 -90)
		(property "Reference" "R333"
			(at 0 0 270)
			(layer "F.SilkS")
			(hide yes)
			(effects
				(font
					(size 1.27 1.27)
				)
			)
		)
		(property "Value" "0R2J-2-GP"
			(at 0.064008 -3.993896 270)
			(unlocked yes)
			(layer "F.Fab")
			(hide yes)
			(effects
				(font
					(size 1.016 1.016)
					(thickness 0.1524)
				)
			)
		)
		(property "Device Type" "R402H16"
			(at 0.064008 -5.517896 270)
			(unlocked yes)
			(layer "F.Fab")
			(hide yes)
			(effects
				(font
					(size 1.016 1.016)
					(thickness 0.1524)
				)
			)
		)
		(duplicate_pad_numbers_are_jumpers no)
		(fp_line
			(start -0.508 -0.9398)
			(end -0.508 0.9398)
			(stroke
				(width 0.1524)
				(type default)
			)
			(layer "F.SilkS")
		)
		(fp_line
			(start 0.508 -0.9398)
			(end -0.508 -0.9398)
			(stroke
				(width 0.1524)
				(type default)
			)
			(layer "F.SilkS")
		)
		(fp_rect
			(start -0.508 0.9398)
			(end 0.508 -0.9398)
			(stroke
				(width 0)
				(type default)
			)
			(fill no)
			(layer "F.CrtYd")
		)
		(fp_rect
			(start -0.508 0.9398)
			(end 0.508 -0.9398)
			(stroke
				(width 0)
				(type default)
			)
			(fill no)
			(layer "F.Fab")
		)
		(pad "1" smd custom
			(at 0 -0.4445 270)
			(size 0.1397 0.1397)
			(layers "F.Cu" "F.Mask" "F.Paste")
			(net "THROTTLE_N")
			(options
				(clearance outline)
				(anchor circle)
			)
			(primitives
				(gr_poly
					(pts
						(arc
							(start -0.1778 -0.2794)
							(mid -0.249642 -0.249642)
							(end -0.2794 -0.1778)
						)
						(arc
							(start -0.2794 0.1778)
							(mid -0.249642 0.249642)
							(end -0.1778 0.2794)
						)
						(arc
							(start 0.1778 0.2794)
							(mid 0.249642 0.249642)
							(end 0.2794 0.1778)
						)
						(arc
							(start 0.2794 -0.1778)
							(mid 0.249642 -0.249642)
							(end 0.1778 -0.2794)
						)
					)
					(width 0)
					(fill yes)
				)
			)
		)
		(pad "2" smd custom
			(at 0 0.4445 270)
			(size 0.1397 0.1397)
			(layers "F.Cu" "F.Mask" "F.Paste")
			(net "COMP_FAST_THROTTLE_N")
			(options
				(clearance outline)
				(anchor circle)
			)
			(primitives
				(gr_poly
					(pts
						(arc
							(start -0.1778 -0.2794)
							(mid -0.249642 -0.249642)
							(end -0.2794 -0.1778)
						)
						(arc
							(start -0.2794 0.1778)
							(mid -0.249642 0.249642)
							(end -0.1778 0.2794)
						)
						(arc
							(start 0.1778 0.2794)
							(mid 0.249642 0.249642)
							(end 0.2794 0.1778)
						)
						(arc
							(start 0.2794 -0.1778)
							(mid 0.249642 -0.249642)
							(end 0.1778 -0.2794)
						)
					)
					(width 0)
					(fill yes)
				)
			)
		)
	)
	(footprint ""
		(layer "F.Cu")
		(at 189.4078 -48.4378 180)
		(property "Reference" "R646"
			(at 0 0 180)
			(layer "F.SilkS")
			(hide yes)
			(effects
				(font
					(size 1.27 1.27)
				)
			)
		)
		(property "Value" "10KR2F-2-GP"
			(at 0.064008 -3.993896 180)
			(unlocked yes)
			(layer "F.Fab")
			(hide yes)
			(effects
				(font
					(size 1.016 1.016)
					(thickness 0.1524)
				)
			)
		)
		(property "Device Type" "R402H16"
			(at 0.064008 -5.517896 180)
			(unlocked yes)
			(layer "F.Fab")
			(hide yes)
			(effects
				(font
					(size 1.016 1.016)
					(thickness 0.1524)
				)
			)
		)
		(duplicate_pad_numbers_are_jumpers no)
		(fp_line
			(start 0.508 -0.9398)
			(end -0.508 -0.9398)
			(stroke
				(width 0.1524)
				(type default)
			)
			(layer "F.SilkS")
		)
		(fp_line
			(start -0.508 -0.9398)
			(end -0.508 0.9398)
			(stroke
				(width 0.1524)
				(type default)
			)
			(layer "F.SilkS")
		)
		(fp_rect
			(start -0.508 0.9398)
			(end 0.508 -0.9398)
			(stroke
				(width 0)
				(type default)
			)
			(fill no)
			(layer "F.CrtYd")
		)
		(fp_rect
			(start -0.508 0.9398)
			(end 0.508 -0.9398)
			(stroke
				(width 0)
				(type default)
			)
			(fill no)
			(layer "F.Fab")
		)
		(pad "1" smd custom
			(at 0 -0.4445 180)
			(size 0.1397 0.1397)
			(layers "F.Cu" "F.Mask" "F.Paste")
			(net "P1V8")
			(options
				(clearance outline)
				(anchor circle)
			)
			(primitives
				(gr_poly
					(pts
						(arc
							(start -0.1778 -0.2794)
							(mid -0.249642 -0.249642)
							(end -0.2794 -0.1778)
						)
						(arc
							(start -0.2794 0.1778)
							(mid -0.249642 0.249642)
							(end -0.1778 0.2794)
						)
						(arc
							(start 0.1778 0.2794)
							(mid 0.249642 0.249642)
							(end 0.2794 0.1778)
						)
						(arc
							(start 0.2794 -0.1778)
							(mid 0.249642 -0.249642)
							(end 0.1778 -0.2794)
						)
					)
					(width 0)
					(fill yes)
				)
			)
		)
		(pad "2" smd custom
			(at 0 0.4445 180)
			(size 0.1397 0.1397)
			(layers "F.Cu" "F.Mask" "F.Paste")
			(net "LSI_JTAG_EN_N")
			(options
				(clearance outline)
				(anchor circle)
			)
			(primitives
				(gr_poly
					(pts
						(arc
							(start -0.1778 -0.2794)
							(mid -0.249642 -0.249642)
							(end -0.2794 -0.1778)
						)
						(arc
							(start -0.2794 0.1778)
							(mid -0.249642 0.249642)
							(end -0.1778 0.2794)
						)
						(arc
							(start 0.1778 0.2794)
							(mid 0.249642 0.249642)
							(end 0.2794 0.1778)
						)
						(arc
							(start 0.2794 -0.1778)
							(mid 0.249642 -0.249642)
							(end 0.1778 -0.2794)
						)
					)
					(width 0)
					(fill yes)
				)
			)
		)
	)
	(footprint ""
		(layer "F.Cu")
		(at 157.099 -120.142 -90)
		(property "Reference" "C215"
			(at 0 0 270)
			(layer "F.SilkS")
			(hide yes)
			(effects
				(font
					(size 1.27 1.27)
				)
			)
		)
		(property "Value" "SC10U6D3V5KX-4GP"
			(at -0.0762 -6.1214 270)
			(unlocked yes)
			(layer "F.Fab")
			(hide yes)
			(effects
				(font
					(size 1.016 1.016)
					(thickness 0.1524)
				)
			)
		)
		(property "Device Type" "C805H58"
			(at -0.0762 -8.1534 270)
			(unlocked yes)
			(layer "F.Fab")
			(hide yes)
			(effects
				(font
					(size 1.016 1.016)
					(thickness 0.1524)
				)
			)
		)
		(duplicate_pad_numbers_are_jumpers no)
		(fp_line
			(start 0.635 0)
			(end -0.635 0)
			(stroke
				(width 0.508)
				(type default)
			)
			(layer "F.SilkS")
		)
		(fp_rect
			(start -0.9652 1.778)
			(end 0.9652 -1.778)
			(stroke
				(width 0)
				(type default)
			)
			(fill no)
			(layer "F.CrtYd")
		)
		(fp_poly
			(pts
				(xy -0.9652 -1.778) (xy 0.9652 -1.778) (xy 0.9652 1.778) (xy -0.9652 1.778)
			)
			(stroke
				(width 0)
				(type default)
			)
			(fill no)
			(layer "F.Fab")
		)
		(pad "1" smd rect
			(at 0 -0.9652 270)
			(size 1.397 1.143)
			(layers "F.Cu" "F.Mask" "F.Paste")
			(net "P1V8_STBY")
		)
		(pad "2" smd rect
			(at 0 0.9652 270)
			(size 1.397 1.143)
			(layers "F.Cu" "F.Mask" "F.Paste")
			(net "GND")
		)
	)
	(footprint ""
		(layer "F.Cu")
		(at 98.878644 -159.532574 -90)
		(property "Reference" "R20"
			(at 0 0 270)
			(layer "F.SilkS")
			(hide yes)
			(effects
				(font
					(size 1.27 1.27)
				)
			)
		)
		(property "Value" "4K7R2F-GP"
			(at 0.064008 -3.993896 270)
			(unlocked yes)
			(layer "F.Fab")
			(hide yes)
			(effects
				(font
					(size 1.016 1.016)
					(thickness 0.1524)
				)
			)
		)
		(property "Device Type" "R402H16"
			(at 0.064008 -5.517896 270)
			(unlocked yes)
			(layer "F.Fab")
			(hide yes)
			(effects
				(font
					(size 1.016 1.016)
					(thickness 0.1524)
				)
			)
		)
		(duplicate_pad_numbers_are_jumpers no)
		(fp_line
			(start -0.508 -0.9398)
			(end -0.508 0.9398)
			(stroke
				(width 0.1524)
				(type default)
			)
			(layer "F.SilkS")
		)
		(fp_line
			(start 0.508 -0.9398)
			(end -0.508 -0.9398)
			(stroke
				(width 0.1524)
				(type default)
			)
			(layer "F.SilkS")
		)
		(fp_rect
			(start -0.508 0.9398)
			(end 0.508 -0.9398)
			(stroke
				(width 0)
				(type default)
			)
			(fill no)
			(layer "F.CrtYd")
		)
		(fp_rect
			(start -0.508 0.9398)
			(end 0.508 -0.9398)
			(stroke
				(width 0)
				(type default)
			)
			(fill no)
			(layer "F.Fab")
		)
		(pad "1" smd custom
			(at 0 -0.4445 270)
			(size 0.1397 0.1397)
			(layers "F.Cu" "F.Mask" "F.Paste")
			(net "P3V3_STBY")
			(options
				(clearance outline)
				(anchor circle)
			)
			(primitives
				(gr_poly
					(pts
						(arc
							(start -0.1778 -0.2794)
							(mid -0.249642 -0.249642)
							(end -0.2794 -0.1778)
						)
						(arc
							(start -0.2794 0.1778)
							(mid -0.249642 0.249642)
							(end -0.1778 0.2794)
						)
						(arc
							(start 0.1778 0.2794)
							(mid 0.249642 0.249642)
							(end 0.2794 0.1778)
						)
						(arc
							(start 0.2794 -0.1778)
							(mid 0.249642 -0.249642)
							(end 0.1778 -0.2794)
						)
					)
					(width 0)
					(fill yes)
				)
			)
		)
		(pad "2" smd custom
			(at 0 0.4445 270)
			(size 0.1397 0.1397)
			(layers "F.Cu" "F.Mask" "F.Paste")
			(net "VBUS_DET")
			(options
				(clearance outline)
				(anchor circle)
			)
			(primitives
				(gr_poly
					(pts
						(arc
							(start -0.1778 -0.2794)
							(mid -0.249642 -0.249642)
							(end -0.2794 -0.1778)
						)
						(arc
							(start -0.2794 0.1778)
							(mid -0.249642 0.249642)
							(end -0.1778 0.2794)
						)
						(arc
							(start 0.1778 0.2794)
							(mid 0.249642 0.249642)
							(end 0.2794 0.1778)
						)
						(arc
							(start 0.2794 -0.1778)
							(mid 0.249642 -0.249642)
							(end 0.1778 -0.2794)
						)
					)
					(width 0)
					(fill yes)
				)
			)
		)
	)
	(footprint ""
		(layer "F.Cu")
		(at 94.488 -30.734 90)
		(property "Reference" "C22"
			(at 0 0 90)
			(layer "F.SilkS")
			(hide yes)
			(effects
				(font
					(size 1.27 1.27)
				)
			)
		)
		(property "Value" "SC1U16V3KX-5GP"
			(at 0 -2.8194 90)
			(unlocked yes)
			(layer "F.Fab")
			(hide yes)
			(effects
				(font
					(size 1.016 1.016)
					(thickness 0.1524)
				)
			)
		)
		(property "Device Type" "C603H36"
			(at 0 -4.3434 90)
			(unlocked yes)
			(layer "F.Fab")
			(hide yes)
			(effects
				(font
					(size 1.016 1.016)
					(thickness 0.1524)
				)
			)
		)
		(duplicate_pad_numbers_are_jumpers no)
		(fp_line
			(start 0.508 0)
			(end -0.508 0)
			(stroke
				(width 0.2032)
				(type default)
			)
			(layer "F.SilkS")
		)
		(fp_rect
			(start -0.5842 1.3335)
			(end 0.5842 -1.3335)
			(stroke
				(width 0)
				(type default)
			)
			(fill no)
			(layer "F.CrtYd")
		)
		(fp_rect
			(start -0.5842 1.3335)
			(end 0.5842 -1.3335)
			(stroke
				(width 0)
				(type default)
			)
			(fill no)
			(layer "F.Fab")
		)
		(pad "1" smd custom
			(at 0 -0.762 90)
			(size 0.2159 0.2159)
			(layers "F.Cu" "F.Mask" "F.Paste")
			(net "P5V_USB")
			(options
				(clearance outline)
				(anchor circle)
			)
			(primitives
				(gr_poly
					(pts
						(arc
							(start -0.3302 -0.4318)
							(mid -0.402042 -0.402042)
							(end -0.4318 -0.3302)
						)
						(arc
							(start -0.4318 0.3302)
							(mid -0.402042 0.402042)
							(end -0.3302 0.4318)
						)
						(arc
							(start 0.3302 0.4318)
							(mid 0.402042 0.402042)
							(end 0.4318 0.3302)
						)
						(arc
							(start 0.4318 -0.3302)
							(mid 0.402042 -0.402042)
							(end 0.3302 -0.4318)
						)
					)
					(width 0)
					(fill yes)
				)
			)
		)
		(pad "2" smd custom
			(at 0 0.762 90)
			(size 0.2159 0.2159)
			(layers "F.Cu" "F.Mask" "F.Paste")
			(net "GND")
			(options
				(clearance outline)
				(anchor circle)
			)
			(primitives
				(gr_poly
					(pts
						(arc
							(start -0.3302 -0.4318)
							(mid -0.402042 -0.402042)
							(end -0.4318 -0.3302)
						)
						(arc
							(start -0.4318 0.3302)
							(mid -0.402042 0.402042)
							(end -0.3302 0.4318)
						)
						(arc
							(start 0.3302 0.4318)
							(mid 0.402042 0.402042)
							(end 0.4318 0.3302)
						)
						(arc
							(start 0.4318 -0.3302)
							(mid 0.402042 -0.402042)
							(end 0.3302 -0.4318)
						)
					)
					(width 0)
					(fill yes)
				)
			)
		)
	)
	(footprint ""
		(layer "F.Cu")
		(at 182.340504 -150.883366 90)
		(property "Reference" "R465"
			(at 0 0 90)
			(layer "F.SilkS")
			(hide yes)
			(effects
				(font
					(size 1.27 1.27)
				)
			)
		)
		(property "Value" "2K2R2F-GP"
			(at 0.064008 -3.993896 90)
			(unlocked yes)
			(layer "F.Fab")
			(hide yes)
			(effects
				(font
					(size 1.016 1.016)
					(thickness 0.1524)
				)
			)
		)
		(property "Device Type" "R402H16"
			(at 0.064008 -5.517896 90)
			(unlocked yes)
			(layer "F.Fab")
			(hide yes)
			(effects
				(font
					(size 1.016 1.016)
					(thickness 0.1524)
				)
			)
		)
		(duplicate_pad_numbers_are_jumpers no)
		(fp_line
			(start 0.508 -0.9398)
			(end -0.508 -0.9398)
			(stroke
				(width 0.1524)
				(type default)
			)
			(layer "F.SilkS")
		)
		(fp_line
			(start -0.508 -0.9398)
			(end -0.508 0.9398)
			(stroke
				(width 0.1524)
				(type default)
			)
			(layer "F.SilkS")
		)
		(fp_rect
			(start -0.508 0.9398)
			(end 0.508 -0.9398)
			(stroke
				(width 0)
				(type default)
			)
			(fill no)
			(layer "F.CrtYd")
		)
		(fp_rect
			(start -0.508 0.9398)
			(end 0.508 -0.9398)
			(stroke
				(width 0)
				(type default)
			)
			(fill no)
			(layer "F.Fab")
		)
		(pad "1" smd custom
			(at 0 -0.4445 90)
			(size 0.1397 0.1397)
			(layers "F.Cu" "F.Mask" "F.Paste")
			(net "P5V_EN_R")
			(options
				(clearance outline)
				(anchor circle)
			)
			(primitives
				(gr_poly
					(pts
						(arc
							(start -0.1778 -0.2794)
							(mid -0.249642 -0.249642)
							(end -0.2794 -0.1778)
						)
						(arc
							(start -0.2794 0.1778)
							(mid -0.249642 0.249642)
							(end -0.1778 0.2794)
						)
						(arc
							(start 0.1778 0.2794)
							(mid 0.249642 0.249642)
							(end 0.2794 0.1778)
						)
						(arc
							(start 0.2794 -0.1778)
							(mid 0.249642 -0.249642)
							(end 0.1778 -0.2794)
						)
					)
					(width 0)
					(fill yes)
				)
			)
		)
		(pad "2" smd custom
			(at 0 0.4445 90)
			(size 0.1397 0.1397)
			(layers "F.Cu" "F.Mask" "F.Paste")
			(net "GND")
			(options
				(clearance outline)
				(anchor circle)
			)
			(primitives
				(gr_poly
					(pts
						(arc
							(start -0.1778 -0.2794)
							(mid -0.249642 -0.249642)
							(end -0.2794 -0.1778)
						)
						(arc
							(start -0.2794 0.1778)
							(mid -0.249642 0.249642)
							(end -0.1778 0.2794)
						)
						(arc
							(start 0.1778 0.2794)
							(mid 0.249642 0.249642)
							(end 0.2794 0.1778)
						)
						(arc
							(start 0.2794 -0.1778)
							(mid 0.249642 -0.249642)
							(end 0.1778 -0.2794)
						)
					)
					(width 0)
					(fill yes)
				)
			)
		)
	)
	(footprint ""
		(layer "F.Cu")
		(at 55.0926 -130.547364)
		(property "Reference" "R146"
			(at 0 0 0)
			(layer "F.SilkS")
			(hide yes)
			(effects
				(font
					(size 1.27 1.27)
				)
			)
		)
		(property "Value" "100KR2F-L1-GP"
			(at 0.064008 -3.993896 0)
			(unlocked yes)
			(layer "F.Fab")
			(hide yes)
			(effects
				(font
					(size 1.016 1.016)
					(thickness 0.1524)
				)
			)
		)
		(property "Device Type" "R402H16"
			(at 0.064008 -5.517896 0)
			(unlocked yes)
			(layer "F.Fab")
			(hide yes)
			(effects
				(font
					(size 1.016 1.016)
					(thickness 0.1524)
				)
			)
		)
		(duplicate_pad_numbers_are_jumpers no)
		(fp_line
			(start -0.508 -0.9398)
			(end -0.508 0.9398)
			(stroke
				(width 0.1524)
				(type default)
			)
			(layer "F.SilkS")
		)
		(fp_line
			(start 0.508 -0.9398)
			(end -0.508 -0.9398)
			(stroke
				(width 0.1524)
				(type default)
			)
			(layer "F.SilkS")
		)
		(fp_rect
			(start -0.508 0.9398)
			(end 0.508 -0.9398)
			(stroke
				(width 0)
				(type default)
			)
			(fill no)
			(layer "F.CrtYd")
		)
		(fp_rect
			(start -0.508 0.9398)
			(end 0.508 -0.9398)
			(stroke
				(width 0)
				(type default)
			)
			(fill no)
			(layer "F.Fab")
		)
		(pad "1" smd custom
			(at 0 -0.4445)
			(size 0.1397 0.1397)
			(layers "F.Cu" "F.Mask" "F.Paste")
			(net "LPC_CPU_CLKOUT0")
			(options
				(clearance outline)
				(anchor circle)
			)
			(primitives
				(gr_poly
					(pts
						(arc
							(start -0.1778 -0.2794)
							(mid -0.249642 -0.249642)
							(end -0.2794 -0.1778)
						)
						(arc
							(start -0.2794 0.1778)
							(mid -0.249642 0.249642)
							(end -0.1778 0.2794)
						)
						(arc
							(start 0.1778 0.2794)
							(mid 0.249642 0.249642)
							(end 0.2794 0.1778)
						)
						(arc
							(start 0.2794 -0.1778)
							(mid 0.249642 -0.249642)
							(end 0.1778 -0.2794)
						)
					)
					(width 0)
					(fill yes)
				)
			)
		)
		(pad "2" smd custom
			(at 0 0.4445)
			(size 0.1397 0.1397)
			(layers "F.Cu" "F.Mask" "F.Paste")
			(net "GND")
			(options
				(clearance outline)
				(anchor circle)
			)
			(primitives
				(gr_poly
					(pts
						(arc
							(start -0.1778 -0.2794)
							(mid -0.249642 -0.249642)
							(end -0.2794 -0.1778)
						)
						(arc
							(start -0.2794 0.1778)
							(mid -0.249642 0.249642)
							(end -0.1778 0.2794)
						)
						(arc
							(start 0.1778 0.2794)
							(mid 0.249642 0.249642)
							(end 0.2794 0.1778)
						)
						(arc
							(start 0.2794 -0.1778)
							(mid 0.249642 -0.249642)
							(end 0.1778 -0.2794)
						)
					)
					(width 0)
					(fill yes)
				)
			)
		)
	)
	(footprint ""
		(layer "F.Cu")
		(at 55.1434 -132.1562)
		(property "Reference" "TP11"
			(at 0 0 0)
			(layer "F.SilkS")
			(hide yes)
			(effects
				(font
					(size 1.27 1.27)
				)
			)
		)
		(property "Value" "TPAD28-2-GP"
			(at -0.0127 -1.6637 0)
			(unlocked yes)
			(layer "F.Fab")
			(hide yes)
			(effects
				(font
					(size 1.016 1.016)
					(thickness 0.1524)
				)
			)
		)
		(property "Device Type" "TPAD28"
			(at -0.0127 -3.1877 0)
			(unlocked yes)
			(layer "F.Fab")
			(hide yes)
			(effects
				(font
					(size 1.016 1.016)
					(thickness 0.1524)
				)
			)
		)
		(duplicate_pad_numbers_are_jumpers no)
		(fp_poly
			(pts
				(arc
					(start 0.3556 0)
					(mid -0.3556 0)
					(end 0.3556 0)
				)
			)
			(stroke
				(width 0)
				(type default)
			)
			(fill no)
			(layer "F.CrtYd")
		)
		(fp_poly
			(pts
				(arc
					(start 0.6096 0)
					(mid -0.6096 0)
					(end 0.6096 0)
				)
			)
			(stroke
				(width 0)
				(type default)
			)
			(fill no)
			(layer "F.Fab")
		)
		(pad "1" smd circle
			(at 0 0)
			(size 0.7112 0.7112)
			(layers "F.Cu" "F.Mask" "F.Paste")
			(net "TP_BMC0_LPC_LAD2")
		)
	)
	(footprint ""
		(layer "F.Cu")
		(at 191.8462 -127.635 180)
		(property "Reference" "C281"
			(at 0 0 180)
			(layer "F.SilkS")
			(hide yes)
			(effects
				(font
					(size 1.27 1.27)
				)
			)
		)
		(property "Value" "SC220P50V2KX-3GP"
			(at 1.1811 -2.7051 180)
			(unlocked yes)
			(layer "F.Fab")
			(hide yes)
			(effects
				(font
					(size 1.016 1.016)
					(thickness 0.1524)
				)
			)
		)
		(property "Device Type" "C402H22"
			(at 1.1811 -4.2291 180)
			(unlocked yes)
			(layer "F.Fab")
			(hide yes)
			(effects
				(font
					(size 1.016 1.016)
					(thickness 0.1524)
				)
			)
		)
		(duplicate_pad_numbers_are_jumpers no)
		(fp_rect
			(start -0.4318 0.9525)
			(end 0.4318 -0.9525)
			(stroke
				(width 0)
				(type default)
			)
			(fill no)
			(layer "F.CrtYd")
		)
		(fp_rect
			(start -0.4318 0.9525)
			(end 0.4318 -0.9525)
			(stroke
				(width 0)
				(type default)
			)
			(fill no)
			(layer "F.Fab")
		)
		(pad "1" smd custom
			(at 0 -0.4445 180)
			(size 0.1524 0.1524)
			(layers "F.Cu" "F.Mask" "F.Paste")
			(net "VT235_PGIN")
			(options
				(clearance outline)
				(anchor circle)
			)
			(primitives
				(gr_poly
					(pts
						(arc
							(start 0.3048 -0.2032)
							(mid 0.275042 -0.275042)
							(end 0.2032 -0.3048)
						)
						(arc
							(start -0.2032 -0.3048)
							(mid -0.275042 -0.275042)
							(end -0.3048 -0.2032)
						)
						(arc
							(start -0.3048 0.2032)
							(mid -0.275042 0.275042)
							(end -0.2032 0.3048)
						)
						(arc
							(start 0.2032 0.3048)
							(mid 0.275042 0.275042)
							(end 0.3048 0.2032)
						)
					)
					(width 0)
					(fill yes)
				)
			)
		)
		(pad "2" smd custom
			(at 0 0.4445 180)
			(size 0.1524 0.1524)
			(layers "F.Cu" "F.Mask" "F.Paste")
			(net "VT235_VREF")
			(options
				(clearance outline)
				(anchor circle)
			)
			(primitives
				(gr_poly
					(pts
						(arc
							(start 0.3048 -0.2032)
							(mid 0.275042 -0.275042)
							(end 0.2032 -0.3048)
						)
						(arc
							(start -0.2032 -0.3048)
							(mid -0.275042 -0.275042)
							(end -0.3048 -0.2032)
						)
						(arc
							(start -0.3048 0.2032)
							(mid -0.275042 0.275042)
							(end -0.2032 0.3048)
						)
						(arc
							(start 0.2032 0.3048)
							(mid 0.275042 0.275042)
							(end 0.3048 0.2032)
						)
					)
					(width 0)
					(fill yes)
				)
			)
		)
	)
	(footprint ""
		(layer "F.Cu")
		(at 29.8958 -131.318)
		(property "Reference" "C79"
			(at 0 0 0)
			(layer "F.SilkS")
			(hide yes)
			(effects
				(font
					(size 1.27 1.27)
				)
			)
		)
		(property "Value" "SCD1U16V2KX-3GP"
			(at 1.1811 -2.7051 0)
			(unlocked yes)
			(layer "F.Fab")
			(hide yes)
			(effects
				(font
					(size 1.016 1.016)
					(thickness 0.1524)
				)
			)
		)
		(property "Device Type" "C402H22"
			(at 1.1811 -4.2291 0)
			(unlocked yes)
			(layer "F.Fab")
			(hide yes)
			(effects
				(font
					(size 1.016 1.016)
					(thickness 0.1524)
				)
			)
		)
		(duplicate_pad_numbers_are_jumpers no)
		(fp_rect
			(start -0.4318 0.9525)
			(end 0.4318 -0.9525)
			(stroke
				(width 0)
				(type default)
			)
			(fill no)
			(layer "F.CrtYd")
		)
		(fp_rect
			(start -0.4318 0.9525)
			(end 0.4318 -0.9525)
			(stroke
				(width 0)
				(type default)
			)
			(fill no)
			(layer "F.Fab")
		)
		(pad "1" smd custom
			(at 0 -0.4445)
			(size 0.1524 0.1524)
			(layers "F.Cu" "F.Mask" "F.Paste")
			(net "P3V3_STBY")
			(options
				(clearance outline)
				(anchor circle)
			)
			(primitives
				(gr_poly
					(pts
						(arc
							(start 0.3048 -0.2032)
							(mid 0.275042 -0.275042)
							(end 0.2032 -0.3048)
						)
						(arc
							(start -0.2032 -0.3048)
							(mid -0.275042 -0.275042)
							(end -0.3048 -0.2032)
						)
						(arc
							(start -0.3048 0.2032)
							(mid -0.275042 0.275042)
							(end -0.2032 0.3048)
						)
						(arc
							(start 0.2032 0.3048)
							(mid 0.275042 0.275042)
							(end 0.3048 0.2032)
						)
					)
					(width 0)
					(fill yes)
				)
			)
		)
		(pad "2" smd custom
			(at 0 0.4445)
			(size 0.1524 0.1524)
			(layers "F.Cu" "F.Mask" "F.Paste")
			(net "GND")
			(options
				(clearance outline)
				(anchor circle)
			)
			(primitives
				(gr_poly
					(pts
						(arc
							(start 0.3048 -0.2032)
							(mid 0.275042 -0.275042)
							(end 0.2032 -0.3048)
						)
						(arc
							(start -0.2032 -0.3048)
							(mid -0.275042 -0.275042)
							(end -0.3048 -0.2032)
						)
						(arc
							(start -0.3048 0.2032)
							(mid -0.275042 0.275042)
							(end -0.2032 0.3048)
						)
						(arc
							(start 0.2032 0.3048)
							(mid 0.275042 0.275042)
							(end 0.3048 0.2032)
						)
					)
					(width 0)
					(fill yes)
				)
			)
		)
	)
	(footprint ""
		(layer "F.Cu")
		(at 192.8368 -127.635)
		(property "Reference" "R554"
			(at 0 0 0)
			(layer "F.SilkS")
			(hide yes)
			(effects
				(font
					(size 1.27 1.27)
				)
			)
		)
		(property "Value" "19K1R2F-GP"
			(at 0.064008 -3.993896 0)
			(unlocked yes)
			(layer "F.Fab")
			(hide yes)
			(effects
				(font
					(size 1.016 1.016)
					(thickness 0.1524)
				)
			)
		)
		(property "Device Type" "R402H16"
			(at 0.064008 -5.517896 0)
			(unlocked yes)
			(layer "F.Fab")
			(hide yes)
			(effects
				(font
					(size 1.016 1.016)
					(thickness 0.1524)
				)
			)
		)
		(duplicate_pad_numbers_are_jumpers no)
		(fp_line
			(start -0.508 -0.9398)
			(end -0.508 0.9398)
			(stroke
				(width 0.1524)
				(type default)
			)
			(layer "F.SilkS")
		)
		(fp_line
			(start 0.508 -0.9398)
			(end -0.508 -0.9398)
			(stroke
				(width 0.1524)
				(type default)
			)
			(layer "F.SilkS")
		)
		(fp_rect
			(start -0.508 0.9398)
			(end 0.508 -0.9398)
			(stroke
				(width 0)
				(type default)
			)
			(fill no)
			(layer "F.CrtYd")
		)
		(fp_rect
			(start -0.508 0.9398)
			(end 0.508 -0.9398)
			(stroke
				(width 0)
				(type default)
			)
			(fill no)
			(layer "F.Fab")
		)
		(pad "1" smd custom
			(at 0 -0.4445)
			(size 0.1397 0.1397)
			(layers "F.Cu" "F.Mask" "F.Paste")
			(net "P0V975")
			(options
				(clearance outline)
				(anchor circle)
			)
			(primitives
				(gr_poly
					(pts
						(arc
							(start -0.1778 -0.2794)
							(mid -0.249642 -0.249642)
							(end -0.2794 -0.1778)
						)
						(arc
							(start -0.2794 0.1778)
							(mid -0.249642 0.249642)
							(end -0.1778 0.2794)
						)
						(arc
							(start 0.1778 0.2794)
							(mid 0.249642 0.249642)
							(end 0.2794 0.1778)
						)
						(arc
							(start 0.2794 -0.1778)
							(mid 0.249642 -0.249642)
							(end 0.1778 -0.2794)
						)
					)
					(width 0)
					(fill yes)
				)
			)
		)
		(pad "2" smd custom
			(at 0 0.4445)
			(size 0.1397 0.1397)
			(layers "F.Cu" "F.Mask" "F.Paste")
			(net "VT235_PGIN")
			(options
				(clearance outline)
				(anchor circle)
			)
			(primitives
				(gr_poly
					(pts
						(arc
							(start -0.1778 -0.2794)
							(mid -0.249642 -0.249642)
							(end -0.2794 -0.1778)
						)
						(arc
							(start -0.2794 0.1778)
							(mid -0.249642 0.249642)
							(end -0.1778 0.2794)
						)
						(arc
							(start 0.1778 0.2794)
							(mid 0.249642 0.249642)
							(end 0.2794 0.1778)
						)
						(arc
							(start 0.2794 -0.1778)
							(mid 0.249642 -0.249642)
							(end 0.1778 -0.2794)
						)
					)
					(width 0)
					(fill yes)
				)
			)
		)
	)
	(footprint ""
		(layer "F.Cu")
		(at 54.713124 -162.481768 180)
		(property "Reference" "C118"
			(at 0 0 180)
			(layer "F.SilkS")
			(hide yes)
			(effects
				(font
					(size 1.27 1.27)
				)
			)
		)
		(property "Value" "SCD1U25V2KX-2-GP"
			(at 1.1811 -2.7051 180)
			(unlocked yes)
			(layer "F.Fab")
			(hide yes)
			(effects
				(font
					(size 1.016 1.016)
					(thickness 0.1524)
				)
			)
		)
		(property "Device Type" "C402H22"
			(at 1.1811 -4.2291 180)
			(unlocked yes)
			(layer "F.Fab")
			(hide yes)
			(effects
				(font
					(size 1.016 1.016)
					(thickness 0.1524)
				)
			)
		)
		(duplicate_pad_numbers_are_jumpers no)
		(fp_rect
			(start -0.4318 0.9525)
			(end 0.4318 -0.9525)
			(stroke
				(width 0)
				(type default)
			)
			(fill no)
			(layer "F.CrtYd")
		)
		(fp_rect
			(start -0.4318 0.9525)
			(end 0.4318 -0.9525)
			(stroke
				(width 0)
				(type default)
			)
			(fill no)
			(layer "F.Fab")
		)
		(pad "1" smd custom
			(at 0 -0.4445 180)
			(size 0.1524 0.1524)
			(layers "F.Cu" "F.Mask" "F.Paste")
			(net "ADC_P1V8_STBY")
			(options
				(clearance outline)
				(anchor circle)
			)
			(primitives
				(gr_poly
					(pts
						(arc
							(start 0.3048 -0.2032)
							(mid 0.275042 -0.275042)
							(end 0.2032 -0.3048)
						)
						(arc
							(start -0.2032 -0.3048)
							(mid -0.275042 -0.275042)
							(end -0.3048 -0.2032)
						)
						(arc
							(start -0.3048 0.2032)
							(mid -0.275042 0.275042)
							(end -0.2032 0.3048)
						)
						(arc
							(start 0.2032 0.3048)
							(mid 0.275042 0.275042)
							(end 0.3048 0.2032)
						)
					)
					(width 0)
					(fill yes)
				)
			)
		)
		(pad "2" smd custom
			(at 0 0.4445 180)
			(size 0.1524 0.1524)
			(layers "F.Cu" "F.Mask" "F.Paste")
			(net "GND")
			(options
				(clearance outline)
				(anchor circle)
			)
			(primitives
				(gr_poly
					(pts
						(arc
							(start 0.3048 -0.2032)
							(mid 0.275042 -0.275042)
							(end 0.2032 -0.3048)
						)
						(arc
							(start -0.2032 -0.3048)
							(mid -0.275042 -0.275042)
							(end -0.3048 -0.2032)
						)
						(arc
							(start -0.3048 0.2032)
							(mid -0.275042 0.275042)
							(end -0.2032 0.3048)
						)
						(arc
							(start 0.2032 0.3048)
							(mid 0.275042 0.275042)
							(end 0.3048 0.2032)
						)
					)
					(width 0)
					(fill yes)
				)
			)
		)
	)
	(footprint ""
		(layer "F.Cu")
		(at 189.865 -127.6858 180)
		(property "Reference" "C287"
			(at 0 0 180)
			(layer "F.SilkS")
			(hide yes)
			(effects
				(font
					(size 1.27 1.27)
				)
			)
		)
		(property "Value" "SC1KP50V2KX-1GP"
			(at 1.1811 -2.7051 180)
			(unlocked yes)
			(layer "F.Fab")
			(hide yes)
			(effects
				(font
					(size 1.016 1.016)
					(thickness 0.1524)
				)
			)
		)
		(property "Device Type" "C402H22"
			(at 1.1811 -4.2291 180)
			(unlocked yes)
			(layer "F.Fab")
			(hide yes)
			(effects
				(font
					(size 1.016 1.016)
					(thickness 0.1524)
				)
			)
		)
		(duplicate_pad_numbers_are_jumpers no)
		(fp_rect
			(start -0.4318 0.9525)
			(end 0.4318 -0.9525)
			(stroke
				(width 0)
				(type default)
			)
			(fill no)
			(layer "F.CrtYd")
		)
		(fp_rect
			(start -0.4318 0.9525)
			(end 0.4318 -0.9525)
			(stroke
				(width 0)
				(type default)
			)
			(fill no)
			(layer "F.Fab")
		)
		(pad "1" smd custom
			(at 0 -0.4445 180)
			(size 0.1524 0.1524)
			(layers "F.Cu" "F.Mask" "F.Paste")
			(net "VT235_VREF")
			(options
				(clearance outline)
				(anchor circle)
			)
			(primitives
				(gr_poly
					(pts
						(arc
							(start 0.3048 -0.2032)
							(mid 0.275042 -0.275042)
							(end 0.2032 -0.3048)
						)
						(arc
							(start -0.2032 -0.3048)
							(mid -0.275042 -0.275042)
							(end -0.3048 -0.2032)
						)
						(arc
							(start -0.3048 0.2032)
							(mid -0.275042 0.275042)
							(end -0.2032 0.3048)
						)
						(arc
							(start 0.2032 0.3048)
							(mid 0.275042 0.275042)
							(end 0.3048 0.2032)
						)
					)
					(width 0)
					(fill yes)
				)
			)
		)
		(pad "2" smd custom
			(at 0 0.4445 180)
			(size 0.1524 0.1524)
			(layers "F.Cu" "F.Mask" "F.Paste")
			(net "VT235_VDES_RCC")
			(options
				(clearance outline)
				(anchor circle)
			)
			(primitives
				(gr_poly
					(pts
						(arc
							(start 0.3048 -0.2032)
							(mid 0.275042 -0.275042)
							(end 0.2032 -0.3048)
						)
						(arc
							(start -0.2032 -0.3048)
							(mid -0.275042 -0.275042)
							(end -0.3048 -0.2032)
						)
						(arc
							(start -0.3048 0.2032)
							(mid -0.275042 0.275042)
							(end -0.2032 0.3048)
						)
						(arc
							(start 0.2032 0.3048)
							(mid 0.275042 0.275042)
							(end 0.3048 0.2032)
						)
					)
					(width 0)
					(fill yes)
				)
			)
		)
	)
	(footprint ""
		(layer "F.Cu")
		(at 178.42484 -122.6439)
		(property "Reference" "C510"
			(at 0 0 0)
			(layer "F.SilkS")
			(hide yes)
			(effects
				(font
					(size 1.27 1.27)
				)
			)
		)
		(property "Value" "SCD1U16V2KX-3GP"
			(at 1.1811 -2.7051 0)
			(unlocked yes)
			(layer "F.Fab")
			(hide yes)
			(effects
				(font
					(size 1.016 1.016)
					(thickness 0.1524)
				)
			)
		)
		(property "Device Type" "C402H22"
			(at 1.1811 -4.2291 0)
			(unlocked yes)
			(layer "F.Fab")
			(hide yes)
			(effects
				(font
					(size 1.016 1.016)
					(thickness 0.1524)
				)
			)
		)
		(duplicate_pad_numbers_are_jumpers no)
		(fp_rect
			(start -0.4318 0.9525)
			(end 0.4318 -0.9525)
			(stroke
				(width 0)
				(type default)
			)
			(fill no)
			(layer "F.CrtYd")
		)
		(fp_rect
			(start -0.4318 0.9525)
			(end 0.4318 -0.9525)
			(stroke
				(width 0)
				(type default)
			)
			(fill no)
			(layer "F.Fab")
		)
		(pad "1" smd custom
			(at 0 -0.4445)
			(size 0.1524 0.1524)
			(layers "F.Cu" "F.Mask" "F.Paste")
			(net "P1V8_EN")
			(options
				(clearance outline)
				(anchor circle)
			)
			(primitives
				(gr_poly
					(pts
						(arc
							(start 0.3048 -0.2032)
							(mid 0.275042 -0.275042)
							(end 0.2032 -0.3048)
						)
						(arc
							(start -0.2032 -0.3048)
							(mid -0.275042 -0.275042)
							(end -0.3048 -0.2032)
						)
						(arc
							(start -0.3048 0.2032)
							(mid -0.275042 0.275042)
							(end -0.2032 0.3048)
						)
						(arc
							(start 0.2032 0.3048)
							(mid 0.275042 0.275042)
							(end 0.3048 0.2032)
						)
					)
					(width 0)
					(fill yes)
				)
			)
		)
		(pad "2" smd custom
			(at 0 0.4445)
			(size 0.1524 0.1524)
			(layers "F.Cu" "F.Mask" "F.Paste")
			(net "GND")
			(options
				(clearance outline)
				(anchor circle)
			)
			(primitives
				(gr_poly
					(pts
						(arc
							(start 0.3048 -0.2032)
							(mid 0.275042 -0.275042)
							(end 0.2032 -0.3048)
						)
						(arc
							(start -0.2032 -0.3048)
							(mid -0.275042 -0.275042)
							(end -0.3048 -0.2032)
						)
						(arc
							(start -0.3048 0.2032)
							(mid -0.275042 0.275042)
							(end -0.2032 0.3048)
						)
						(arc
							(start 0.2032 0.3048)
							(mid 0.275042 0.275042)
							(end 0.3048 0.2032)
						)
					)
					(width 0)
					(fill yes)
				)
			)
		)
	)
	(footprint ""
		(layer "F.Cu")
		(at 39.1922 -179.12461)
		(property "Reference" "R491"
			(at 0 0 0)
			(layer "F.SilkS")
			(hide yes)
			(effects
				(font
					(size 1.27 1.27)
				)
			)
		)
		(property "Value" "15KR2F-GP"
			(at 0.064008 -3.993896 0)
			(unlocked yes)
			(layer "F.Fab")
			(hide yes)
			(effects
				(font
					(size 1.016 1.016)
					(thickness 0.1524)
				)
			)
		)
		(property "Device Type" "R402H16"
			(at 0.064008 -5.517896 0)
			(unlocked yes)
			(layer "F.Fab")
			(hide yes)
			(effects
				(font
					(size 1.016 1.016)
					(thickness 0.1524)
				)
			)
		)
		(duplicate_pad_numbers_are_jumpers no)
		(fp_line
			(start -0.508 -0.9398)
			(end -0.508 0.9398)
			(stroke
				(width 0.1524)
				(type default)
			)
			(layer "F.SilkS")
		)
		(fp_line
			(start 0.508 -0.9398)
			(end -0.508 -0.9398)
			(stroke
				(width 0.1524)
				(type default)
			)
			(layer "F.SilkS")
		)
		(fp_rect
			(start -0.508 0.9398)
			(end 0.508 -0.9398)
			(stroke
				(width 0)
				(type default)
			)
			(fill no)
			(layer "F.CrtYd")
		)
		(fp_rect
			(start -0.508 0.9398)
			(end 0.508 -0.9398)
			(stroke
				(width 0)
				(type default)
			)
			(fill no)
			(layer "F.Fab")
		)
		(pad "1" smd custom
			(at 0 -0.4445)
			(size 0.1397 0.1397)
			(layers "F.Cu" "F.Mask" "F.Paste")
			(net "PWRGD_P3V3_STBY")
			(options
				(clearance outline)
				(anchor circle)
			)
			(primitives
				(gr_poly
					(pts
						(arc
							(start -0.1778 -0.2794)
							(mid -0.249642 -0.249642)
							(end -0.2794 -0.1778)
						)
						(arc
							(start -0.2794 0.1778)
							(mid -0.249642 0.249642)
							(end -0.1778 0.2794)
						)
						(arc
							(start 0.1778 0.2794)
							(mid 0.249642 0.249642)
							(end 0.2794 0.1778)
						)
						(arc
							(start 0.2794 -0.1778)
							(mid 0.249642 -0.249642)
							(end 0.1778 -0.2794)
						)
					)
					(width 0)
					(fill yes)
				)
			)
		)
		(pad "2" smd custom
			(at 0 0.4445)
			(size 0.1397 0.1397)
			(layers "F.Cu" "F.Mask" "F.Paste")
			(net "GND")
			(options
				(clearance outline)
				(anchor circle)
			)
			(primitives
				(gr_poly
					(pts
						(arc
							(start -0.1778 -0.2794)
							(mid -0.249642 -0.249642)
							(end -0.2794 -0.1778)
						)
						(arc
							(start -0.2794 0.1778)
							(mid -0.249642 0.249642)
							(end -0.1778 0.2794)
						)
						(arc
							(start 0.1778 0.2794)
							(mid 0.249642 0.249642)
							(end 0.2794 0.1778)
						)
						(arc
							(start 0.2794 -0.1778)
							(mid 0.249642 -0.249642)
							(end 0.1778 -0.2794)
						)
					)
					(width 0)
					(fill yes)
				)
			)
		)
	)
	(footprint ""
		(layer "F.Cu")
		(at 60.375546 -185.000138 -90)
		(property "Reference" "R480"
			(at 0 0 270)
			(layer "F.SilkS")
			(hide yes)
			(effects
				(font
					(size 1.27 1.27)
				)
			)
		)
		(property "Value" "0R6J-3-GP"
			(at -0.0508 -4.8514 270)
			(unlocked yes)
			(layer "F.Fab")
			(hide yes)
			(effects
				(font
					(size 1.016 1.016)
					(thickness 0.1524)
				)
			)
		)
		(property "Device Type" "R1206H28"
			(at 0 -6.3754 270)
			(unlocked yes)
			(layer "F.Fab")
			(hide yes)
			(effects
				(font
					(size 1.016 1.016)
					(thickness 0.1524)
				)
			)
		)
		(duplicate_pad_numbers_are_jumpers no)
		(fp_line
			(start -1.016 2.2352)
			(end -1.016 -2.2352)
			(stroke
				(width 0.1524)
				(type default)
			)
			(layer "F.SilkS")
		)
		(fp_line
			(start 1.016 2.2352)
			(end -1.016 2.2352)
			(stroke
				(width 0.1524)
				(type default)
			)
			(layer "F.SilkS")
		)
		(fp_line
			(start -1.016 -2.2352)
			(end 1.016 -2.2352)
			(stroke
				(width 0.1524)
				(type default)
			)
			(layer "F.SilkS")
		)
		(fp_line
			(start 1.016 -2.2352)
			(end 1.016 2.2352)
			(stroke
				(width 0.1524)
				(type default)
			)
			(layer "F.SilkS")
		)
		(fp_rect
			(start -1.0922 2.3114)
			(end 1.0922 -2.3114)
			(stroke
				(width 0)
				(type default)
			)
			(fill no)
			(layer "F.CrtYd")
		)
		(fp_poly
			(pts
				(xy -1.0922 -2.3114) (xy 1.0922 -2.3114) (xy 1.0922 2.3114) (xy -1.0922 2.3114)
			)
			(stroke
				(width 0)
				(type default)
			)
			(fill no)
			(layer "F.Fab")
		)
		(pad "1" smd rect
			(at 0 -1.397 270)
			(size 1.651 1.27)
			(layers "F.Cu" "F.Mask" "F.Paste")
			(net "P3V3_STBY")
		)
		(pad "2" smd rect
			(at 0 1.397 270)
			(size 1.651 1.27)
			(layers "F.Cu" "F.Mask" "F.Paste")
			(net "P3V3_STBY_OUT")
		)
	)
	(footprint ""
		(layer "F.Cu")
		(at 94.488 -29.464 90)
		(property "Reference" "C21"
			(at 0 0 90)
			(layer "F.SilkS")
			(hide yes)
			(effects
				(font
					(size 1.27 1.27)
				)
			)
		)
		(property "Value" "SC1U16V3KX-5GP"
			(at 0 -2.8194 90)
			(unlocked yes)
			(layer "F.Fab")
			(hide yes)
			(effects
				(font
					(size 1.016 1.016)
					(thickness 0.1524)
				)
			)
		)
		(property "Device Type" "C603H36"
			(at 0 -4.3434 90)
			(unlocked yes)
			(layer "F.Fab")
			(hide yes)
			(effects
				(font
					(size 1.016 1.016)
					(thickness 0.1524)
				)
			)
		)
		(duplicate_pad_numbers_are_jumpers no)
		(fp_line
			(start 0.508 0)
			(end -0.508 0)
			(stroke
				(width 0.2032)
				(type default)
			)
			(layer "F.SilkS")
		)
		(fp_rect
			(start -0.5842 1.3335)
			(end 0.5842 -1.3335)
			(stroke
				(width 0)
				(type default)
			)
			(fill no)
			(layer "F.CrtYd")
		)
		(fp_rect
			(start -0.5842 1.3335)
			(end 0.5842 -1.3335)
			(stroke
				(width 0)
				(type default)
			)
			(fill no)
			(layer "F.Fab")
		)
		(pad "1" smd custom
			(at 0 -0.762 90)
			(size 0.2159 0.2159)
			(layers "F.Cu" "F.Mask" "F.Paste")
			(net "P5V_USB")
			(options
				(clearance outline)
				(anchor circle)
			)
			(primitives
				(gr_poly
					(pts
						(arc
							(start -0.3302 -0.4318)
							(mid -0.402042 -0.402042)
							(end -0.4318 -0.3302)
						)
						(arc
							(start -0.4318 0.3302)
							(mid -0.402042 0.402042)
							(end -0.3302 0.4318)
						)
						(arc
							(start 0.3302 0.4318)
							(mid 0.402042 0.402042)
							(end 0.4318 0.3302)
						)
						(arc
							(start 0.4318 -0.3302)
							(mid 0.402042 -0.402042)
							(end 0.3302 -0.4318)
						)
					)
					(width 0)
					(fill yes)
				)
			)
		)
		(pad "2" smd custom
			(at 0 0.762 90)
			(size 0.2159 0.2159)
			(layers "F.Cu" "F.Mask" "F.Paste")
			(net "GND")
			(options
				(clearance outline)
				(anchor circle)
			)
			(primitives
				(gr_poly
					(pts
						(arc
							(start -0.3302 -0.4318)
							(mid -0.402042 -0.402042)
							(end -0.4318 -0.3302)
						)
						(arc
							(start -0.4318 0.3302)
							(mid -0.402042 0.402042)
							(end -0.3302 0.4318)
						)
						(arc
							(start 0.3302 0.4318)
							(mid 0.402042 0.402042)
							(end 0.4318 0.3302)
						)
						(arc
							(start 0.4318 -0.3302)
							(mid 0.402042 -0.402042)
							(end 0.3302 -0.4318)
						)
					)
					(width 0)
					(fill yes)
				)
			)
		)
	)
	(footprint ""
		(layer "F.Cu")
		(at 31.5976 -160.6042 90)
		(property "Reference" "R706"
			(at 0 0 90)
			(layer "F.SilkS")
			(hide yes)
			(effects
				(font
					(size 1.27 1.27)
				)
			)
		)
		(property "Value" "4K7R2F-GP"
			(at 0.064008 -3.993896 90)
			(unlocked yes)
			(layer "F.Fab")
			(hide yes)
			(effects
				(font
					(size 1.016 1.016)
					(thickness 0.1524)
				)
			)
		)
		(property "Device Type" "R402H16"
			(at 0.064008 -5.517896 90)
			(unlocked yes)
			(layer "F.Fab")
			(hide yes)
			(effects
				(font
					(size 1.016 1.016)
					(thickness 0.1524)
				)
			)
		)
		(duplicate_pad_numbers_are_jumpers no)
		(fp_line
			(start 0.508 -0.9398)
			(end -0.508 -0.9398)
			(stroke
				(width 0.1524)
				(type default)
			)
			(layer "F.SilkS")
		)
		(fp_line
			(start -0.508 -0.9398)
			(end -0.508 0.9398)
			(stroke
				(width 0.1524)
				(type default)
			)
			(layer "F.SilkS")
		)
		(fp_rect
			(start -0.508 0.9398)
			(end 0.508 -0.9398)
			(stroke
				(width 0)
				(type default)
			)
			(fill no)
			(layer "F.CrtYd")
		)
		(fp_rect
			(start -0.508 0.9398)
			(end 0.508 -0.9398)
			(stroke
				(width 0)
				(type default)
			)
			(fill no)
			(layer "F.Fab")
		)
		(pad "1" smd custom
			(at 0 -0.4445 90)
			(size 0.1397 0.1397)
			(layers "F.Cu" "F.Mask" "F.Paste")
			(net "GND")
			(options
				(clearance outline)
				(anchor circle)
			)
			(primitives
				(gr_poly
					(pts
						(arc
							(start -0.1778 -0.2794)
							(mid -0.249642 -0.249642)
							(end -0.2794 -0.1778)
						)
						(arc
							(start -0.2794 0.1778)
							(mid -0.249642 0.249642)
							(end -0.1778 0.2794)
						)
						(arc
							(start 0.1778 0.2794)
							(mid 0.249642 0.249642)
							(end 0.2794 0.1778)
						)
						(arc
							(start 0.2794 -0.1778)
							(mid 0.249642 -0.249642)
							(end 0.1778 -0.2794)
						)
					)
					(width 0)
					(fill yes)
				)
			)
		)
		(pad "2" smd custom
			(at 0 0.4445 90)
			(size 0.1397 0.1397)
			(layers "F.Cu" "F.Mask" "F.Paste")
			(net "IOM_TYPE3")
			(options
				(clearance outline)
				(anchor circle)
			)
			(primitives
				(gr_poly
					(pts
						(arc
							(start -0.1778 -0.2794)
							(mid -0.249642 -0.249642)
							(end -0.2794 -0.1778)
						)
						(arc
							(start -0.2794 0.1778)
							(mid -0.249642 0.249642)
							(end -0.1778 0.2794)
						)
						(arc
							(start 0.1778 0.2794)
							(mid 0.249642 0.249642)
							(end 0.2794 0.1778)
						)
						(arc
							(start 0.2794 -0.1778)
							(mid 0.249642 -0.249642)
							(end 0.1778 -0.2794)
						)
					)
					(width 0)
					(fill yes)
				)
			)
		)
	)
	(footprint ""
		(layer "F.Cu")
		(at 207.323436 -98.984308 -90)
		(property "Reference" "C323"
			(at 0 0 270)
			(layer "F.SilkS")
			(hide yes)
			(effects
				(font
					(size 1.27 1.27)
				)
			)
		)
		(property "Value" "SCD1U16V2KX-3GP"
			(at 1.1811 -2.7051 270)
			(unlocked yes)
			(layer "F.Fab")
			(hide yes)
			(effects
				(font
					(size 1.016 1.016)
					(thickness 0.1524)
				)
			)
		)
		(property "Device Type" "C402H22"
			(at 1.1811 -4.2291 270)
			(unlocked yes)
			(layer "F.Fab")
			(hide yes)
			(effects
				(font
					(size 1.016 1.016)
					(thickness 0.1524)
				)
			)
		)
		(duplicate_pad_numbers_are_jumpers no)
		(fp_rect
			(start -0.4318 0.9525)
			(end 0.4318 -0.9525)
			(stroke
				(width 0)
				(type default)
			)
			(fill no)
			(layer "F.CrtYd")
		)
		(fp_rect
			(start -0.4318 0.9525)
			(end 0.4318 -0.9525)
			(stroke
				(width 0)
				(type default)
			)
			(fill no)
			(layer "F.Fab")
		)
		(pad "1" smd custom
			(at 0 -0.4445 270)
			(size 0.1524 0.1524)
			(layers "F.Cu" "F.Mask" "F.Paste")
			(net "P1V8")
			(options
				(clearance outline)
				(anchor circle)
			)
			(primitives
				(gr_poly
					(pts
						(arc
							(start 0.3048 -0.2032)
							(mid 0.275042 -0.275042)
							(end 0.2032 -0.3048)
						)
						(arc
							(start -0.2032 -0.3048)
							(mid -0.275042 -0.275042)
							(end -0.3048 -0.2032)
						)
						(arc
							(start -0.3048 0.2032)
							(mid -0.275042 0.275042)
							(end -0.2032 0.3048)
						)
						(arc
							(start 0.2032 0.3048)
							(mid 0.275042 0.275042)
							(end 0.3048 0.2032)
						)
					)
					(width 0)
					(fill yes)
				)
			)
		)
		(pad "2" smd custom
			(at 0 0.4445 270)
			(size 0.1524 0.1524)
			(layers "F.Cu" "F.Mask" "F.Paste")
			(net "GND")
			(options
				(clearance outline)
				(anchor circle)
			)
			(primitives
				(gr_poly
					(pts
						(arc
							(start 0.3048 -0.2032)
							(mid 0.275042 -0.275042)
							(end 0.2032 -0.3048)
						)
						(arc
							(start -0.2032 -0.3048)
							(mid -0.275042 -0.275042)
							(end -0.3048 -0.2032)
						)
						(arc
							(start -0.3048 0.2032)
							(mid -0.275042 0.275042)
							(end -0.2032 0.3048)
						)
						(arc
							(start 0.2032 0.3048)
							(mid 0.275042 0.275042)
							(end 0.3048 0.2032)
						)
					)
					(width 0)
					(fill yes)
				)
			)
		)
	)
	(footprint ""
		(layer "F.Cu")
		(at 176.0982 -75.438)
		(property "Reference" "TP121"
			(at 0 0 0)
			(layer "F.SilkS")
			(hide yes)
			(effects
				(font
					(size 1.27 1.27)
				)
			)
		)
		(property "Value" "TPAD28-2-GP"
			(at -0.0127 -1.6637 0)
			(unlocked yes)
			(layer "F.Fab")
			(hide yes)
			(effects
				(font
					(size 1.016 1.016)
					(thickness 0.1524)
				)
			)
		)
		(property "Device Type" "TPAD28"
			(at -0.0127 -3.1877 0)
			(unlocked yes)
			(layer "F.Fab")
			(hide yes)
			(effects
				(font
					(size 1.016 1.016)
					(thickness 0.1524)
				)
			)
		)
		(duplicate_pad_numbers_are_jumpers no)
		(fp_poly
			(pts
				(arc
					(start 0.3556 0)
					(mid -0.3556 0)
					(end 0.3556 0)
				)
			)
			(stroke
				(width 0)
				(type default)
			)
			(fill no)
			(layer "F.CrtYd")
		)
		(fp_poly
			(pts
				(arc
					(start 0.6096 0)
					(mid -0.6096 0)
					(end 0.6096 0)
				)
			)
			(stroke
				(width 0)
				(type default)
			)
			(fill no)
			(layer "F.Fab")
		)
		(pad "1" smd circle
			(at 0 0)
			(size 0.7112 0.7112)
			(layers "F.Cu" "F.Mask" "F.Paste")
			(net "IOC_GPIO_31")
		)
	)
	(footprint ""
		(layer "F.Cu")
		(at 195.453 -19.177)
		(property "Reference" "U49"
			(at 0 0 0)
			(layer "F.SilkS")
			(hide yes)
			(effects
				(font
					(size 1.27 1.27)
				)
			)
		)
		(property "Value" "SN74LVC1G08DCKR-GP"
			(at -2.3368 -8.6868 0)
			(unlocked yes)
			(layer "F.Fab")
			(hide yes)
			(effects
				(font
					(size 1.016 1.016)
					(thickness 0.1524)
				)
			)
		)
		(property "Device Type" "SC70-5H44"
			(at -2.3114 -10.414 0)
			(unlocked yes)
			(layer "F.Fab")
			(hide yes)
			(effects
				(font
					(size 1.016 1.016)
					(thickness 0.1524)
				)
			)
		)
		(duplicate_pad_numbers_are_jumpers no)
		(fp_line
			(start -1.27 -1.7018)
			(end 1.27 -1.7018)
			(stroke
				(width 0.1524)
				(type default)
			)
			(layer "F.SilkS")
		)
		(fp_line
			(start -1.27 1.7018)
			(end -1.27 -1.7018)
			(stroke
				(width 0.1524)
				(type default)
			)
			(layer "F.SilkS")
		)
		(fp_line
			(start 0.6604 -1.8034)
			(end 1.3843 -1.8034)
			(stroke
				(width 0.3302)
				(type default)
			)
			(layer "F.SilkS")
		)
		(fp_line
			(start 1.27 -1.7018)
			(end 1.27 1.7018)
			(stroke
				(width 0.1524)
				(type default)
			)
			(layer "F.SilkS")
		)
		(fp_line
			(start 1.27 1.7018)
			(end -1.27 1.7018)
			(stroke
				(width 0.1524)
				(type default)
			)
			(layer "F.SilkS")
		)
		(fp_line
			(start 1.3843 -1.8034)
			(end 1.3843 -1.1176)
			(stroke
				(width 0.3302)
				(type default)
			)
			(layer "F.SilkS")
		)
		(fp_rect
			(start -1.524 1.9558)
			(end 1.524 -1.9558)
			(stroke
				(width 0)
				(type default)
			)
			(fill no)
			(layer "F.CrtYd")
		)
		(fp_poly
			(pts
				(xy -1.524 -1.9558) (xy 1.524 -1.9558) (xy 1.524 1.9558) (xy -1.524 1.9558)
			)
			(stroke
				(width 0)
				(type default)
			)
			(fill no)
			(layer "F.Fab")
		)
		(pad "1" smd rect
			(at 0.65024 -0.8255)
			(size 0.4064 1.2192)
			(layers "F.Cu" "F.Mask" "F.Paste")
			(net "BMC_EXT1_LED_Y")
		)
		(pad "2" smd rect
			(at 0 -0.8255)
			(size 0.4064 1.2192)
			(layers "F.Cu" "F.Mask" "F.Paste")
			(net "EXT1_LED_YELLOW_D")
		)
		(pad "3" smd rect
			(at -0.65024 -0.8255)
			(size 0.4064 1.2192)
			(layers "F.Cu" "F.Mask" "F.Paste")
			(net "GND")
		)
		(pad "4" smd rect
			(at -0.65024 0.8255)
			(size 0.4064 1.2192)
			(layers "F.Cu" "F.Mask" "F.Paste")
			(net "EXT1_LED_YELLOW_G1")
		)
		(pad "5" smd rect
			(at 0.65024 0.8255)
			(size 0.4064 1.2192)
			(layers "F.Cu" "F.Mask" "F.Paste")
			(net "P3V3_STBY")
		)
	)
	(footprint ""
		(layer "F.Cu")
		(at 42.9006 -161.3662)
		(property "Reference" "R313"
			(at 0 0 0)
			(layer "F.SilkS")
			(hide yes)
			(effects
				(font
					(size 1.27 1.27)
				)
			)
		)
		(property "Value" "4K7R2F-GP"
			(at 0.064008 -3.993896 0)
			(unlocked yes)
			(layer "F.Fab")
			(hide yes)
			(effects
				(font
					(size 1.016 1.016)
					(thickness 0.1524)
				)
			)
		)
		(property "Device Type" "R402H16"
			(at 0.064008 -5.517896 0)
			(unlocked yes)
			(layer "F.Fab")
			(hide yes)
			(effects
				(font
					(size 1.016 1.016)
					(thickness 0.1524)
				)
			)
		)
		(duplicate_pad_numbers_are_jumpers no)
		(fp_line
			(start -0.508 -0.9398)
			(end -0.508 0.9398)
			(stroke
				(width 0.1524)
				(type default)
			)
			(layer "F.SilkS")
		)
		(fp_line
			(start 0.508 -0.9398)
			(end -0.508 -0.9398)
			(stroke
				(width 0.1524)
				(type default)
			)
			(layer "F.SilkS")
		)
		(fp_rect
			(start -0.508 0.9398)
			(end 0.508 -0.9398)
			(stroke
				(width 0)
				(type default)
			)
			(fill no)
			(layer "F.CrtYd")
		)
		(fp_rect
			(start -0.508 0.9398)
			(end 0.508 -0.9398)
			(stroke
				(width 0)
				(type default)
			)
			(fill no)
			(layer "F.Fab")
		)
		(pad "1" smd custom
			(at 0 -0.4445)
			(size 0.1397 0.1397)
			(layers "F.Cu" "F.Mask" "F.Paste")
			(net "GND")
			(options
				(clearance outline)
				(anchor circle)
			)
			(primitives
				(gr_poly
					(pts
						(arc
							(start -0.1778 -0.2794)
							(mid -0.249642 -0.249642)
							(end -0.2794 -0.1778)
						)
						(arc
							(start -0.2794 0.1778)
							(mid -0.249642 0.249642)
							(end -0.1778 0.2794)
						)
						(arc
							(start 0.1778 0.2794)
							(mid 0.249642 0.249642)
							(end 0.2794 0.1778)
						)
						(arc
							(start 0.2794 -0.1778)
							(mid 0.249642 -0.249642)
							(end 0.1778 -0.2794)
						)
					)
					(width 0)
					(fill yes)
				)
			)
		)
		(pad "2" smd custom
			(at 0 0.4445)
			(size 0.1397 0.1397)
			(layers "F.Cu" "F.Mask" "F.Paste")
			(net "BOARD_REV_0")
			(options
				(clearance outline)
				(anchor circle)
			)
			(primitives
				(gr_poly
					(pts
						(arc
							(start -0.1778 -0.2794)
							(mid -0.249642 -0.249642)
							(end -0.2794 -0.1778)
						)
						(arc
							(start -0.2794 0.1778)
							(mid -0.249642 0.249642)
							(end -0.1778 0.2794)
						)
						(arc
							(start 0.1778 0.2794)
							(mid 0.249642 0.249642)
							(end 0.2794 0.1778)
						)
						(arc
							(start 0.2794 -0.1778)
							(mid 0.249642 -0.249642)
							(end 0.1778 -0.2794)
						)
					)
					(width 0)
					(fill yes)
				)
			)
		)
	)
	(footprint ""
		(layer "F.Cu")
		(at 39.839646 -180.64861 90)
		(property "Reference" "R498"
			(at 0 0 90)
			(layer "F.SilkS")
			(hide yes)
			(effects
				(font
					(size 1.27 1.27)
				)
			)
		)
		(property "Value" "0R2J-2-GP"
			(at 0.064008 -3.993896 90)
			(unlocked yes)
			(layer "F.Fab")
			(hide yes)
			(effects
				(font
					(size 1.016 1.016)
					(thickness 0.1524)
				)
			)
		)
		(property "Device Type" "R402H16"
			(at 0.064008 -5.517896 90)
			(unlocked yes)
			(layer "F.Fab")
			(hide yes)
			(effects
				(font
					(size 1.016 1.016)
					(thickness 0.1524)
				)
			)
		)
		(duplicate_pad_numbers_are_jumpers no)
		(fp_line
			(start 0.508 -0.9398)
			(end -0.508 -0.9398)
			(stroke
				(width 0.1524)
				(type default)
			)
			(layer "F.SilkS")
		)
		(fp_line
			(start -0.508 -0.9398)
			(end -0.508 0.9398)
			(stroke
				(width 0.1524)
				(type default)
			)
			(layer "F.SilkS")
		)
		(fp_rect
			(start -0.508 0.9398)
			(end 0.508 -0.9398)
			(stroke
				(width 0)
				(type default)
			)
			(fill no)
			(layer "F.CrtYd")
		)
		(fp_rect
			(start -0.508 0.9398)
			(end 0.508 -0.9398)
			(stroke
				(width 0)
				(type default)
			)
			(fill no)
			(layer "F.Fab")
		)
		(pad "1" smd custom
			(at 0 -0.4445 90)
			(size 0.1397 0.1397)
			(layers "F.Cu" "F.Mask" "F.Paste")
			(net "P3V3_STBY_ROVP")
			(options
				(clearance outline)
				(anchor circle)
			)
			(primitives
				(gr_poly
					(pts
						(arc
							(start -0.1778 -0.2794)
							(mid -0.249642 -0.249642)
							(end -0.2794 -0.1778)
						)
						(arc
							(start -0.2794 0.1778)
							(mid -0.249642 0.249642)
							(end -0.1778 0.2794)
						)
						(arc
							(start 0.1778 0.2794)
							(mid 0.249642 0.249642)
							(end 0.2794 0.1778)
						)
						(arc
							(start 0.2794 -0.1778)
							(mid 0.249642 -0.249642)
							(end 0.1778 -0.2794)
						)
					)
					(width 0)
					(fill yes)
				)
			)
		)
		(pad "2" smd custom
			(at 0 0.4445 90)
			(size 0.1397 0.1397)
			(layers "F.Cu" "F.Mask" "F.Paste")
			(net "AGND_P3V3_STBY")
			(options
				(clearance outline)
				(anchor circle)
			)
			(primitives
				(gr_poly
					(pts
						(arc
							(start -0.1778 -0.2794)
							(mid -0.249642 -0.249642)
							(end -0.2794 -0.1778)
						)
						(arc
							(start -0.2794 0.1778)
							(mid -0.249642 0.249642)
							(end -0.1778 0.2794)
						)
						(arc
							(start 0.1778 0.2794)
							(mid 0.249642 0.249642)
							(end 0.2794 0.1778)
						)
						(arc
							(start 0.2794 -0.1778)
							(mid 0.249642 -0.249642)
							(end 0.1778 -0.2794)
						)
					)
					(width 0)
					(fill yes)
				)
			)
		)
	)
	(footprint ""
		(layer "F.Cu")
		(at 168.6306 -108.1532 -90)
		(property "Reference" "C465"
			(at 0 0 270)
			(layer "F.SilkS")
			(hide yes)
			(effects
				(font
					(size 1.27 1.27)
				)
			)
		)
		(property "Value" "SC1U16V2KX-7-GP"
			(at 1.7526 -1.6002 270)
			(unlocked yes)
			(layer "F.Fab")
			(hide yes)
			(effects
				(font
					(size 1.016 1.016)
					(thickness 0.1524)
				)
			)
		)
		(property "Device Type" "C402-TO0D2H24"
			(at 1.7526 -3.1242 270)
			(unlocked yes)
			(layer "F.Fab")
			(hide yes)
			(effects
				(font
					(size 1.016 1.016)
					(thickness 0.1524)
				)
			)
		)
		(duplicate_pad_numbers_are_jumpers no)
		(fp_rect
			(start -0.4826 0.889)
			(end 0.4826 -0.889)
			(stroke
				(width 0)
				(type default)
			)
			(fill no)
			(layer "F.CrtYd")
		)
		(fp_rect
			(start -0.4826 0.889)
			(end 0.4826 -0.889)
			(stroke
				(width 0)
				(type default)
			)
			(fill no)
			(layer "F.Fab")
		)
		(pad "1" smd custom
			(at 0 -0.4572 270)
			(size 0.1524 0.1524)
			(layers "F.Cu" "F.Mask" "F.Paste")
			(net "P1V8")
			(options
				(clearance outline)
				(anchor circle)
			)
			(primitives
				(gr_poly
					(pts
						(arc
							(start -0.254 0.3048)
							(mid -0.325842 0.275042)
							(end -0.3556 0.2032)
						)
						(arc
							(start -0.3556 -0.2032)
							(mid -0.325842 -0.275042)
							(end -0.254 -0.3048)
						)
						(arc
							(start 0.254 -0.3048)
							(mid 0.325842 -0.275042)
							(end 0.3556 -0.2032)
						)
						(arc
							(start 0.3556 0.2032)
							(mid 0.325842 0.275042)
							(end 0.254 0.3048)
						)
					)
					(width 0)
					(fill yes)
				)
			)
		)
		(pad "2" smd custom
			(at 0 0.4572 270)
			(size 0.1524 0.1524)
			(layers "F.Cu" "F.Mask" "F.Paste")
			(net "GND")
			(options
				(clearance outline)
				(anchor circle)
			)
			(primitives
				(gr_poly
					(pts
						(arc
							(start -0.254 0.3048)
							(mid -0.325842 0.275042)
							(end -0.3556 0.2032)
						)
						(arc
							(start -0.3556 -0.2032)
							(mid -0.325842 -0.275042)
							(end -0.254 -0.3048)
						)
						(arc
							(start 0.254 -0.3048)
							(mid 0.325842 -0.275042)
							(end 0.3556 -0.2032)
						)
						(arc
							(start 0.3556 0.2032)
							(mid 0.325842 0.275042)
							(end 0.254 0.3048)
						)
					)
					(width 0)
					(fill yes)
				)
			)
		)
	)
	(footprint ""
		(layer "F.Cu")
		(at 78.122018 -90.155268 90)
		(property "Reference" "VIA7"
			(at 0 0 90)
			(layer "F.SilkS")
			(hide yes)
			(effects
				(font
					(size 1.27 1.27)
				)
			)
		)
		(property "Value" "85OHM-8L-1D6MM-L16L18-GP"
			(at 4.064 0.6096 90)
			(unlocked yes)
			(layer "F.Fab")
			(hide yes)
			(effects
				(font
					(size 1.016 1.016)
					(thickness 0.1524)
				)
			)
		)
		(property "Device Type" "VIA-PCIE-4P-368076"
			(at 4.064 -0.9144 90)
			(unlocked yes)
			(layer "F.Fab")
			(hide yes)
			(effects
				(font
					(size 1.016 1.016)
					(thickness 0.1524)
				)
			)
		)
		(duplicate_pad_numbers_are_jumpers no)
		(fp_rect
			(start -1.8415 0.381)
			(end 1.8415 -0.381)
			(stroke
				(width 0)
				(type default)
			)
			(fill no)
			(layer "F.CrtYd")
		)
		(fp_rect
			(start -1.8415 0.381)
			(end 1.8415 -0.381)
			(stroke
				(width 0)
				(type default)
			)
			(fill no)
			(layer "F.Fab")
		)
		(pad "1" thru_hole circle
			(at -1.4605 0 90)
			(size 0.508 0.508)
			(drill 0.254)
			(layers "*.Cu" "*.Mask")
			(remove_unused_layers no)
			(net "GND")
			(clearance 0.127)
			(thermal_gap 0.127)
		)
		(pad "2" thru_hole circle
			(at -0.4445 0 90)
			(size 0.508 0.508)
			(drill 0.254)
			(layers "*.Cu" "*.Mask")
			(remove_unused_layers no)
			(net "PCIE_COMP_TO_IOM_22_DP")
			(clearance 0.127)
			(thermal_gap 0.127)
		)
		(pad "3" thru_hole circle
			(at 0.4445 0 90)
			(size 0.508 0.508)
			(drill 0.254)
			(layers "*.Cu" "*.Mask")
			(remove_unused_layers no)
			(net "PCIE_COMP_TO_IOM_22_DN")
			(clearance 0.127)
			(thermal_gap 0.127)
		)
		(pad "4" thru_hole circle
			(at 1.4605 0 90)
			(size 0.508 0.508)
			(drill 0.254)
			(layers "*.Cu" "*.Mask")
			(remove_unused_layers no)
			(net "GND")
			(clearance 0.127)
			(thermal_gap 0.127)
		)
	)
	(footprint ""
		(layer "F.Cu")
		(at 128.917446 -10.732008 -90)
		(property "Reference" "R710"
			(at 0 0 270)
			(layer "F.SilkS")
			(hide yes)
			(effects
				(font
					(size 1.27 1.27)
				)
			)
		)
		(property "Value" "0R5J-5-GP"
			(at 0 -8.9535 270)
			(unlocked yes)
			(layer "F.Fab")
			(hide yes)
			(effects
				(font
					(size 1.27 1.016)
					(thickness 0.1524)
				)
			)
		)
		(property "Device Type" "R805H24"
			(at 0 -10.6299 270)
			(unlocked yes)
			(layer "F.Fab")
			(hide yes)
			(effects
				(font
					(size 1.27 1.016)
					(thickness 0.1524)
				)
			)
		)
		(duplicate_pad_numbers_are_jumpers no)
		(fp_line
			(start -0.889 1.7018)
			(end 0.889 1.7018)
			(stroke
				(width 0.1524)
				(type default)
			)
			(layer "F.SilkS")
		)
		(fp_line
			(start 0.889 1.7018)
			(end 0.889 -0.508)
			(stroke
				(width 0.1524)
				(type default)
			)
			(layer "F.SilkS")
		)
		(fp_line
			(start -0.889 0.0762)
			(end -0.889 1.7018)
			(stroke
				(width 0.1524)
				(type default)
			)
			(layer "F.SilkS")
		)
		(fp_line
			(start -0.889 -1.7018)
			(end -0.889 0.2794)
			(stroke
				(width 0.1524)
				(type default)
			)
			(layer "F.SilkS")
		)
		(fp_line
			(start 0.889 -1.7018)
			(end 0.889 -0.381)
			(stroke
				(width 0.1524)
				(type default)
			)
			(layer "F.SilkS")
		)
		(fp_line
			(start 0.889 -1.7018)
			(end -0.889 -1.7018)
			(stroke
				(width 0.1524)
				(type default)
			)
			(layer "F.SilkS")
		)
		(fp_poly
			(pts
				(xy 0.9652 -1.778) (xy 0.9652 1.778) (xy -0.9652 1.778) (xy -0.9652 -1.778)
			)
			(stroke
				(width 0)
				(type default)
			)
			(fill no)
			(layer "F.CrtYd")
		)
		(fp_rect
			(start -0.9652 1.778)
			(end 0.9652 -1.778)
			(stroke
				(width 0)
				(type default)
			)
			(fill no)
			(layer "F.Fab")
		)
		(pad "1" smd rect
			(at 0 -0.9652 270)
			(size 1.397 1.143)
			(layers "F.Cu" "F.Mask" "F.Paste")
			(net "MB0_CM_GATE_R")
		)
		(pad "2" smd rect
			(at 0 0.9652 270)
			(size 1.397 1.143)
			(layers "F.Cu" "F.Mask" "F.Paste")
			(net "MB0_CM_GATE")
		)
	)
	(footprint ""
		(layer "F.Cu")
		(at 172.9486 -136.2964 -90)
		(property "Reference" "C151"
			(at 0 0 270)
			(layer "F.SilkS")
			(hide yes)
			(effects
				(font
					(size 1.27 1.27)
				)
			)
		)
		(property "Value" "SC10U16V5KX-7-GP-U"
			(at -0.0762 -6.1214 270)
			(unlocked yes)
			(layer "F.Fab")
			(hide yes)
			(effects
				(font
					(size 1.016 1.016)
					(thickness 0.1524)
				)
			)
		)
		(property "Device Type" "C805H58"
			(at -0.0762 -8.1534 270)
			(unlocked yes)
			(layer "F.Fab")
			(hide yes)
			(effects
				(font
					(size 1.016 1.016)
					(thickness 0.1524)
				)
			)
		)
		(duplicate_pad_numbers_are_jumpers no)
		(fp_line
			(start 0.635 0)
			(end -0.635 0)
			(stroke
				(width 0.508)
				(type default)
			)
			(layer "F.SilkS")
		)
		(fp_rect
			(start -0.9652 1.778)
			(end 0.9652 -1.778)
			(stroke
				(width 0)
				(type default)
			)
			(fill no)
			(layer "F.CrtYd")
		)
		(fp_poly
			(pts
				(xy -0.9652 -1.778) (xy 0.9652 -1.778) (xy 0.9652 1.778) (xy -0.9652 1.778)
			)
			(stroke
				(width 0)
				(type default)
			)
			(fill no)
			(layer "F.Fab")
		)
		(pad "1" smd rect
			(at 0 -0.9652 270)
			(size 1.397 1.143)
			(layers "F.Cu" "F.Mask" "F.Paste")
			(net "P12V_STBY_VIN_PU1")
		)
		(pad "2" smd rect
			(at 0 0.9652 270)
			(size 1.397 1.143)
			(layers "F.Cu" "F.Mask" "F.Paste")
			(net "GND")
		)
	)
	(footprint ""
		(layer "F.Cu")
		(at 167.4368 -138.0998 180)
		(property "Reference" "R512"
			(at 0 0 180)
			(layer "F.SilkS")
			(hide yes)
			(effects
				(font
					(size 1.27 1.27)
				)
			)
		)
		(property "Value" "0R6J-3-GP"
			(at -0.0508 -4.8514 180)
			(unlocked yes)
			(layer "F.Fab")
			(hide yes)
			(effects
				(font
					(size 1.016 1.016)
					(thickness 0.1524)
				)
			)
		)
		(property "Device Type" "R1206H28"
			(at 0 -6.3754 180)
			(unlocked yes)
			(layer "F.Fab")
			(hide yes)
			(effects
				(font
					(size 1.016 1.016)
					(thickness 0.1524)
				)
			)
		)
		(duplicate_pad_numbers_are_jumpers no)
		(fp_line
			(start 1.016 2.2352)
			(end -1.016 2.2352)
			(stroke
				(width 0.1524)
				(type default)
			)
			(layer "F.SilkS")
		)
		(fp_line
			(start 1.016 -2.2352)
			(end 1.016 2.2352)
			(stroke
				(width 0.1524)
				(type default)
			)
			(layer "F.SilkS")
		)
		(fp_line
			(start -1.016 2.2352)
			(end -1.016 -2.2352)
			(stroke
				(width 0.1524)
				(type default)
			)
			(layer "F.SilkS")
		)
		(fp_line
			(start -1.016 -2.2352)
			(end 1.016 -2.2352)
			(stroke
				(width 0.1524)
				(type default)
			)
			(layer "F.SilkS")
		)
		(fp_rect
			(start -1.0922 2.3114)
			(end 1.0922 -2.3114)
			(stroke
				(width 0)
				(type default)
			)
			(fill no)
			(layer "F.CrtYd")
		)
		(fp_poly
			(pts
				(xy -1.0922 -2.3114) (xy 1.0922 -2.3114) (xy 1.0922 2.3114) (xy -1.0922 2.3114)
			)
			(stroke
				(width 0)
				(type default)
			)
			(fill no)
			(layer "F.Fab")
		)
		(pad "1" smd rect
			(at 0 -1.397 180)
			(size 1.651 1.27)
			(layers "F.Cu" "F.Mask" "F.Paste")
			(net "P12V_STBY_VIN_PU4")
		)
		(pad "2" smd rect
			(at 0 1.397 180)
			(size 1.651 1.27)
			(layers "F.Cu" "F.Mask" "F.Paste")
			(net "P12V_STBY")
		)
	)
	(footprint ""
		(layer "F.Cu")
		(at 74.426572 -173.774862 -90)
		(property "Reference" "R505"
			(at 0 0 270)
			(layer "F.SilkS")
			(hide yes)
			(effects
				(font
					(size 1.27 1.27)
				)
			)
		)
		(property "Value" "3K57R2F-GP"
			(at 0.064008 -3.993896 270)
			(unlocked yes)
			(layer "F.Fab")
			(hide yes)
			(effects
				(font
					(size 1.016 1.016)
					(thickness 0.1524)
				)
			)
		)
		(property "Device Type" "R402H16"
			(at 0.064008 -5.517896 270)
			(unlocked yes)
			(layer "F.Fab")
			(hide yes)
			(effects
				(font
					(size 1.016 1.016)
					(thickness 0.1524)
				)
			)
		)
		(duplicate_pad_numbers_are_jumpers no)
		(fp_line
			(start -0.508 -0.9398)
			(end -0.508 0.9398)
			(stroke
				(width 0.1524)
				(type default)
			)
			(layer "F.SilkS")
		)
		(fp_line
			(start 0.508 -0.9398)
			(end -0.508 -0.9398)
			(stroke
				(width 0.1524)
				(type default)
			)
			(layer "F.SilkS")
		)
		(fp_rect
			(start -0.508 0.9398)
			(end 0.508 -0.9398)
			(stroke
				(width 0)
				(type default)
			)
			(fill no)
			(layer "F.CrtYd")
		)
		(fp_rect
			(start -0.508 0.9398)
			(end 0.508 -0.9398)
			(stroke
				(width 0)
				(type default)
			)
			(fill no)
			(layer "F.Fab")
		)
		(pad "1" smd custom
			(at 0 -0.4445 270)
			(size 0.1397 0.1397)
			(layers "F.Cu" "F.Mask" "F.Paste")
			(net "TPS74801_P2V5_STBY_OUT")
			(options
				(clearance outline)
				(anchor circle)
			)
			(primitives
				(gr_poly
					(pts
						(arc
							(start -0.1778 -0.2794)
							(mid -0.249642 -0.249642)
							(end -0.2794 -0.1778)
						)
						(arc
							(start -0.2794 0.1778)
							(mid -0.249642 0.249642)
							(end -0.1778 0.2794)
						)
						(arc
							(start 0.1778 0.2794)
							(mid 0.249642 0.249642)
							(end 0.2794 0.1778)
						)
						(arc
							(start 0.2794 -0.1778)
							(mid 0.249642 -0.249642)
							(end 0.1778 -0.2794)
						)
					)
					(width 0)
					(fill yes)
				)
			)
		)
		(pad "2" smd custom
			(at 0 0.4445 270)
			(size 0.1397 0.1397)
			(layers "F.Cu" "F.Mask" "F.Paste")
			(net "TPS74801_P2V5_STBY_FB")
			(options
				(clearance outline)
				(anchor circle)
			)
			(primitives
				(gr_poly
					(pts
						(arc
							(start -0.1778 -0.2794)
							(mid -0.249642 -0.249642)
							(end -0.2794 -0.1778)
						)
						(arc
							(start -0.2794 0.1778)
							(mid -0.249642 0.249642)
							(end -0.1778 0.2794)
						)
						(arc
							(start 0.1778 0.2794)
							(mid 0.249642 0.249642)
							(end 0.2794 0.1778)
						)
						(arc
							(start 0.2794 -0.1778)
							(mid 0.249642 -0.249642)
							(end 0.1778 -0.2794)
						)
					)
					(width 0)
					(fill yes)
				)
			)
		)
	)
	(footprint ""
		(layer "F.Cu")
		(at 61.3664 -147.5994 -90)
		(property "Reference" "R164"
			(at 0 0 270)
			(layer "F.SilkS")
			(hide yes)
			(effects
				(font
					(size 1.27 1.27)
				)
			)
		)
		(property "Value" "0R2J-2-GP"
			(at 0.064008 -3.993896 270)
			(unlocked yes)
			(layer "F.Fab")
			(hide yes)
			(effects
				(font
					(size 1.016 1.016)
					(thickness 0.1524)
				)
			)
		)
		(property "Device Type" "R402H16"
			(at 0.064008 -5.517896 270)
			(unlocked yes)
			(layer "F.Fab")
			(hide yes)
			(effects
				(font
					(size 1.016 1.016)
					(thickness 0.1524)
				)
			)
		)
		(duplicate_pad_numbers_are_jumpers no)
		(fp_line
			(start -0.508 -0.9398)
			(end -0.508 0.9398)
			(stroke
				(width 0.1524)
				(type default)
			)
			(layer "F.SilkS")
		)
		(fp_line
			(start 0.508 -0.9398)
			(end -0.508 -0.9398)
			(stroke
				(width 0.1524)
				(type default)
			)
			(layer "F.SilkS")
		)
		(fp_rect
			(start -0.508 0.9398)
			(end 0.508 -0.9398)
			(stroke
				(width 0)
				(type default)
			)
			(fill no)
			(layer "F.CrtYd")
		)
		(fp_rect
			(start -0.508 0.9398)
			(end 0.508 -0.9398)
			(stroke
				(width 0)
				(type default)
			)
			(fill no)
			(layer "F.Fab")
		)
		(pad "1" smd custom
			(at 0 -0.4445 270)
			(size 0.1397 0.1397)
			(layers "F.Cu" "F.Mask" "F.Paste")
			(net "I2C_BMC_COMP_SCL_OUT")
			(options
				(clearance outline)
				(anchor circle)
			)
			(primitives
				(gr_poly
					(pts
						(arc
							(start -0.1778 -0.2794)
							(mid -0.249642 -0.249642)
							(end -0.2794 -0.1778)
						)
						(arc
							(start -0.2794 0.1778)
							(mid -0.249642 0.249642)
							(end -0.1778 0.2794)
						)
						(arc
							(start 0.1778 0.2794)
							(mid 0.249642 0.249642)
							(end 0.2794 0.1778)
						)
						(arc
							(start 0.2794 -0.1778)
							(mid 0.249642 -0.249642)
							(end 0.1778 -0.2794)
						)
					)
					(width 0)
					(fill yes)
				)
			)
		)
		(pad "2" smd custom
			(at 0 0.4445 270)
			(size 0.1397 0.1397)
			(layers "F.Cu" "F.Mask" "F.Paste")
			(net "BMC_SMB4_CLK")
			(options
				(clearance outline)
				(anchor circle)
			)
			(primitives
				(gr_poly
					(pts
						(arc
							(start -0.1778 -0.2794)
							(mid -0.249642 -0.249642)
							(end -0.2794 -0.1778)
						)
						(arc
							(start -0.2794 0.1778)
							(mid -0.249642 0.249642)
							(end -0.1778 0.2794)
						)
						(arc
							(start 0.1778 0.2794)
							(mid 0.249642 0.249642)
							(end 0.2794 0.1778)
						)
						(arc
							(start 0.2794 -0.1778)
							(mid 0.249642 -0.249642)
							(end 0.1778 -0.2794)
						)
					)
					(width 0)
					(fill yes)
				)
			)
		)
	)
	(footprint ""
		(layer "F.Cu")
		(at 37.9476 -158.623)
		(property "Reference" "R317"
			(at 0 0 0)
			(layer "F.SilkS")
			(hide yes)
			(effects
				(font
					(size 1.27 1.27)
				)
			)
		)
		(property "Value" "0R2J-2-GP"
			(at 0.064008 -3.993896 0)
			(unlocked yes)
			(layer "F.Fab")
			(hide yes)
			(effects
				(font
					(size 1.016 1.016)
					(thickness 0.1524)
				)
			)
		)
		(property "Device Type" "R402H16"
			(at 0.064008 -5.517896 0)
			(unlocked yes)
			(layer "F.Fab")
			(hide yes)
			(effects
				(font
					(size 1.016 1.016)
					(thickness 0.1524)
				)
			)
		)
		(duplicate_pad_numbers_are_jumpers no)
		(fp_line
			(start -0.508 -0.9398)
			(end -0.508 0.9398)
			(stroke
				(width 0.1524)
				(type default)
			)
			(layer "F.SilkS")
		)
		(fp_line
			(start 0.508 -0.9398)
			(end -0.508 -0.9398)
			(stroke
				(width 0.1524)
				(type default)
			)
			(layer "F.SilkS")
		)
		(fp_rect
			(start -0.508 0.9398)
			(end 0.508 -0.9398)
			(stroke
				(width 0)
				(type default)
			)
			(fill no)
			(layer "F.CrtYd")
		)
		(fp_rect
			(start -0.508 0.9398)
			(end 0.508 -0.9398)
			(stroke
				(width 0)
				(type default)
			)
			(fill no)
			(layer "F.Fab")
		)
		(pad "1" smd custom
			(at 0 -0.4445)
			(size 0.1397 0.1397)
			(layers "F.Cu" "F.Mask" "F.Paste")
			(net "PWM_OUT_ZONE_C")
			(options
				(clearance outline)
				(anchor circle)
			)
			(primitives
				(gr_poly
					(pts
						(arc
							(start -0.1778 -0.2794)
							(mid -0.249642 -0.249642)
							(end -0.2794 -0.1778)
						)
						(arc
							(start -0.2794 0.1778)
							(mid -0.249642 0.249642)
							(end -0.1778 0.2794)
						)
						(arc
							(start 0.1778 0.2794)
							(mid 0.249642 0.249642)
							(end 0.2794 0.1778)
						)
						(arc
							(start 0.2794 -0.1778)
							(mid 0.249642 -0.249642)
							(end 0.1778 -0.2794)
						)
					)
					(width 0)
					(fill yes)
				)
			)
		)
		(pad "2" smd custom
			(at 0 0.4445)
			(size 0.1397 0.1397)
			(layers "F.Cu" "F.Mask" "F.Paste")
			(net "FAN_PWM0_BMC")
			(options
				(clearance outline)
				(anchor circle)
			)
			(primitives
				(gr_poly
					(pts
						(arc
							(start -0.1778 -0.2794)
							(mid -0.249642 -0.249642)
							(end -0.2794 -0.1778)
						)
						(arc
							(start -0.2794 0.1778)
							(mid -0.249642 0.249642)
							(end -0.1778 0.2794)
						)
						(arc
							(start 0.1778 0.2794)
							(mid 0.249642 0.249642)
							(end 0.2794 0.1778)
						)
						(arc
							(start 0.2794 -0.1778)
							(mid 0.249642 -0.249642)
							(end 0.1778 -0.2794)
						)
					)
					(width 0)
					(fill yes)
				)
			)
		)
	)
	(footprint ""
		(layer "F.Cu")
		(at 77.151992 -157.601158 90)
		(property "Reference" "R538"
			(at 0 0 90)
			(layer "F.SilkS")
			(hide yes)
			(effects
				(font
					(size 1.27 1.27)
				)
			)
		)
		(property "Value" "4K64R2F-GP"
			(at 0.064008 -3.993896 90)
			(unlocked yes)
			(layer "F.Fab")
			(hide yes)
			(effects
				(font
					(size 1.016 1.016)
					(thickness 0.1524)
				)
			)
		)
		(property "Device Type" "R402H16"
			(at 0.064008 -5.517896 90)
			(unlocked yes)
			(layer "F.Fab")
			(hide yes)
			(effects
				(font
					(size 1.016 1.016)
					(thickness 0.1524)
				)
			)
		)
		(duplicate_pad_numbers_are_jumpers no)
		(fp_line
			(start 0.508 -0.9398)
			(end -0.508 -0.9398)
			(stroke
				(width 0.1524)
				(type default)
			)
			(layer "F.SilkS")
		)
		(fp_line
			(start -0.508 -0.9398)
			(end -0.508 0.9398)
			(stroke
				(width 0.1524)
				(type default)
			)
			(layer "F.SilkS")
		)
		(fp_rect
			(start -0.508 0.9398)
			(end 0.508 -0.9398)
			(stroke
				(width 0)
				(type default)
			)
			(fill no)
			(layer "F.CrtYd")
		)
		(fp_rect
			(start -0.508 0.9398)
			(end 0.508 -0.9398)
			(stroke
				(width 0)
				(type default)
			)
			(fill no)
			(layer "F.Fab")
		)
		(pad "1" smd custom
			(at 0 -0.4445 90)
			(size 0.1397 0.1397)
			(layers "F.Cu" "F.Mask" "F.Paste")
			(net "TPS74801_P1V15_STBY_FB")
			(options
				(clearance outline)
				(anchor circle)
			)
			(primitives
				(gr_poly
					(pts
						(arc
							(start -0.1778 -0.2794)
							(mid -0.249642 -0.249642)
							(end -0.2794 -0.1778)
						)
						(arc
							(start -0.2794 0.1778)
							(mid -0.249642 0.249642)
							(end -0.1778 0.2794)
						)
						(arc
							(start 0.1778 0.2794)
							(mid 0.249642 0.249642)
							(end 0.2794 0.1778)
						)
						(arc
							(start 0.2794 -0.1778)
							(mid 0.249642 -0.249642)
							(end 0.1778 -0.2794)
						)
					)
					(width 0)
					(fill yes)
				)
			)
		)
		(pad "2" smd custom
			(at 0 0.4445 90)
			(size 0.1397 0.1397)
			(layers "F.Cu" "F.Mask" "F.Paste")
			(net "GND")
			(options
				(clearance outline)
				(anchor circle)
			)
			(primitives
				(gr_poly
					(pts
						(arc
							(start -0.1778 -0.2794)
							(mid -0.249642 -0.249642)
							(end -0.2794 -0.1778)
						)
						(arc
							(start -0.2794 0.1778)
							(mid -0.249642 0.249642)
							(end -0.1778 0.2794)
						)
						(arc
							(start 0.1778 0.2794)
							(mid 0.249642 0.249642)
							(end 0.2794 0.1778)
						)
						(arc
							(start 0.2794 -0.1778)
							(mid 0.249642 -0.249642)
							(end 0.1778 -0.2794)
						)
					)
					(width 0)
					(fill yes)
				)
			)
		)
	)
	(footprint ""
		(layer "F.Cu")
		(at 59.5884 -161.9504 -90)
		(property "Reference" "R407"
			(at 0 0 270)
			(layer "F.SilkS")
			(hide yes)
			(effects
				(font
					(size 1.27 1.27)
				)
			)
		)
		(property "Value" "1K4R2F-1-GP"
			(at 0.064008 -3.993896 270)
			(unlocked yes)
			(layer "F.Fab")
			(hide yes)
			(effects
				(font
					(size 1.016 1.016)
					(thickness 0.1524)
				)
			)
		)
		(property "Device Type" "R402H16"
			(at 0.064008 -5.517896 270)
			(unlocked yes)
			(layer "F.Fab")
			(hide yes)
			(effects
				(font
					(size 1.016 1.016)
					(thickness 0.1524)
				)
			)
		)
		(duplicate_pad_numbers_are_jumpers no)
		(fp_line
			(start -0.508 -0.9398)
			(end -0.508 0.9398)
			(stroke
				(width 0.1524)
				(type default)
			)
			(layer "F.SilkS")
		)
		(fp_line
			(start 0.508 -0.9398)
			(end -0.508 -0.9398)
			(stroke
				(width 0.1524)
				(type default)
			)
			(layer "F.SilkS")
		)
		(fp_rect
			(start -0.508 0.9398)
			(end 0.508 -0.9398)
			(stroke
				(width 0)
				(type default)
			)
			(fill no)
			(layer "F.CrtYd")
		)
		(fp_rect
			(start -0.508 0.9398)
			(end 0.508 -0.9398)
			(stroke
				(width 0)
				(type default)
			)
			(fill no)
			(layer "F.Fab")
		)
		(pad "1" smd custom
			(at 0 -0.4445 270)
			(size 0.1397 0.1397)
			(layers "F.Cu" "F.Mask" "F.Paste")
			(net "P3V3_STBY")
			(options
				(clearance outline)
				(anchor circle)
			)
			(primitives
				(gr_poly
					(pts
						(arc
							(start -0.1778 -0.2794)
							(mid -0.249642 -0.249642)
							(end -0.2794 -0.1778)
						)
						(arc
							(start -0.2794 0.1778)
							(mid -0.249642 0.249642)
							(end -0.1778 0.2794)
						)
						(arc
							(start 0.1778 0.2794)
							(mid 0.249642 0.249642)
							(end 0.2794 0.1778)
						)
						(arc
							(start 0.2794 -0.1778)
							(mid 0.249642 -0.249642)
							(end 0.1778 -0.2794)
						)
					)
					(width 0)
					(fill yes)
				)
			)
		)
		(pad "2" smd custom
			(at 0 0.4445 270)
			(size 0.1397 0.1397)
			(layers "F.Cu" "F.Mask" "F.Paste")
			(net "ADC_P3V3_STBY")
			(options
				(clearance outline)
				(anchor circle)
			)
			(primitives
				(gr_poly
					(pts
						(arc
							(start -0.1778 -0.2794)
							(mid -0.249642 -0.249642)
							(end -0.2794 -0.1778)
						)
						(arc
							(start -0.2794 0.1778)
							(mid -0.249642 0.249642)
							(end -0.1778 0.2794)
						)
						(arc
							(start 0.1778 0.2794)
							(mid 0.249642 0.249642)
							(end 0.2794 0.1778)
						)
						(arc
							(start 0.2794 -0.1778)
							(mid 0.249642 -0.249642)
							(end 0.1778 -0.2794)
						)
					)
					(width 0)
					(fill yes)
				)
			)
		)
	)
	(footprint ""
		(layer "F.Cu")
		(at 180.6321 -45.5422)
		(property "Reference" "R673"
			(at 0 0 0)
			(layer "F.SilkS")
			(hide yes)
			(effects
				(font
					(size 1.27 1.27)
				)
			)
		)
		(property "Value" "10KR2F-2-GP"
			(at 0.064008 -3.993896 0)
			(unlocked yes)
			(layer "F.Fab")
			(hide yes)
			(effects
				(font
					(size 1.016 1.016)
					(thickness 0.1524)
				)
			)
		)
		(property "Device Type" "R402H16"
			(at 0.064008 -5.517896 0)
			(unlocked yes)
			(layer "F.Fab")
			(hide yes)
			(effects
				(font
					(size 1.016 1.016)
					(thickness 0.1524)
				)
			)
		)
		(duplicate_pad_numbers_are_jumpers no)
		(fp_line
			(start -0.508 -0.9398)
			(end -0.508 0.9398)
			(stroke
				(width 0.1524)
				(type default)
			)
			(layer "F.SilkS")
		)
		(fp_line
			(start 0.508 -0.9398)
			(end -0.508 -0.9398)
			(stroke
				(width 0.1524)
				(type default)
			)
			(layer "F.SilkS")
		)
		(fp_rect
			(start -0.508 0.9398)
			(end 0.508 -0.9398)
			(stroke
				(width 0)
				(type default)
			)
			(fill no)
			(layer "F.CrtYd")
		)
		(fp_rect
			(start -0.508 0.9398)
			(end 0.508 -0.9398)
			(stroke
				(width 0)
				(type default)
			)
			(fill no)
			(layer "F.Fab")
		)
		(pad "1" smd custom
			(at 0 -0.4445)
			(size 0.1397 0.1397)
			(layers "F.Cu" "F.Mask" "F.Paste")
			(net "XM_ADDR_8")
			(options
				(clearance outline)
				(anchor circle)
			)
			(primitives
				(gr_poly
					(pts
						(arc
							(start -0.1778 -0.2794)
							(mid -0.249642 -0.249642)
							(end -0.2794 -0.1778)
						)
						(arc
							(start -0.2794 0.1778)
							(mid -0.249642 0.249642)
							(end -0.1778 0.2794)
						)
						(arc
							(start 0.1778 0.2794)
							(mid 0.249642 0.249642)
							(end 0.2794 0.1778)
						)
						(arc
							(start 0.2794 -0.1778)
							(mid 0.249642 -0.249642)
							(end 0.1778 -0.2794)
						)
					)
					(width 0)
					(fill yes)
				)
			)
		)
		(pad "2" smd custom
			(at 0 0.4445)
			(size 0.1397 0.1397)
			(layers "F.Cu" "F.Mask" "F.Paste")
			(net "GND")
			(options
				(clearance outline)
				(anchor circle)
			)
			(primitives
				(gr_poly
					(pts
						(arc
							(start -0.1778 -0.2794)
							(mid -0.249642 -0.249642)
							(end -0.2794 -0.1778)
						)
						(arc
							(start -0.2794 0.1778)
							(mid -0.249642 0.249642)
							(end -0.1778 0.2794)
						)
						(arc
							(start 0.1778 0.2794)
							(mid 0.249642 0.249642)
							(end 0.2794 0.1778)
						)
						(arc
							(start 0.2794 -0.1778)
							(mid 0.249642 -0.249642)
							(end 0.1778 -0.2794)
						)
					)
					(width 0)
					(fill yes)
				)
			)
		)
	)
	(footprint ""
		(layer "F.Cu")
		(at 78.5622 -172.5422 180)
		(property "Reference" "R504"
			(at 0 0 180)
			(layer "F.SilkS")
			(hide yes)
			(effects
				(font
					(size 1.27 1.27)
				)
			)
		)
		(property "Value" "0R5J-5-GP"
			(at 0 -8.9535 180)
			(unlocked yes)
			(layer "F.Fab")
			(hide yes)
			(effects
				(font
					(size 1.27 1.016)
					(thickness 0.1524)
				)
			)
		)
		(property "Device Type" "R805H24"
			(at 0 -10.6299 180)
			(unlocked yes)
			(layer "F.Fab")
			(hide yes)
			(effects
				(font
					(size 1.27 1.016)
					(thickness 0.1524)
				)
			)
		)
		(duplicate_pad_numbers_are_jumpers no)
		(fp_line
			(start 0.889 1.7018)
			(end 0.889 -0.508)
			(stroke
				(width 0.1524)
				(type default)
			)
			(layer "F.SilkS")
		)
		(fp_line
			(start 0.889 -1.7018)
			(end 0.889 -0.381)
			(stroke
				(width 0.1524)
				(type default)
			)
			(layer "F.SilkS")
		)
		(fp_line
			(start 0.889 -1.7018)
			(end -0.889 -1.7018)
			(stroke
				(width 0.1524)
				(type default)
			)
			(layer "F.SilkS")
		)
		(fp_line
			(start -0.889 1.7018)
			(end 0.889 1.7018)
			(stroke
				(width 0.1524)
				(type default)
			)
			(layer "F.SilkS")
		)
		(fp_line
			(start -0.889 0.0762)
			(end -0.889 1.7018)
			(stroke
				(width 0.1524)
				(type default)
			)
			(layer "F.SilkS")
		)
		(fp_line
			(start -0.889 -1.7018)
			(end -0.889 0.2794)
			(stroke
				(width 0.1524)
				(type default)
			)
			(layer "F.SilkS")
		)
		(fp_poly
			(pts
				(xy 0.9652 -1.778) (xy 0.9652 1.778) (xy -0.9652 1.778) (xy -0.9652 -1.778)
			)
			(stroke
				(width 0)
				(type default)
			)
			(fill no)
			(layer "F.CrtYd")
		)
		(fp_rect
			(start -0.9652 1.778)
			(end 0.9652 -1.778)
			(stroke
				(width 0)
				(type default)
			)
			(fill no)
			(layer "F.Fab")
		)
		(pad "1" smd rect
			(at 0 -0.9652 180)
			(size 1.397 1.143)
			(layers "F.Cu" "F.Mask" "F.Paste")
			(net "P2V5_STBY")
		)
		(pad "2" smd rect
			(at 0 0.9652 180)
			(size 1.397 1.143)
			(layers "F.Cu" "F.Mask" "F.Paste")
			(net "TPS74801_P2V5_STBY_OUT")
		)
	)
	(footprint ""
		(layer "F.Cu")
		(at 75.48245 -136.335516)
		(property "Reference" "R54"
			(at 0 0 0)
			(layer "F.SilkS")
			(hide yes)
			(effects
				(font
					(size 1.27 1.27)
				)
			)
		)
		(property "Value" "0R2J-2-GP"
			(at 0.064008 -3.993896 0)
			(unlocked yes)
			(layer "F.Fab")
			(hide yes)
			(effects
				(font
					(size 1.016 1.016)
					(thickness 0.1524)
				)
			)
		)
		(property "Device Type" "R402H16"
			(at 0.064008 -5.517896 0)
			(unlocked yes)
			(layer "F.Fab")
			(hide yes)
			(effects
				(font
					(size 1.016 1.016)
					(thickness 0.1524)
				)
			)
		)
		(duplicate_pad_numbers_are_jumpers no)
		(fp_line
			(start -0.508 -0.9398)
			(end -0.508 0.9398)
			(stroke
				(width 0.1524)
				(type default)
			)
			(layer "F.SilkS")
		)
		(fp_line
			(start 0.508 -0.9398)
			(end -0.508 -0.9398)
			(stroke
				(width 0.1524)
				(type default)
			)
			(layer "F.SilkS")
		)
		(fp_rect
			(start -0.508 0.9398)
			(end 0.508 -0.9398)
			(stroke
				(width 0)
				(type default)
			)
			(fill no)
			(layer "F.CrtYd")
		)
		(fp_rect
			(start -0.508 0.9398)
			(end 0.508 -0.9398)
			(stroke
				(width 0)
				(type default)
			)
			(fill no)
			(layer "F.Fab")
		)
		(pad "1" smd custom
			(at 0 -0.4445)
			(size 0.1397 0.1397)
			(layers "F.Cu" "F.Mask" "F.Paste")
			(net "D_FLIP_D")
			(options
				(clearance outline)
				(anchor circle)
			)
			(primitives
				(gr_poly
					(pts
						(arc
							(start -0.1778 -0.2794)
							(mid -0.249642 -0.249642)
							(end -0.2794 -0.1778)
						)
						(arc
							(start -0.2794 0.1778)
							(mid -0.249642 0.249642)
							(end -0.1778 0.2794)
						)
						(arc
							(start 0.1778 0.2794)
							(mid 0.249642 0.249642)
							(end 0.2794 0.1778)
						)
						(arc
							(start 0.2794 -0.1778)
							(mid 0.249642 -0.249642)
							(end 0.1778 -0.2794)
						)
					)
					(width 0)
					(fill yes)
				)
			)
		)
		(pad "2" smd custom
			(at 0 0.4445)
			(size 0.1397 0.1397)
			(layers "F.Cu" "F.Mask" "F.Paste")
			(net "D_FLIP_Q#")
			(options
				(clearance outline)
				(anchor circle)
			)
			(primitives
				(gr_poly
					(pts
						(arc
							(start -0.1778 -0.2794)
							(mid -0.249642 -0.249642)
							(end -0.2794 -0.1778)
						)
						(arc
							(start -0.2794 0.1778)
							(mid -0.249642 0.249642)
							(end -0.1778 0.2794)
						)
						(arc
							(start 0.1778 0.2794)
							(mid 0.249642 0.249642)
							(end 0.2794 0.1778)
						)
						(arc
							(start 0.2794 -0.1778)
							(mid 0.249642 -0.249642)
							(end 0.1778 -0.2794)
						)
					)
					(width 0)
					(fill yes)
				)
			)
		)
	)
	(footprint ""
		(layer "F.Cu")
		(at 8.8392 -139.573 90)
		(property "Reference" "R217"
			(at 0 0 90)
			(layer "F.SilkS")
			(hide yes)
			(effects
				(font
					(size 1.27 1.27)
				)
			)
		)
		(property "Value" "120R2F-GP"
			(at 0.064008 -3.993896 90)
			(unlocked yes)
			(layer "F.Fab")
			(hide yes)
			(effects
				(font
					(size 1.016 1.016)
					(thickness 0.1524)
				)
			)
		)
		(property "Device Type" "R402H16"
			(at 0.064008 -5.517896 90)
			(unlocked yes)
			(layer "F.Fab")
			(hide yes)
			(effects
				(font
					(size 1.016 1.016)
					(thickness 0.1524)
				)
			)
		)
		(duplicate_pad_numbers_are_jumpers no)
		(fp_line
			(start 0.508 -0.9398)
			(end -0.508 -0.9398)
			(stroke
				(width 0.1524)
				(type default)
			)
			(layer "F.SilkS")
		)
		(fp_line
			(start -0.508 -0.9398)
			(end -0.508 0.9398)
			(stroke
				(width 0.1524)
				(type default)
			)
			(layer "F.SilkS")
		)
		(fp_rect
			(start -0.508 0.9398)
			(end 0.508 -0.9398)
			(stroke
				(width 0)
				(type default)
			)
			(fill no)
			(layer "F.CrtYd")
		)
		(fp_rect
			(start -0.508 0.9398)
			(end 0.508 -0.9398)
			(stroke
				(width 0)
				(type default)
			)
			(fill no)
			(layer "F.Fab")
		)
		(pad "1" smd custom
			(at 0 -0.4445 90)
			(size 0.1397 0.1397)
			(layers "F.Cu" "F.Mask" "F.Paste")
			(net "GND")
			(options
				(clearance outline)
				(anchor circle)
			)
			(primitives
				(gr_poly
					(pts
						(arc
							(start -0.1778 -0.2794)
							(mid -0.249642 -0.249642)
							(end -0.2794 -0.1778)
						)
						(arc
							(start -0.2794 0.1778)
							(mid -0.249642 0.249642)
							(end -0.1778 0.2794)
						)
						(arc
							(start 0.1778 0.2794)
							(mid 0.249642 0.249642)
							(end 0.2794 0.1778)
						)
						(arc
							(start 0.2794 -0.1778)
							(mid 0.249642 -0.249642)
							(end 0.1778 -0.2794)
						)
					)
					(width 0)
					(fill yes)
				)
			)
		)
		(pad "2" smd custom
			(at 0 0.4445 90)
			(size 0.1397 0.1397)
			(layers "F.Cu" "F.Mask" "F.Paste")
			(net "MEMBG_0")
			(options
				(clearance outline)
				(anchor circle)
			)
			(primitives
				(gr_poly
					(pts
						(arc
							(start -0.1778 -0.2794)
							(mid -0.249642 -0.249642)
							(end -0.2794 -0.1778)
						)
						(arc
							(start -0.2794 0.1778)
							(mid -0.249642 0.249642)
							(end -0.1778 0.2794)
						)
						(arc
							(start 0.1778 0.2794)
							(mid 0.249642 0.249642)
							(end 0.2794 0.1778)
						)
						(arc
							(start 0.2794 -0.1778)
							(mid 0.249642 -0.249642)
							(end 0.1778 -0.2794)
						)
					)
					(width 0)
					(fill yes)
				)
			)
		)
	)
	(footprint ""
		(layer "F.Cu")
		(at 37.299646 -173.66361 90)
		(property "Reference" "R496"
			(at 0 0 90)
			(layer "F.SilkS")
			(hide yes)
			(effects
				(font
					(size 1.27 1.27)
				)
			)
		)
		(property "Value" "44K2R2F-1-GP"
			(at 0.064008 -3.993896 90)
			(unlocked yes)
			(layer "F.Fab")
			(hide yes)
			(effects
				(font
					(size 1.016 1.016)
					(thickness 0.1524)
				)
			)
		)
		(property "Device Type" "R402H16"
			(at 0.064008 -5.517896 90)
			(unlocked yes)
			(layer "F.Fab")
			(hide yes)
			(effects
				(font
					(size 1.016 1.016)
					(thickness 0.1524)
				)
			)
		)
		(duplicate_pad_numbers_are_jumpers no)
		(fp_line
			(start 0.508 -0.9398)
			(end -0.508 -0.9398)
			(stroke
				(width 0.1524)
				(type default)
			)
			(layer "F.SilkS")
		)
		(fp_line
			(start -0.508 -0.9398)
			(end -0.508 0.9398)
			(stroke
				(width 0.1524)
				(type default)
			)
			(layer "F.SilkS")
		)
		(fp_rect
			(start -0.508 0.9398)
			(end 0.508 -0.9398)
			(stroke
				(width 0)
				(type default)
			)
			(fill no)
			(layer "F.CrtYd")
		)
		(fp_rect
			(start -0.508 0.9398)
			(end 0.508 -0.9398)
			(stroke
				(width 0)
				(type default)
			)
			(fill no)
			(layer "F.Fab")
		)
		(pad "1" smd custom
			(at 0 -0.4445 90)
			(size 0.1397 0.1397)
			(layers "F.Cu" "F.Mask" "F.Paste")
			(net "P3V3_STBY_VFB")
			(options
				(clearance outline)
				(anchor circle)
			)
			(primitives
				(gr_poly
					(pts
						(arc
							(start -0.1778 -0.2794)
							(mid -0.249642 -0.249642)
							(end -0.2794 -0.1778)
						)
						(arc
							(start -0.2794 0.1778)
							(mid -0.249642 0.249642)
							(end -0.1778 0.2794)
						)
						(arc
							(start 0.1778 0.2794)
							(mid 0.249642 0.249642)
							(end 0.2794 0.1778)
						)
						(arc
							(start 0.2794 -0.1778)
							(mid 0.249642 -0.249642)
							(end 0.1778 -0.2794)
						)
					)
					(width 0)
					(fill yes)
				)
			)
		)
		(pad "2" smd custom
			(at 0 0.4445 90)
			(size 0.1397 0.1397)
			(layers "F.Cu" "F.Mask" "F.Paste")
			(net "P3V3_STBY_VFB_R")
			(options
				(clearance outline)
				(anchor circle)
			)
			(primitives
				(gr_poly
					(pts
						(arc
							(start -0.1778 -0.2794)
							(mid -0.249642 -0.249642)
							(end -0.2794 -0.1778)
						)
						(arc
							(start -0.2794 0.1778)
							(mid -0.249642 0.249642)
							(end -0.1778 0.2794)
						)
						(arc
							(start 0.1778 0.2794)
							(mid 0.249642 0.249642)
							(end 0.2794 0.1778)
						)
						(arc
							(start 0.2794 -0.1778)
							(mid 0.249642 -0.249642)
							(end 0.1778 -0.2794)
						)
					)
					(width 0)
					(fill yes)
				)
			)
		)
	)
	(footprint ""
		(layer "F.Cu")
		(at 214.122 -72.39 -45)
		(property "Reference" "VIA44"
			(at 0 0 315)
			(layer "F.SilkS")
			(hide yes)
			(effects
				(font
					(size 1.27 1.27)
				)
			)
		)
		(property "Value" "100OHM-8L-1D6MM-L18L16-GP"
			(at -3.721059 -4.508373 315)
			(unlocked yes)
			(layer "F.Fab")
			(hide yes)
			(effects
				(font
					(size 1.016 1.016)
					(thickness 0.1524)
				)
			)
		)
		(property "Device Type" "VIA-PCIE-4P-394076"
			(at -3.721059 -6.032502 315)
			(unlocked yes)
			(layer "F.Fab")
			(hide yes)
			(effects
				(font
					(size 1.016 1.016)
					(thickness 0.1524)
				)
			)
		)
		(duplicate_pad_numbers_are_jumpers no)
		(fp_poly
			(pts
				(xy -1.968472 -0.380877) (xy 1.968528 -0.380878) (xy 1.968527 0.381122) (xy -1.968472 0.381122)
			)
			(stroke
				(width 0)
				(type default)
			)
			(fill no)
			(layer "F.CrtYd")
		)
		(fp_poly
			(pts
				(xy -1.968472 -0.380877) (xy 1.968528 -0.380878) (xy 1.968527 0.381122) (xy -1.968472 0.381122)
			)
			(stroke
				(width 0)
				(type default)
			)
			(fill no)
			(layer "F.Fab")
		)
		(pad "1" thru_hole circle
			(at -1.5875 0 315)
			(size 0.508 0.508)
			(drill 0.254)
			(layers "*.Cu" "*.Mask")
			(remove_unused_layers no)
			(net "GND")
			(clearance 0.127)
			(thermal_gap 0.127)
		)
		(pad "2" thru_hole circle
			(at -0.571501 0 315)
			(size 0.508 0.508)
			(drill 0.254)
			(layers "*.Cu" "*.Mask")
			(remove_unused_layers no)
			(net "PHY_IOC_TO_CON_A_3_DP")
			(clearance 0.127)
			(thermal_gap 0.127)
		)
		(pad "3" thru_hole circle
			(at 0.571501 0 315)
			(size 0.508 0.508)
			(drill 0.254)
			(layers "*.Cu" "*.Mask")
			(remove_unused_layers no)
			(net "PHY_IOC_TO_CON_A_3_DN")
			(clearance 0.127)
			(thermal_gap 0.127)
		)
		(pad "4" thru_hole circle
			(at 1.5875 0 315)
			(size 0.508 0.508)
			(drill 0.254)
			(layers "*.Cu" "*.Mask")
			(remove_unused_layers no)
			(net "GND")
			(clearance 0.127)
			(thermal_gap 0.127)
		)
	)
	(footprint ""
		(layer "F.Cu")
		(at 194.437 -122.8852 90)
		(property "Reference" "C282"
			(at 0 0 90)
			(layer "F.SilkS")
			(hide yes)
			(effects
				(font
					(size 1.27 1.27)
				)
			)
		)
		(property "Value" "SC1U25V3KX-GP"
			(at 0 -2.8194 90)
			(unlocked yes)
			(layer "F.Fab")
			(hide yes)
			(effects
				(font
					(size 1.016 1.016)
					(thickness 0.1524)
				)
			)
		)
		(property "Device Type" "C603H36"
			(at 0 -4.3434 90)
			(unlocked yes)
			(layer "F.Fab")
			(hide yes)
			(effects
				(font
					(size 1.016 1.016)
					(thickness 0.1524)
				)
			)
		)
		(duplicate_pad_numbers_are_jumpers no)
		(fp_line
			(start 0.508 0)
			(end -0.508 0)
			(stroke
				(width 0.2032)
				(type default)
			)
			(layer "F.SilkS")
		)
		(fp_rect
			(start -0.5842 1.3335)
			(end 0.5842 -1.3335)
			(stroke
				(width 0)
				(type default)
			)
			(fill no)
			(layer "F.CrtYd")
		)
		(fp_rect
			(start -0.5842 1.3335)
			(end 0.5842 -1.3335)
			(stroke
				(width 0)
				(type default)
			)
			(fill no)
			(layer "F.Fab")
		)
		(pad "1" smd custom
			(at 0 -0.762 90)
			(size 0.2159 0.2159)
			(layers "F.Cu" "F.Mask" "F.Paste")
			(net "VT235_VDDL")
			(options
				(clearance outline)
				(anchor circle)
			)
			(primitives
				(gr_poly
					(pts
						(arc
							(start -0.3302 -0.4318)
							(mid -0.402042 -0.402042)
							(end -0.4318 -0.3302)
						)
						(arc
							(start -0.4318 0.3302)
							(mid -0.402042 0.402042)
							(end -0.3302 0.4318)
						)
						(arc
							(start 0.3302 0.4318)
							(mid 0.402042 0.402042)
							(end 0.4318 0.3302)
						)
						(arc
							(start 0.4318 -0.3302)
							(mid 0.402042 -0.402042)
							(end 0.3302 -0.4318)
						)
					)
					(width 0)
					(fill yes)
				)
			)
		)
		(pad "2" smd custom
			(at 0 0.762 90)
			(size 0.2159 0.2159)
			(layers "F.Cu" "F.Mask" "F.Paste")
			(net "GND")
			(options
				(clearance outline)
				(anchor circle)
			)
			(primitives
				(gr_poly
					(pts
						(arc
							(start -0.3302 -0.4318)
							(mid -0.402042 -0.402042)
							(end -0.4318 -0.3302)
						)
						(arc
							(start -0.4318 0.3302)
							(mid -0.402042 0.402042)
							(end -0.3302 0.4318)
						)
						(arc
							(start 0.3302 0.4318)
							(mid 0.402042 0.402042)
							(end 0.4318 0.3302)
						)
						(arc
							(start 0.4318 -0.3302)
							(mid 0.402042 -0.402042)
							(end 0.3302 -0.4318)
						)
					)
					(width 0)
					(fill yes)
				)
			)
		)
	)
	(footprint ""
		(layer "F.Cu")
		(at 211.464144 -63.520574 -45)
		(property "Reference" "VIA48"
			(at 0 0 315)
			(layer "F.SilkS")
			(hide yes)
			(effects
				(font
					(size 1.27 1.27)
				)
			)
		)
		(property "Value" "100OHM-8L-1D6MM-L18L16-GP"
			(at -3.721059 -4.508373 315)
			(unlocked yes)
			(layer "F.Fab")
			(hide yes)
			(effects
				(font
					(size 1.016 1.016)
					(thickness 0.1524)
				)
			)
		)
		(property "Device Type" "VIA-PCIE-4P-394076"
			(at -3.721239 -6.032322 315)
			(unlocked yes)
			(layer "F.Fab")
			(hide yes)
			(effects
				(font
					(size 1.016 1.016)
					(thickness 0.1524)
				)
			)
		)
		(duplicate_pad_numbers_are_jumpers no)
		(fp_poly
			(pts
				(xy -1.968472 -0.380877) (xy 1.968528 -0.380878) (xy 1.968527 0.381122) (xy -1.968472 0.381122)
			)
			(stroke
				(width 0)
				(type default)
			)
			(fill no)
			(layer "F.CrtYd")
		)
		(fp_poly
			(pts
				(xy -1.968472 -0.380877) (xy 1.968528 -0.380878) (xy 1.968527 0.381122) (xy -1.968472 0.381122)
			)
			(stroke
				(width 0)
				(type default)
			)
			(fill no)
			(layer "F.Fab")
		)
		(pad "1" thru_hole circle
			(at -1.5875 0 315)
			(size 0.508 0.508)
			(drill 0.254)
			(layers "*.Cu" "*.Mask")
			(remove_unused_layers no)
			(net "GND")
			(clearance 0.127)
			(thermal_gap 0.127)
		)
		(pad "2" thru_hole circle
			(at -0.571501 0 315)
			(size 0.508 0.508)
			(drill 0.254)
			(layers "*.Cu" "*.Mask")
			(remove_unused_layers no)
			(net "PHY_IOC_TO_CON_B_3_DP")
			(clearance 0.127)
			(thermal_gap 0.127)
		)
		(pad "3" thru_hole circle
			(at 0.571501 0 315)
			(size 0.508 0.508)
			(drill 0.254)
			(layers "*.Cu" "*.Mask")
			(remove_unused_layers no)
			(net "PHY_IOC_TO_CON_B_3_DN")
			(clearance 0.127)
			(thermal_gap 0.127)
		)
		(pad "4" thru_hole circle
			(at 1.5875 0 315)
			(size 0.508 0.508)
			(drill 0.254)
			(layers "*.Cu" "*.Mask")
			(remove_unused_layers no)
			(net "GND")
			(clearance 0.127)
			(thermal_gap 0.127)
		)
	)
	(footprint ""
		(layer "F.Cu")
		(at 82.296 -149.733 90)
		(property "Reference" "U102"
			(at 0 0 90)
			(layer "F.SilkS")
			(hide yes)
			(effects
				(font
					(size 1.27 1.27)
				)
			)
		)
		(property "Value" "SN74LVC1G14DCKR-GP"
			(at -2.3368 -8.6868 90)
			(unlocked yes)
			(layer "F.Fab")
			(hide yes)
			(effects
				(font
					(size 1.016 1.016)
					(thickness 0.1524)
				)
			)
		)
		(property "Device Type" "SC70-5H44"
			(at -2.3114 -10.414 90)
			(unlocked yes)
			(layer "F.Fab")
			(hide yes)
			(effects
				(font
					(size 1.016 1.016)
					(thickness 0.1524)
				)
			)
		)
		(duplicate_pad_numbers_are_jumpers no)
		(fp_line
			(start 1.3843 -1.8034)
			(end 1.3843 -1.1176)
			(stroke
				(width 0.3302)
				(type default)
			)
			(layer "F.SilkS")
		)
		(fp_line
			(start 0.6604 -1.8034)
			(end 1.3843 -1.8034)
			(stroke
				(width 0.3302)
				(type default)
			)
			(layer "F.SilkS")
		)
		(fp_line
			(start 1.27 -1.7018)
			(end 1.27 1.7018)
			(stroke
				(width 0.1524)
				(type default)
			)
			(layer "F.SilkS")
		)
		(fp_line
			(start -1.27 -1.7018)
			(end 1.27 -1.7018)
			(stroke
				(width 0.1524)
				(type default)
			)
			(layer "F.SilkS")
		)
		(fp_line
			(start 1.27 1.7018)
			(end -1.27 1.7018)
			(stroke
				(width 0.1524)
				(type default)
			)
			(layer "F.SilkS")
		)
		(fp_line
			(start -1.27 1.7018)
			(end -1.27 -1.7018)
			(stroke
				(width 0.1524)
				(type default)
			)
			(layer "F.SilkS")
		)
		(fp_rect
			(start -1.524 1.9558)
			(end 1.524 -1.9558)
			(stroke
				(width 0)
				(type default)
			)
			(fill no)
			(layer "F.CrtYd")
		)
		(fp_poly
			(pts
				(xy -1.524 -1.9558) (xy 1.524 -1.9558) (xy 1.524 1.9558) (xy -1.524 1.9558)
			)
			(stroke
				(width 0)
				(type default)
			)
			(fill no)
			(layer "F.Fab")
		)
		(pad "1" smd rect
			(at 0.65024 -0.8255 90)
			(size 0.4064 1.2192)
			(layers "F.Cu" "F.Mask" "F.Paste")
			(net "Net_23")
		)
		(pad "2" smd rect
			(at 0 -0.8255 90)
			(size 0.4064 1.2192)
			(layers "F.Cu" "F.Mask" "F.Paste")
			(net "COMP_TO_BMC_RESET_R")
		)
		(pad "3" smd rect
			(at -0.65024 -0.8255 90)
			(size 0.4064 1.2192)
			(layers "F.Cu" "F.Mask" "F.Paste")
			(net "GND")
		)
		(pad "4" smd rect
			(at -0.65024 0.8255 90)
			(size 0.4064 1.2192)
			(layers "F.Cu" "F.Mask" "F.Paste")
			(net "COMP_TO_BMC_RESET_N_OUT")
		)
		(pad "5" smd rect
			(at 0.65024 0.8255 90)
			(size 0.4064 1.2192)
			(layers "F.Cu" "F.Mask" "F.Paste")
			(net "P3V3_STBY")
		)
	)
	(footprint ""
		(layer "F.Cu")
		(at 18.05686 -14.6812 180)
		(property "Reference" "C528"
			(at 0 0 180)
			(layer "F.SilkS")
			(hide yes)
			(effects
				(font
					(size 1.27 1.27)
				)
			)
		)
		(property "Value" "SC1000P2KV6KX-GP-U"
			(at 0.0508 -3.5052 180)
			(unlocked yes)
			(layer "F.Fab")
			(hide yes)
			(effects
				(font
					(size 1.016 1.016)
					(thickness 0.1524)
				)
			)
		)
		(property "Device Type" "C1206H58"
			(at 0.0508 -5.0292 180)
			(unlocked yes)
			(layer "F.Fab")
			(hide yes)
			(effects
				(font
					(size 1.016 1.016)
					(thickness 0.1524)
				)
			)
		)
		(duplicate_pad_numbers_are_jumpers no)
		(fp_line
			(start 1.016 2.2352)
			(end -1.016 2.2352)
			(stroke
				(width 0.1524)
				(type default)
			)
			(layer "F.SilkS")
		)
		(fp_line
			(start 1.016 0.8382)
			(end 1.016 2.2352)
			(stroke
				(width 0.1524)
				(type default)
			)
			(layer "F.SilkS")
		)
		(fp_line
			(start 1.016 -2.2352)
			(end 1.016 -0.8382)
			(stroke
				(width 0.1524)
				(type default)
			)
			(layer "F.SilkS")
		)
		(fp_line
			(start 1.016 -2.2352)
			(end -1.016 -2.2352)
			(stroke
				(width 0.1524)
				(type default)
			)
			(layer "F.SilkS")
		)
		(fp_line
			(start -1.016 2.2352)
			(end -1.016 0.8128)
			(stroke
				(width 0.1524)
				(type default)
			)
			(layer "F.SilkS")
		)
		(fp_line
			(start -1.016 -2.2352)
			(end -1.016 -0.8382)
			(stroke
				(width 0.1524)
				(type default)
			)
			(layer "F.SilkS")
		)
		(fp_rect
			(start -1.0922 2.3114)
			(end 1.0922 -2.3114)
			(stroke
				(width 0)
				(type default)
			)
			(fill no)
			(layer "F.CrtYd")
		)
		(fp_poly
			(pts
				(xy -1.0922 -2.3114) (xy 1.0922 -2.3114) (xy 1.0922 2.3114) (xy -1.0922 2.3114)
			)
			(stroke
				(width 0)
				(type default)
			)
			(fill no)
			(layer "F.Fab")
		)
		(pad "1" smd rect
			(at 0 -1.397 180)
			(size 1.651 1.27)
			(layers "F.Cu" "F.Mask" "F.Paste")
			(net "PWR_BTN_GND")
		)
		(pad "2" smd rect
			(at 0 1.397 180)
			(size 1.651 1.27)
			(layers "F.Cu" "F.Mask" "F.Paste")
			(net "GND")
		)
	)
	(footprint ""
		(layer "F.Cu")
		(at 194.85229 -105.784142)
		(property "Reference" "C266"
			(at 0 0 0)
			(layer "F.SilkS")
			(hide yes)
			(effects
				(font
					(size 1.27 1.27)
				)
			)
		)
		(property "Value" "SC22U6D3V6KX-2-GP"
			(at -0.0762 -5.1308 0)
			(unlocked yes)
			(layer "F.Fab")
			(hide yes)
			(effects
				(font
					(size 1.016 1.016)
					(thickness 0.1524)
				)
			)
		)
		(property "Device Type" "C1206H71"
			(at -0.127 -6.6548 0)
			(unlocked yes)
			(layer "F.Fab")
			(hide yes)
			(effects
				(font
					(size 1.016 1.016)
					(thickness 0.1524)
				)
			)
		)
		(duplicate_pad_numbers_are_jumpers no)
		(fp_line
			(start -1.016 -2.2352)
			(end 1.016 -2.2352)
			(stroke
				(width 0.1524)
				(type default)
			)
			(layer "F.SilkS")
		)
		(fp_line
			(start -1.016 -0.8382)
			(end -1.016 -2.2352)
			(stroke
				(width 0.1524)
				(type default)
			)
			(layer "F.SilkS")
		)
		(fp_line
			(start -1.016 2.2352)
			(end -1.016 0.8382)
			(stroke
				(width 0.1524)
				(type default)
			)
			(layer "F.SilkS")
		)
		(fp_line
			(start 1.016 -2.2352)
			(end 1.016 -0.8382)
			(stroke
				(width 0.1524)
				(type default)
			)
			(layer "F.SilkS")
		)
		(fp_line
			(start 1.016 0.8382)
			(end 1.016 2.2352)
			(stroke
				(width 0.1524)
				(type default)
			)
			(layer "F.SilkS")
		)
		(fp_line
			(start 1.016 2.2352)
			(end -1.016 2.2352)
			(stroke
				(width 0.1524)
				(type default)
			)
			(layer "F.SilkS")
		)
		(fp_rect
			(start -1.0922 2.3114)
			(end 1.0922 -2.3114)
			(stroke
				(width 0)
				(type default)
			)
			(fill no)
			(layer "F.CrtYd")
		)
		(fp_poly
			(pts
				(xy 1.0922 -2.3114) (xy 1.0922 2.3114) (xy -1.0922 2.3114) (xy -1.0922 -2.3114)
			)
			(stroke
				(width 0)
				(type default)
			)
			(fill no)
			(layer "F.Fab")
		)
		(pad "1" smd rect
			(at 0 -1.397)
			(size 1.651 1.27)
			(layers "F.Cu" "F.Mask" "F.Paste")
			(net "P0V975")
		)
		(pad "2" smd rect
			(at 0 1.397)
			(size 1.651 1.27)
			(layers "F.Cu" "F.Mask" "F.Paste")
			(net "GND")
		)
	)
	(footprint ""
		(layer "F.Cu")
		(at 11.04392 -12.9413 180)
		(property "Reference" "C31"
			(at 0 0 180)
			(layer "F.SilkS")
			(hide yes)
			(effects
				(font
					(size 1.27 1.27)
				)
			)
		)
		(property "Value" "SC1U16V3KX-5GP"
			(at 0 -2.8194 180)
			(unlocked yes)
			(layer "F.Fab")
			(hide yes)
			(effects
				(font
					(size 1.016 1.016)
					(thickness 0.1524)
				)
			)
		)
		(property "Device Type" "C603H36"
			(at 0 -4.3434 180)
			(unlocked yes)
			(layer "F.Fab")
			(hide yes)
			(effects
				(font
					(size 1.016 1.016)
					(thickness 0.1524)
				)
			)
		)
		(duplicate_pad_numbers_are_jumpers no)
		(fp_line
			(start 0.508 0)
			(end -0.508 0)
			(stroke
				(width 0.2032)
				(type default)
			)
			(layer "F.SilkS")
		)
		(fp_rect
			(start -0.5842 1.3335)
			(end 0.5842 -1.3335)
			(stroke
				(width 0)
				(type default)
			)
			(fill no)
			(layer "F.CrtYd")
		)
		(fp_rect
			(start -0.5842 1.3335)
			(end 0.5842 -1.3335)
			(stroke
				(width 0)
				(type default)
			)
			(fill no)
			(layer "F.Fab")
		)
		(pad "1" smd custom
			(at 0 -0.762 180)
			(size 0.2159 0.2159)
			(layers "F.Cu" "F.Mask" "F.Paste")
			(net "SYS_RST_BTN_IN_N")
			(options
				(clearance outline)
				(anchor circle)
			)
			(primitives
				(gr_poly
					(pts
						(arc
							(start -0.3302 -0.4318)
							(mid -0.402042 -0.402042)
							(end -0.4318 -0.3302)
						)
						(arc
							(start -0.4318 0.3302)
							(mid -0.402042 0.402042)
							(end -0.3302 0.4318)
						)
						(arc
							(start 0.3302 0.4318)
							(mid 0.402042 0.402042)
							(end 0.4318 0.3302)
						)
						(arc
							(start 0.4318 -0.3302)
							(mid 0.402042 -0.402042)
							(end 0.3302 -0.4318)
						)
					)
					(width 0)
					(fill yes)
				)
			)
		)
		(pad "2" smd custom
			(at 0 0.762 180)
			(size 0.2159 0.2159)
			(layers "F.Cu" "F.Mask" "F.Paste")
			(net "GND")
			(options
				(clearance outline)
				(anchor circle)
			)
			(primitives
				(gr_poly
					(pts
						(arc
							(start -0.3302 -0.4318)
							(mid -0.402042 -0.402042)
							(end -0.4318 -0.3302)
						)
						(arc
							(start -0.4318 0.3302)
							(mid -0.402042 0.402042)
							(end -0.3302 0.4318)
						)
						(arc
							(start 0.3302 0.4318)
							(mid 0.402042 0.402042)
							(end 0.4318 0.3302)
						)
						(arc
							(start 0.4318 -0.3302)
							(mid 0.402042 -0.402042)
							(end 0.3302 -0.4318)
						)
					)
					(width 0)
					(fill yes)
				)
			)
		)
	)
	(footprint ""
		(layer "F.Cu")
		(at 142.494 -20.828 -90)
		(property "Reference" "R735"
			(at 0 0 270)
			(layer "F.SilkS")
			(hide yes)
			(effects
				(font
					(size 1.27 1.27)
				)
			)
		)
		(property "Value" "1KR2F-3-GP"
			(at 0.064008 -3.993896 270)
			(unlocked yes)
			(layer "F.Fab")
			(hide yes)
			(effects
				(font
					(size 1.016 1.016)
					(thickness 0.1524)
				)
			)
		)
		(property "Device Type" "R402H16"
			(at 0.064008 -5.517896 270)
			(unlocked yes)
			(layer "F.Fab")
			(hide yes)
			(effects
				(font
					(size 1.016 1.016)
					(thickness 0.1524)
				)
			)
		)
		(duplicate_pad_numbers_are_jumpers no)
		(fp_line
			(start -0.508 -0.9398)
			(end -0.508 0.9398)
			(stroke
				(width 0.1524)
				(type default)
			)
			(layer "F.SilkS")
		)
		(fp_line
			(start 0.508 -0.9398)
			(end -0.508 -0.9398)
			(stroke
				(width 0.1524)
				(type default)
			)
			(layer "F.SilkS")
		)
		(fp_rect
			(start -0.508 0.9398)
			(end 0.508 -0.9398)
			(stroke
				(width 0)
				(type default)
			)
			(fill no)
			(layer "F.CrtYd")
		)
		(fp_rect
			(start -0.508 0.9398)
			(end 0.508 -0.9398)
			(stroke
				(width 0)
				(type default)
			)
			(fill no)
			(layer "F.Fab")
		)
		(pad "1" smd custom
			(at 0 -0.4445 270)
			(size 0.1397 0.1397)
			(layers "F.Cu" "F.Mask" "F.Paste")
			(net "P3V3_STBY")
			(options
				(clearance outline)
				(anchor circle)
			)
			(primitives
				(gr_poly
					(pts
						(arc
							(start -0.1778 -0.2794)
							(mid -0.249642 -0.249642)
							(end -0.2794 -0.1778)
						)
						(arc
							(start -0.2794 0.1778)
							(mid -0.249642 0.249642)
							(end -0.1778 0.2794)
						)
						(arc
							(start 0.1778 0.2794)
							(mid 0.249642 0.249642)
							(end 0.2794 0.1778)
						)
						(arc
							(start 0.2794 -0.1778)
							(mid 0.249642 -0.249642)
							(end 0.1778 -0.2794)
						)
					)
					(width 0)
					(fill yes)
				)
			)
		)
		(pad "2" smd custom
			(at 0 0.4445 270)
			(size 0.1397 0.1397)
			(layers "F.Cu" "F.Mask" "F.Paste")
			(net "EXT2_LED_YELLOW_D")
			(options
				(clearance outline)
				(anchor circle)
			)
			(primitives
				(gr_poly
					(pts
						(arc
							(start -0.1778 -0.2794)
							(mid -0.249642 -0.249642)
							(end -0.2794 -0.1778)
						)
						(arc
							(start -0.2794 0.1778)
							(mid -0.249642 0.249642)
							(end -0.1778 0.2794)
						)
						(arc
							(start 0.1778 0.2794)
							(mid 0.249642 0.249642)
							(end 0.2794 0.1778)
						)
						(arc
							(start 0.2794 -0.1778)
							(mid 0.249642 -0.249642)
							(end 0.1778 -0.2794)
						)
					)
					(width 0)
					(fill yes)
				)
			)
		)
	)
	(footprint ""
		(layer "F.Cu")
		(at 62.8396 -162.8648)
		(property "Reference" "C50"
			(at 0 0 0)
			(layer "F.SilkS")
			(hide yes)
			(effects
				(font
					(size 1.27 1.27)
				)
			)
		)
		(property "Value" "SCD1U16V2KX-3GP"
			(at 1.1811 -2.7051 0)
			(unlocked yes)
			(layer "F.Fab")
			(hide yes)
			(effects
				(font
					(size 1.016 1.016)
					(thickness 0.1524)
				)
			)
		)
		(property "Device Type" "C402H22"
			(at 1.1811 -4.2291 0)
			(unlocked yes)
			(layer "F.Fab")
			(hide yes)
			(effects
				(font
					(size 1.016 1.016)
					(thickness 0.1524)
				)
			)
		)
		(duplicate_pad_numbers_are_jumpers no)
		(fp_rect
			(start -0.4318 0.9525)
			(end 0.4318 -0.9525)
			(stroke
				(width 0)
				(type default)
			)
			(fill no)
			(layer "F.CrtYd")
		)
		(fp_rect
			(start -0.4318 0.9525)
			(end 0.4318 -0.9525)
			(stroke
				(width 0)
				(type default)
			)
			(fill no)
			(layer "F.Fab")
		)
		(pad "1" smd custom
			(at 0 -0.4445)
			(size 0.1524 0.1524)
			(layers "F.Cu" "F.Mask" "F.Paste")
			(net "FM_TPM_PRSNT_RST")
			(options
				(clearance outline)
				(anchor circle)
			)
			(primitives
				(gr_poly
					(pts
						(arc
							(start 0.3048 -0.2032)
							(mid 0.275042 -0.275042)
							(end 0.2032 -0.3048)
						)
						(arc
							(start -0.2032 -0.3048)
							(mid -0.275042 -0.275042)
							(end -0.3048 -0.2032)
						)
						(arc
							(start -0.3048 0.2032)
							(mid -0.275042 0.275042)
							(end -0.2032 0.3048)
						)
						(arc
							(start 0.2032 0.3048)
							(mid 0.275042 0.275042)
							(end 0.3048 0.2032)
						)
					)
					(width 0)
					(fill yes)
				)
			)
		)
		(pad "2" smd custom
			(at 0 0.4445)
			(size 0.1524 0.1524)
			(layers "F.Cu" "F.Mask" "F.Paste")
			(net "GND")
			(options
				(clearance outline)
				(anchor circle)
			)
			(primitives
				(gr_poly
					(pts
						(arc
							(start 0.3048 -0.2032)
							(mid 0.275042 -0.275042)
							(end 0.2032 -0.3048)
						)
						(arc
							(start -0.2032 -0.3048)
							(mid -0.275042 -0.275042)
							(end -0.3048 -0.2032)
						)
						(arc
							(start -0.3048 0.2032)
							(mid -0.275042 0.275042)
							(end -0.2032 0.3048)
						)
						(arc
							(start 0.2032 0.3048)
							(mid 0.275042 0.275042)
							(end 0.3048 0.2032)
						)
					)
					(width 0)
					(fill yes)
				)
			)
		)
	)
	(footprint ""
		(layer "F.Cu")
		(at 159.999934 -14.699996)
		(property "Reference" "EXT2"
			(at 0 0 0)
			(layer "F.SilkS")
			(hide yes)
			(effects
				(font
					(size 1.27 1.27)
				)
			)
		)
		(property "Value" "MINI-SAS-36P-7-GP"
			(at -9.3345 2.159 0)
			(unlocked yes)
			(layer "F.Fab")
			(hide yes)
			(effects
				(font
					(size 1.016 1.016)
					(thickness 0.1524)
				)
			)
		)
		(property "Device Type" "PREFIT-42P-131384H522"
			(at -9.3345 0.635 0)
			(unlocked yes)
			(layer "F.Fab")
			(hide yes)
			(effects
				(font
					(size 1.016 1.016)
					(thickness 0.1524)
				)
			)
		)
		(duplicate_pad_numbers_are_jumpers no)
		(fp_line
			(start -6.8072 9.3726)
			(end -6.2103 9.3726)
			(stroke
				(width 0.1524)
				(type default)
			)
			(layer "F.SilkS")
		)
		(fp_line
			(start -6.8072 20.6248)
			(end -6.8072 9.3726)
			(stroke
				(width 0.1524)
				(type default)
			)
			(layer "F.SilkS")
		)
		(fp_line
			(start -6.2103 -18.288)
			(end 6.2103 -18.288)
			(stroke
				(width 0.1524)
				(type default)
			)
			(layer "F.SilkS")
		)
		(fp_line
			(start -6.2103 9.3726)
			(end -6.2103 -18.288)
			(stroke
				(width 0.1524)
				(type default)
			)
			(layer "F.SilkS")
		)
		(fp_line
			(start 6.2103 -18.288)
			(end 6.2103 9.3726)
			(stroke
				(width 0.1524)
				(type default)
			)
			(layer "F.SilkS")
		)
		(fp_line
			(start 6.2103 9.3726)
			(end 6.8072 9.3726)
			(stroke
				(width 0.1524)
				(type default)
			)
			(layer "F.SilkS")
		)
		(fp_line
			(start 6.8072 9.3726)
			(end 6.8072 20.6248)
			(stroke
				(width 0.1524)
				(type default)
			)
			(layer "F.SilkS")
		)
		(fp_line
			(start 6.8072 20.6248)
			(end -6.8072 20.6248)
			(stroke
				(width 0.1524)
				(type default)
			)
			(layer "F.SilkS")
		)
		(fp_poly
			(pts
				(xy -6.8072 20.6248) (xy -6.8072 10.5156) (xy 6.8072 10.5156) (xy 6.8072 20.6248)
			)
			(stroke
				(width 0)
				(type default)
			)
			(fill yes)
			(layer "F.SilkS")
		)
		(fp_poly
			(pts
				(arc
					(start -3.7211 9.970008)
					(mid -4.0767 10.325608)
					(end -4.4323 9.970008)
				)
				(arc
					(start -4.4323 9.284208)
					(mid -4.0767 8.928608)
					(end -3.7211 9.284208)
				)
			)
			(stroke
				(width 0)
				(type default)
			)
			(fill yes)
			(layer "F.SilkS")
		)
		(fp_poly
			(pts
				(arc
					(start 4.4069 9.970008)
					(mid 4.0513 10.325608)
					(end 3.6957 9.970008)
				)
				(arc
					(start 3.6957 9.284208)
					(mid 4.0513 8.928608)
					(end 4.4069 9.284208)
				)
			)
			(stroke
				(width 0)
				(type default)
			)
			(fill yes)
			(layer "F.SilkS")
		)
		(fp_poly
			(pts
				(arc
					(start -3.9116 -2.8829)
					(mid -4.2926 -2.5019)
					(end -4.6736 -2.8829)
				)
				(arc
					(start -4.6736 -4.4069)
					(mid -4.2926 -4.7879)
					(end -3.9116 -4.4069)
				)
			)
			(stroke
				(width 0)
				(type default)
			)
			(fill yes)
			(layer "F.SilkS")
		)
		(fp_poly
			(pts
				(arc
					(start -0.0381 -17.145)
					(mid -0.4191 -17.526)
					(end -0.0381 -17.907)
				)
				(arc
					(start 1.4859 -17.907)
					(mid 1.8669 -17.526)
					(end 1.4859 -17.145)
				)
			)
			(stroke
				(width 0)
				(type default)
			)
			(fill yes)
			(layer "F.SilkS")
		)
		(fp_poly
			(pts
				(arc
					(start 4.7244 -2.8829)
					(mid 4.3434 -2.5019)
					(end 3.9624 -2.8829)
				)
				(arc
					(start 3.9624 -4.4069)
					(mid 4.3434 -4.7879)
					(end 4.7244 -4.4069)
				)
			)
			(stroke
				(width 0)
				(type default)
			)
			(fill yes)
			(layer "F.SilkS")
		)
		(fp_poly
			(pts
				(arc
					(start -4.6101 -14.2875)
					(mid -5.1181 -13.7795)
					(end -5.6261 -14.2875)
				)
				(arc
					(start -5.6261 -15.8115)
					(mid -5.1181 -16.3195)
					(end -4.6101 -15.8115)
				)
			)
			(stroke
				(width 0)
				(type default)
			)
			(fill yes)
			(layer "F.SilkS")
		)
		(fp_poly
			(pts
				(arc
					(start -4.6101 -10.414)
					(mid -5.1181 -9.906)
					(end -5.6261 -10.414)
				)
				(arc
					(start -5.6261 -11.938)
					(mid -5.1181 -12.446)
					(end -4.6101 -11.938)
				)
			)
			(stroke
				(width 0)
				(type default)
			)
			(fill yes)
			(layer "F.SilkS")
		)
		(fp_poly
			(pts
				(arc
					(start -4.5847 -6.5024)
					(mid -5.0927 -5.9944)
					(end -5.6007 -6.5024)
				)
				(arc
					(start -5.6007 -8.0264)
					(mid -5.0927 -8.5344)
					(end -4.5847 -8.0264)
				)
			)
			(stroke
				(width 0)
				(type default)
			)
			(fill yes)
			(layer "F.SilkS")
		)
		(fp_rect
			(start -10.9601 15.0622)
			(end 10.9601 -22.9743)
			(stroke
				(width 0)
				(type default)
			)
			(fill no)
			(layer "B.CrtYd")
		)
		(fp_poly
			(pts
				(xy -6.5532 20.3708) (xy -6.5532 9.6266) (xy -5.9563 9.6266) (xy -5.9563 -18.034) (xy 5.9563 -18.034)
				(xy 5.9563 9.6266) (xy 6.5532 9.6266) (xy 6.5532 20.3708)
			)
			(stroke
				(width 0)
				(type default)
			)
			(fill no)
			(layer "F.CrtYd")
		)
		(fp_poly
			(pts
				(xy -11.557 25.3746) (xy -11.557 4.6228) (xy -10.9601 4.6228) (xy -10.9601 -23.0378) (xy 10.9601 -23.0378)
				(xy 10.9601 2.1717) (xy 6.464554 2.1717) (xy 6.464554 -18.542254) (xy -6.464554 -18.542254) (xy -6.464554 9.118346)
				(xy -7.061454 9.118346) (xy -7.061454 20.879054) (xy 7.061454 20.879054) (xy 7.061454 9.118346)
				(xy 6.464554 9.118346) (xy 6.464554 2.1844) (xy 10.9601 2.1844) (xy 10.9601 4.6228) (xy 11.557 4.6228)
				(xy 11.557 25.3746)
			)
			(stroke
				(width 0)
				(type default)
			)
			(fill no)
			(layer "F.CrtYd")
		)
		(fp_poly
			(pts
				(xy -7.0612 20.8788) (xy -7.0612 9.1186) (xy -6.4643 9.1186) (xy -6.4643 -18.542) (xy 6.4643 -18.542)
				(xy 6.4643 -0.00635) (xy 5.9563 -0.00635) (xy 5.9563 -18.034) (xy -5.9563 -18.034) (xy -5.9563 9.6266)
				(xy -6.5532 9.6266) (xy -6.5532 20.3708) (xy 6.5532 20.3708) (xy 6.5532 9.6266) (xy 5.9563 9.6266)
				(xy 5.9563 0.00635) (xy 6.4643 0.00635) (xy 6.4643 9.1186) (xy 7.0612 9.1186) (xy 7.0612 20.8788)
			)
			(stroke
				(width 0)
				(type default)
			)
			(fill no)
			(layer "F.CrtYd")
		)
		(fp_rect
			(start -15.9639 20.066)
			(end 15.9639 -27.9781)
			(stroke
				(width 0)
				(type default)
			)
			(fill no)
			(layer "B.Fab")
		)
		(fp_rect
			(start -10.9601 15.0622)
			(end 10.9601 -22.9743)
			(stroke
				(width 0)
				(type default)
			)
			(fill no)
			(layer "B.Fab")
		)
		(fp_poly
			(pts
				(xy -16.5608 30.3784) (xy -16.5608 -0.381) (xy -15.9639 -0.381) (xy -15.9639 -28.0416) (xy 15.9639 -28.0416)
				(xy 15.9639 -0.381) (xy 16.5608 -0.381) (xy 16.5608 30.3784)
			)
			(stroke
				(width 0)
				(type default)
			)
			(fill no)
			(layer "F.Fab")
		)
		(fp_poly
			(pts
				(xy -11.557 25.3746) (xy -11.557 4.6228) (xy -10.9601 4.6228) (xy -10.9601 -23.0378) (xy 10.9601 -23.0378)
				(xy 10.9601 4.6228) (xy 11.557 4.6228) (xy 11.557 25.3746)
			)
			(stroke
				(width 0)
				(type default)
			)
			(fill no)
			(layer "F.Fab")
		)
		(fp_poly
			(pts
				(xy -7.0612 20.8788) (xy -7.0612 9.1186) (xy -6.4643 9.1186) (xy -6.4643 -18.542) (xy 6.4643 -18.542)
				(xy 6.4643 9.1186) (xy 7.0612 9.1186) (xy 7.0612 20.8788)
			)
			(stroke
				(width 0)
				(type default)
			)
			(fill no)
			(layer "F.Fab")
		)
		(fp_text user "Press Fit"
			(at -5.055108 12.29614 0)
			(unlocked yes)
			(layer "F.SilkS")
			(effects
				(font
					(size 1.016 1.016)
					(thickness 0.1524)
				)
				(justify left)
			)
		)
		(fp_text user "Can not place BGA,CSP,Wave Solder Component"
			(at -24.838914 17.72412 0)
			(unlocked yes)
			(layer "B.Fab")
			(effects
				(font
					(size 1.016 1.016)
					(thickness 0.1524)
				)
				(justify left)
			)
		)
		(fp_text user "Can not place BGA,CSP,Wave Solder Component"
			(at -25.305766 27.745182 0)
			(unlocked yes)
			(layer "F.Fab")
			(effects
				(font
					(size 1.016 1.016)
					(thickness 0.1524)
				)
				(justify left)
			)
		)
		(fp_text user "High Limit 2mm"
			(at -7.86384 23.09876 0)
			(unlocked yes)
			(layer "F.Fab")
			(effects
				(font
					(size 1.016 1.016)
					(thickness 0.1524)
				)
				(justify left)
			)
		)
		(pad "A1" thru_hole circle
			(at -2.999994 -4.400042)
			(size 0.7366 0.7366)
			(drill 0.369824)
			(layers "*.Cu" "*.Mask")
			(remove_unused_layers no)
			(net "ZDEF_EXTB_TP_A1")
			(clearance 0.1778)
			(thermal_gap 0.1778)
		)
		(pad "A2" thru_hole circle
			(at -2.249932 -2.999994)
			(size 0.7366 0.7366)
			(drill 0.369824)
			(layers "*.Cu" "*.Mask")
			(remove_unused_layers no)
			(net "ZDEF_EXTB_TP_A2")
			(clearance 0.1778)
			(thermal_gap 0.1778)
		)
		(pad "A3" thru_hole circle
			(at -1.500124 -3.700018)
			(size 0.7366 0.7366)
			(drill 0.369824)
			(layers "*.Cu" "*.Mask")
			(remove_unused_layers no)
			(net "GND")
			(clearance 0.1778)
			(thermal_gap 0.1778)
		)
		(pad "A4" thru_hole circle
			(at -0.749808 -4.400042)
			(size 0.7366 0.7366)
			(drill 0.369824)
			(layers "*.Cu" "*.Mask")
			(remove_unused_layers no)
			(net "PHY_CON_B_TO_IOC_1_DP_C")
			(clearance 0.1778)
			(thermal_gap 0.1778)
		)
		(pad "A5" thru_hole circle
			(at 0 -2.999994)
			(size 0.7366 0.7366)
			(drill 0.369824)
			(layers "*.Cu" "*.Mask")
			(remove_unused_layers no)
			(net "PHY_CON_B_TO_IOC_1_DN_C")
			(clearance 0.1778)
			(thermal_gap 0.1778)
		)
		(pad "A6" thru_hole circle
			(at 0.749808 -3.700018)
			(size 0.7366 0.7366)
			(drill 0.369824)
			(layers "*.Cu" "*.Mask")
			(remove_unused_layers no)
			(net "GND")
			(clearance 0.1778)
			(thermal_gap 0.1778)
		)
		(pad "A7" thru_hole circle
			(at 1.500124 -4.400042)
			(size 0.7366 0.7366)
			(drill 0.369824)
			(layers "*.Cu" "*.Mask")
			(remove_unused_layers no)
			(net "PHY_CON_B_TO_IOC_0_DP_C")
			(clearance 0.1778)
			(thermal_gap 0.1778)
		)
		(pad "A8" thru_hole circle
			(at 2.250186 -2.999994)
			(size 0.7366 0.7366)
			(drill 0.369824)
			(layers "*.Cu" "*.Mask")
			(remove_unused_layers no)
			(net "PHY_CON_B_TO_IOC_0_DN_C")
			(clearance 0.1778)
			(thermal_gap 0.1778)
		)
		(pad "A9" thru_hole circle
			(at 2.999994 -3.700018)
			(size 0.7366 0.7366)
			(drill 0.369824)
			(layers "*.Cu" "*.Mask")
			(remove_unused_layers no)
			(net "GND")
			(clearance 0.1778)
			(thermal_gap 0.1778)
		)
		(pad "B1" thru_hole circle
			(at -2.999994 -8.199882)
			(size 0.7366 0.7366)
			(drill 0.369824)
			(layers "*.Cu" "*.Mask")
			(remove_unused_layers no)
			(net "ZDEF_EXTB_TP_B1")
			(clearance 0.1778)
			(thermal_gap 0.1778)
		)
		(pad "B2" thru_hole circle
			(at -2.249932 -6.800088)
			(size 0.7366 0.7366)
			(drill 0.369824)
			(layers "*.Cu" "*.Mask")
			(remove_unused_layers no)
			(net "ZDEF_EXTB_TP_B2")
			(clearance 0.1778)
			(thermal_gap 0.1778)
		)
		(pad "B3" thru_hole circle
			(at -1.500124 -7.500112)
			(size 0.7366 0.7366)
			(drill 0.369824)
			(layers "*.Cu" "*.Mask")
			(remove_unused_layers no)
			(net "GND")
			(clearance 0.1778)
			(thermal_gap 0.1778)
		)
		(pad "B4" thru_hole circle
			(at -0.749808 -8.199882)
			(size 0.7366 0.7366)
			(drill 0.369824)
			(layers "*.Cu" "*.Mask")
			(remove_unused_layers no)
			(net "PHY_CON_B_TO_IOC_3_DP_C")
			(clearance 0.1778)
			(thermal_gap 0.1778)
		)
		(pad "B5" thru_hole circle
			(at 0 -6.800088)
			(size 0.7366 0.7366)
			(drill 0.369824)
			(layers "*.Cu" "*.Mask")
			(remove_unused_layers no)
			(net "PHY_CON_B_TO_IOC_3_DN_C")
			(clearance 0.1778)
			(thermal_gap 0.1778)
		)
		(pad "B6" thru_hole circle
			(at 0.749808 -7.500112)
			(size 0.7366 0.7366)
			(drill 0.369824)
			(layers "*.Cu" "*.Mask")
			(remove_unused_layers no)
			(net "GND")
			(clearance 0.1778)
			(thermal_gap 0.1778)
		)
		(pad "B7" thru_hole circle
			(at 1.500124 -8.199882)
			(size 0.7366 0.7366)
			(drill 0.369824)
			(layers "*.Cu" "*.Mask")
			(remove_unused_layers no)
			(net "PHY_CON_B_TO_IOC_2_DP_C")
			(clearance 0.1778)
			(thermal_gap 0.1778)
		)
		(pad "B8" thru_hole circle
			(at 2.250186 -6.800088)
			(size 0.7366 0.7366)
			(drill 0.369824)
			(layers "*.Cu" "*.Mask")
			(remove_unused_layers no)
			(net "PHY_CON_B_TO_IOC_2_DN_C")
			(clearance 0.1778)
			(thermal_gap 0.1778)
		)
		(pad "B9" thru_hole circle
			(at 2.999994 -7.500112)
			(size 0.7366 0.7366)
			(drill 0.369824)
			(layers "*.Cu" "*.Mask")
			(remove_unused_layers no)
			(net "GND")
			(clearance 0.1778)
			(thermal_gap 0.1778)
		)
		(pad "C1" thru_hole circle
			(at -2.999994 -11.999976)
			(size 0.7366 0.7366)
			(drill 0.369824)
			(layers "*.Cu" "*.Mask")
			(remove_unused_layers no)
			(net "ZDEF_EXTB_TP_C1")
			(clearance 0.1778)
			(thermal_gap 0.1778)
		)
		(pad "C2" thru_hole circle
			(at -2.249932 -10.599928)
			(size 0.7366 0.7366)
			(drill 0.369824)
			(layers "*.Cu" "*.Mask")
			(remove_unused_layers no)
			(net "ZDEF_EXTB_TP_C2")
			(clearance 0.1778)
			(thermal_gap 0.1778)
		)
		(pad "C3" thru_hole circle
			(at -1.500124 -11.299952)
			(size 0.7366 0.7366)
			(drill 0.369824)
			(layers "*.Cu" "*.Mask")
			(remove_unused_layers no)
			(net "GND")
			(clearance 0.1778)
			(thermal_gap 0.1778)
		)
		(pad "C4" thru_hole circle
			(at -0.749808 -11.999976)
			(size 0.7366 0.7366)
			(drill 0.369824)
			(layers "*.Cu" "*.Mask")
			(remove_unused_layers no)
			(net "PHY_IOC_TO_CON_B_1_DP")
			(clearance 0.1778)
			(thermal_gap 0.1778)
		)
		(pad "C5" thru_hole circle
			(at 0 -10.599928)
			(size 0.7366 0.7366)
			(drill 0.369824)
			(layers "*.Cu" "*.Mask")
			(remove_unused_layers no)
			(net "PHY_IOC_TO_CON_B_1_DN")
			(clearance 0.1778)
			(thermal_gap 0.1778)
		)
		(pad "C6" thru_hole circle
			(at 0.749808 -11.299952)
			(size 0.7366 0.7366)
			(drill 0.369824)
			(layers "*.Cu" "*.Mask")
			(remove_unused_layers no)
			(net "GND")
			(clearance 0.1778)
			(thermal_gap 0.1778)
		)
		(pad "C7" thru_hole circle
			(at 1.500124 -11.999976)
			(size 0.7366 0.7366)
			(drill 0.369824)
			(layers "*.Cu" "*.Mask")
			(remove_unused_layers no)
			(net "PHY_IOC_TO_CON_B_0_DP")
			(clearance 0.1778)
			(thermal_gap 0.1778)
		)
		(pad "C8" thru_hole circle
			(at 2.250186 -10.599928)
			(size 0.7366 0.7366)
			(drill 0.369824)
			(layers "*.Cu" "*.Mask")
			(remove_unused_layers no)
			(net "PHY_IOC_TO_CON_B_0_DN")
			(clearance 0.1778)
			(thermal_gap 0.1778)
		)
		(pad "C9" thru_hole circle
			(at 2.999994 -11.299952)
			(size 0.7366 0.7366)
			(drill 0.369824)
			(layers "*.Cu" "*.Mask")
			(remove_unused_layers no)
			(net "GND")
			(clearance 0.1778)
			(thermal_gap 0.1778)
		)
		(pad "D1" thru_hole circle
			(at -2.999994 -15.80007)
			(size 0.7366 0.7366)
			(drill 0.369824)
			(layers "*.Cu" "*.Mask")
			(remove_unused_layers no)
			(net "ZDEF_EXTB_TP_D1")
			(clearance 0.1778)
			(thermal_gap 0.1778)
		)
		(pad "D2" thru_hole circle
			(at -2.249932 -14.400022)
			(size 0.7366 0.7366)
			(drill 0.369824)
			(layers "*.Cu" "*.Mask")
			(remove_unused_layers no)
			(net "ZDEF_EXTB_TP_D2")
			(clearance 0.1778)
			(thermal_gap 0.1778)
		)
		(pad "D3" thru_hole circle
			(at -1.500124 -15.100046)
			(size 0.7366 0.7366)
			(drill 0.369824)
			(layers "*.Cu" "*.Mask")
			(remove_unused_layers no)
			(net "GND")
			(clearance 0.1778)
			(thermal_gap 0.1778)
		)
		(pad "D4" thru_hole circle
			(at -0.749808 -15.80007)
			(size 0.7366 0.7366)
			(drill 0.369824)
			(layers "*.Cu" "*.Mask")
			(remove_unused_layers no)
			(net "PHY_IOC_TO_CON_B_3_DP")
			(clearance 0.1778)
			(thermal_gap 0.1778)
		)
		(pad "D5" thru_hole circle
			(at 0 -14.400022)
			(size 0.7366 0.7366)
			(drill 0.369824)
			(layers "*.Cu" "*.Mask")
			(remove_unused_layers no)
			(net "PHY_IOC_TO_CON_B_3_DN")
			(clearance 0.1778)
			(thermal_gap 0.1778)
		)
		(pad "D6" thru_hole circle
			(at 0.749808 -15.100046)
			(size 0.7366 0.7366)
			(drill 0.369824)
			(layers "*.Cu" "*.Mask")
			(remove_unused_layers no)
			(net "GND")
			(clearance 0.1778)
			(thermal_gap 0.1778)
		)
		(pad "D7" thru_hole circle
			(at 1.500124 -15.80007)
			(size 0.7366 0.7366)
			(drill 0.369824)
			(layers "*.Cu" "*.Mask")
			(remove_unused_layers no)
			(net "PHY_IOC_TO_CON_B_2_DP")
			(clearance 0.1778)
			(thermal_gap 0.1778)
		)
		(pad "D8" thru_hole circle
			(at 2.250186 -14.400022)
			(size 0.7366 0.7366)
			(drill 0.369824)
			(layers "*.Cu" "*.Mask")
			(remove_unused_layers no)
			(net "PHY_IOC_TO_CON_B_2_DN")
			(clearance 0.1778)
			(thermal_gap 0.1778)
		)
		(pad "D9" thru_hole circle
			(at 2.999994 -15.100046)
			(size 0.7366 0.7366)
			(drill 0.369824)
			(layers "*.Cu" "*.Mask")
			(remove_unused_layers no)
			(net "GND")
			(clearance 0.1778)
			(thermal_gap 0.1778)
		)
		(pad "G1" thru_hole circle
			(at -5.500116 9.61009)
			(size 0.9144 0.9144)
			(drill 0.569976)
			(layers "*.Cu" "*.Mask")
			(remove_unused_layers no)
			(net "EXT2_CONN_GND")
			(clearance 0.1905)
			(thermal_gap 0.1905)
		)
		(pad "G2" thru_hole circle
			(at 5.500116 9.61009)
			(size 0.9144 0.9144)
			(drill 0.569976)
			(layers "*.Cu" "*.Mask")
			(remove_unused_layers no)
			(net "EXT2_CONN_GND")
			(clearance 0.1905)
			(thermal_gap 0.1905)
		)
		(pad "G3" thru_hole circle
			(at -5.500116 -3.700018)
			(size 0.9144 0.9144)
			(drill 0.569976)
			(layers "*.Cu" "*.Mask")
			(remove_unused_layers no)
			(net "EXT2_CONN_GND")
			(clearance 0.1905)
			(thermal_gap 0.1905)
		)
		(pad "G4" thru_hole circle
			(at 5.500116 -3.700018)
			(size 0.9144 0.9144)
			(drill 0.569976)
			(layers "*.Cu" "*.Mask")
			(remove_unused_layers no)
			(net "EXT2_CONN_GND")
			(clearance 0.1905)
			(thermal_gap 0.1905)
		)
		(pad "G5" thru_hole circle
			(at -1.500124 -17.509998)
			(size 0.9144 0.9144)
			(drill 0.569976)
			(layers "*.Cu" "*.Mask")
			(remove_unused_layers no)
			(net "EXT2_CONN_GND")
			(clearance 0.1905)
			(thermal_gap 0.1905)
		)
		(pad "G6" thru_hole circle
			(at 2.999994 -17.509998)
			(size 0.9144 0.9144)
			(drill 0.569976)
			(layers "*.Cu" "*.Mask")
			(remove_unused_layers no)
			(net "EXT2_CONN_GND")
			(clearance 0.1905)
			(thermal_gap 0.1905)
		)
		(pad "G7" thru_hole circle
			(at 0 0)
			(size 3.81 3.81)
			(drill 2.2098)
			(layers "*.Cu" "*.Mask")
			(remove_unused_layers no)
			(net "EXT2_CONN_GND")
			(clearance -0.2921)
			(thermal_gap 0.3048)
			(padstack
				(mode front_inner_back)
				(layer "Inner"
					(shape circle)
					(size 2.6162 2.6162)
					(clearance 0.3048)
				)
				(layer "B.Cu"
					(shape circle)
					(size 3.81 3.81)
					(clearance -0.2921)
				)
			)
		)
		(zone
			(layer "F.Cu")
			(hatch none 0.5)
			(connect_pads
				(clearance 0)
			)
			(min_thickness 0.25)
			(keepout
				(tracks not_allowed)
				(vias allowed)
				(pads allowed)
				(copperpour not_allowed)
				(footprints allowed)
			)
			(placement
				(enabled no)
				(sheetname "")
			)
			(fill
				(thermal_gap 0.5)
				(thermal_bridge_width 0.5)
				(island_removal_mode 0)
			)
			(polygon
				(pts
					(xy 154.199844 -7.260082) (xy 154.199844 -5.96011) (xy 154.800046 -5.96011) (xy 154.800046 -7.260082)
				)
			)
		)
		(zone
			(layer "F.Cu")
			(hatch none 0.5)
			(connect_pads
				(clearance 0)
			)
			(min_thickness 0.25)
			(keepout
				(tracks allowed)
				(vias not_allowed)
				(pads allowed)
				(copperpour not_allowed)
				(footprints allowed)
			)
			(placement
				(enabled no)
				(sheetname "")
			)
			(fill
				(thermal_gap 0.5)
				(thermal_bridge_width 0.5)
				(island_removal_mode 0)
			)
			(polygon
				(pts
					(xy 154.199844 -5.96011) (xy 154.800046 -5.96011) (xy 154.800046 -7.260082) (xy 154.199844 -7.260082)
				)
			)
		)
		(zone
			(layer "F.Cu")
			(hatch none 0.5)
			(connect_pads
				(clearance 0)
			)
			(min_thickness 0.25)
			(keepout
				(tracks not_allowed)
				(vias allowed)
				(pads allowed)
				(copperpour not_allowed)
				(footprints allowed)
			)
			(placement
				(enabled no)
				(sheetname "")
			)
			(fill
				(thermal_gap 0.5)
				(thermal_bridge_width 0.5)
				(island_removal_mode 0)
			)
			(polygon
				(pts
					(xy 165.199822 -7.260082) (xy 165.199822 -5.96011) (xy 165.800024 -5.96011) (xy 165.800024 -7.260082)
				)
			)
		)
		(zone
			(layer "F.Cu")
			(hatch none 0.5)
			(connect_pads
				(clearance 0)
			)
			(min_thickness 0.25)
			(keepout
				(tracks allowed)
				(vias not_allowed)
				(pads allowed)
				(copperpour not_allowed)
				(footprints allowed)
			)
			(placement
				(enabled no)
				(sheetname "")
			)
			(fill
				(thermal_gap 0.5)
				(thermal_bridge_width 0.5)
				(island_removal_mode 0)
			)
			(polygon
				(pts
					(xy 165.199822 -5.96011) (xy 165.800024 -5.96011) (xy 165.800024 -7.260082) (xy 165.199822 -7.260082)
				)
			)
		)
	)
	(footprint ""
		(layer "F.Cu")
		(at 66.71183 -179.375054 180)
		(property "Reference" "R82"
			(at 0 0 180)
			(layer "F.SilkS")
			(hide yes)
			(effects
				(font
					(size 1.27 1.27)
				)
			)
		)
		(property "Value" "10KR2F-2-GP"
			(at 0.064008 -3.99415 180)
			(unlocked yes)
			(layer "F.Fab")
			(hide yes)
			(effects
				(font
					(size 1.016 1.016)
					(thickness 0.1524)
				)
			)
		)
		(property "Device Type" "R402H16"
			(at 0.064262 -5.51815 180)
			(unlocked yes)
			(layer "F.Fab")
			(hide yes)
			(effects
				(font
					(size 1.016 1.016)
					(thickness 0.1524)
				)
			)
		)
		(duplicate_pad_numbers_are_jumpers no)
		(fp_line
			(start 0.508 -0.9398)
			(end -0.508 -0.9398)
			(stroke
				(width 0.1524)
				(type default)
			)
			(layer "F.SilkS")
		)
		(fp_line
			(start -0.508 -0.9398)
			(end -0.508 0.9398)
			(stroke
				(width 0.1524)
				(type default)
			)
			(layer "F.SilkS")
		)
		(fp_rect
			(start -0.508 0.9398)
			(end 0.508 -0.9398)
			(stroke
				(width 0)
				(type default)
			)
			(fill no)
			(layer "F.CrtYd")
		)
		(fp_rect
			(start -0.508 0.9398)
			(end 0.508 -0.9398)
			(stroke
				(width 0)
				(type default)
			)
			(fill no)
			(layer "F.Fab")
		)
		(pad "1" smd custom
			(at 0 -0.4445 180)
			(size 0.1397 0.1397)
			(layers "F.Cu" "F.Mask" "F.Paste")
			(net "VREF_2V2")
			(options
				(clearance outline)
				(anchor circle)
			)
			(primitives
				(gr_poly
					(pts
						(arc
							(start -0.1778 -0.2794)
							(mid -0.249642 -0.249642)
							(end -0.2794 -0.1778)
						)
						(arc
							(start -0.2794 0.1778)
							(mid -0.249642 0.249642)
							(end -0.1778 0.2794)
						)
						(arc
							(start 0.1778 0.2794)
							(mid 0.249642 0.249642)
							(end 0.2794 0.1778)
						)
						(arc
							(start 0.2794 -0.1778)
							(mid 0.249642 -0.249642)
							(end 0.1778 -0.2794)
						)
					)
					(width 0)
					(fill yes)
				)
			)
		)
		(pad "2" smd custom
			(at 0 0.4445 180)
			(size 0.1397 0.1397)
			(layers "F.Cu" "F.Mask" "F.Paste")
			(net "GND")
			(options
				(clearance outline)
				(anchor circle)
			)
			(primitives
				(gr_poly
					(pts
						(arc
							(start -0.1778 -0.2794)
							(mid -0.249642 -0.249642)
							(end -0.2794 -0.1778)
						)
						(arc
							(start -0.2794 0.1778)
							(mid -0.249642 0.249642)
							(end -0.1778 0.2794)
						)
						(arc
							(start 0.1778 0.2794)
							(mid 0.249642 0.249642)
							(end 0.2794 0.1778)
						)
						(arc
							(start 0.2794 -0.1778)
							(mid 0.249642 -0.249642)
							(end 0.1778 -0.2794)
						)
					)
					(width 0)
					(fill yes)
				)
			)
		)
	)
	(footprint ""
		(layer "F.Cu")
		(at 172.942504 -138.259566 -90)
		(property "Reference" "C152"
			(at 0 0 270)
			(layer "F.SilkS")
			(hide yes)
			(effects
				(font
					(size 1.27 1.27)
				)
			)
		)
		(property "Value" "SC10U16V5KX-7-GP-U"
			(at -0.0762 -6.1214 270)
			(unlocked yes)
			(layer "F.Fab")
			(hide yes)
			(effects
				(font
					(size 1.016 1.016)
					(thickness 0.1524)
				)
			)
		)
		(property "Device Type" "C805H58"
			(at -0.0762 -8.1534 270)
			(unlocked yes)
			(layer "F.Fab")
			(hide yes)
			(effects
				(font
					(size 1.016 1.016)
					(thickness 0.1524)
				)
			)
		)
		(duplicate_pad_numbers_are_jumpers no)
		(fp_line
			(start 0.635 0)
			(end -0.635 0)
			(stroke
				(width 0.508)
				(type default)
			)
			(layer "F.SilkS")
		)
		(fp_rect
			(start -0.9652 1.778)
			(end 0.9652 -1.778)
			(stroke
				(width 0)
				(type default)
			)
			(fill no)
			(layer "F.CrtYd")
		)
		(fp_poly
			(pts
				(xy -0.9652 -1.778) (xy 0.9652 -1.778) (xy 0.9652 1.778) (xy -0.9652 1.778)
			)
			(stroke
				(width 0)
				(type default)
			)
			(fill no)
			(layer "F.Fab")
		)
		(pad "1" smd rect
			(at 0 -0.9652 270)
			(size 1.397 1.143)
			(layers "F.Cu" "F.Mask" "F.Paste")
			(net "P12V_STBY_VIN_PU1")
		)
		(pad "2" smd rect
			(at 0 0.9652 270)
			(size 1.397 1.143)
			(layers "F.Cu" "F.Mask" "F.Paste")
			(net "GND")
		)
	)
	(footprint ""
		(layer "F.Cu")
		(at 83.358228 -82.149696 90)
		(property "Reference" "VIA12"
			(at 0 0 90)
			(layer "F.SilkS")
			(hide yes)
			(effects
				(font
					(size 1.27 1.27)
				)
			)
		)
		(property "Value" "85OHM-8L-1D6MM-L16L18-GP"
			(at 4.064 0.6096 90)
			(unlocked yes)
			(layer "F.Fab")
			(hide yes)
			(effects
				(font
					(size 1.016 1.016)
					(thickness 0.1524)
				)
			)
		)
		(property "Device Type" "VIA-PCIE-4P-368076"
			(at 4.064 -0.9144 90)
			(unlocked yes)
			(layer "F.Fab")
			(hide yes)
			(effects
				(font
					(size 1.016 1.016)
					(thickness 0.1524)
				)
			)
		)
		(duplicate_pad_numbers_are_jumpers no)
		(fp_rect
			(start -1.8415 0.381)
			(end 1.8415 -0.381)
			(stroke
				(width 0)
				(type default)
			)
			(fill no)
			(layer "F.CrtYd")
		)
		(fp_rect
			(start -1.8415 0.381)
			(end 1.8415 -0.381)
			(stroke
				(width 0)
				(type default)
			)
			(fill no)
			(layer "F.Fab")
		)
		(pad "1" thru_hole circle
			(at -1.4605 0 90)
			(size 0.508 0.508)
			(drill 0.254)
			(layers "*.Cu" "*.Mask")
			(remove_unused_layers no)
			(net "GND")
			(clearance 0.127)
			(thermal_gap 0.127)
		)
		(pad "2" thru_hole circle
			(at -0.4445 0 90)
			(size 0.508 0.508)
			(drill 0.254)
			(layers "*.Cu" "*.Mask")
			(remove_unused_layers no)
			(net "PCIE_IOM_TO_COMP_19_DP")
			(clearance 0.127)
			(thermal_gap 0.127)
		)
		(pad "3" thru_hole circle
			(at 0.4445 0 90)
			(size 0.508 0.508)
			(drill 0.254)
			(layers "*.Cu" "*.Mask")
			(remove_unused_layers no)
			(net "PCIE_IOM_TO_COMP_19_DN")
			(clearance 0.127)
			(thermal_gap 0.127)
		)
		(pad "4" thru_hole circle
			(at 1.4605 0 90)
			(size 0.508 0.508)
			(drill 0.254)
			(layers "*.Cu" "*.Mask")
			(remove_unused_layers no)
			(net "GND")
			(clearance 0.127)
			(thermal_gap 0.127)
		)
	)
	(footprint ""
		(layer "F.Cu")
		(at 173.863 -77.978 90)
		(property "Reference" "R619"
			(at 0 0 90)
			(layer "F.SilkS")
			(hide yes)
			(effects
				(font
					(size 1.27 1.27)
				)
			)
		)
		(property "Value" "4K7R2F-GP"
			(at 0.064008 -3.993896 90)
			(unlocked yes)
			(layer "F.Fab")
			(hide yes)
			(effects
				(font
					(size 1.016 1.016)
					(thickness 0.1524)
				)
			)
		)
		(property "Device Type" "R402H16"
			(at 0.064008 -5.517896 90)
			(unlocked yes)
			(layer "F.Fab")
			(hide yes)
			(effects
				(font
					(size 1.016 1.016)
					(thickness 0.1524)
				)
			)
		)
		(duplicate_pad_numbers_are_jumpers no)
		(fp_line
			(start 0.508 -0.9398)
			(end -0.508 -0.9398)
			(stroke
				(width 0.1524)
				(type default)
			)
			(layer "F.SilkS")
		)
		(fp_line
			(start -0.508 -0.9398)
			(end -0.508 0.9398)
			(stroke
				(width 0.1524)
				(type default)
			)
			(layer "F.SilkS")
		)
		(fp_rect
			(start -0.508 0.9398)
			(end 0.508 -0.9398)
			(stroke
				(width 0)
				(type default)
			)
			(fill no)
			(layer "F.CrtYd")
		)
		(fp_rect
			(start -0.508 0.9398)
			(end 0.508 -0.9398)
			(stroke
				(width 0)
				(type default)
			)
			(fill no)
			(layer "F.Fab")
		)
		(pad "1" smd custom
			(at 0 -0.4445 90)
			(size 0.1397 0.1397)
			(layers "F.Cu" "F.Mask" "F.Paste")
			(net "P1V8")
			(options
				(clearance outline)
				(anchor circle)
			)
			(primitives
				(gr_poly
					(pts
						(arc
							(start -0.1778 -0.2794)
							(mid -0.249642 -0.249642)
							(end -0.2794 -0.1778)
						)
						(arc
							(start -0.2794 0.1778)
							(mid -0.249642 0.249642)
							(end -0.1778 0.2794)
						)
						(arc
							(start 0.1778 0.2794)
							(mid 0.249642 0.249642)
							(end 0.2794 0.1778)
						)
						(arc
							(start 0.2794 -0.1778)
							(mid 0.249642 -0.249642)
							(end 0.1778 -0.2794)
						)
					)
					(width 0)
					(fill yes)
				)
			)
		)
		(pad "2" smd custom
			(at 0 0.4445 90)
			(size 0.1397 0.1397)
			(layers "F.Cu" "F.Mask" "F.Paste")
			(net "UART_SERCLK")
			(options
				(clearance outline)
				(anchor circle)
			)
			(primitives
				(gr_poly
					(pts
						(arc
							(start -0.1778 -0.2794)
							(mid -0.249642 -0.249642)
							(end -0.2794 -0.1778)
						)
						(arc
							(start -0.2794 0.1778)
							(mid -0.249642 0.249642)
							(end -0.1778 0.2794)
						)
						(arc
							(start 0.1778 0.2794)
							(mid 0.249642 0.249642)
							(end 0.2794 0.1778)
						)
						(arc
							(start 0.2794 -0.1778)
							(mid 0.249642 -0.249642)
							(end 0.1778 -0.2794)
						)
					)
					(width 0)
					(fill yes)
				)
			)
		)
	)
	(footprint ""
		(layer "F.Cu")
		(at 37.3126 -175.6664 -90)
		(property "Reference" "C183"
			(at 0 0 270)
			(layer "F.SilkS")
			(hide yes)
			(effects
				(font
					(size 1.27 1.27)
				)
			)
		)
		(property "Value" "SC1KP50V2KX-1GP"
			(at 1.1811 -2.7051 270)
			(unlocked yes)
			(layer "F.Fab")
			(hide yes)
			(effects
				(font
					(size 1.016 1.016)
					(thickness 0.1524)
				)
			)
		)
		(property "Device Type" "C402H22"
			(at 1.1811 -4.2291 270)
			(unlocked yes)
			(layer "F.Fab")
			(hide yes)
			(effects
				(font
					(size 1.016 1.016)
					(thickness 0.1524)
				)
			)
		)
		(duplicate_pad_numbers_are_jumpers no)
		(fp_rect
			(start -0.4318 0.9525)
			(end 0.4318 -0.9525)
			(stroke
				(width 0)
				(type default)
			)
			(fill no)
			(layer "F.CrtYd")
		)
		(fp_rect
			(start -0.4318 0.9525)
			(end 0.4318 -0.9525)
			(stroke
				(width 0)
				(type default)
			)
			(fill no)
			(layer "F.Fab")
		)
		(pad "1" smd custom
			(at 0 -0.4445 270)
			(size 0.1524 0.1524)
			(layers "F.Cu" "F.Mask" "F.Paste")
			(net "P3V3_STBY_LL_R")
			(options
				(clearance outline)
				(anchor circle)
			)
			(primitives
				(gr_poly
					(pts
						(arc
							(start 0.3048 -0.2032)
							(mid 0.275042 -0.275042)
							(end 0.2032 -0.3048)
						)
						(arc
							(start -0.2032 -0.3048)
							(mid -0.275042 -0.275042)
							(end -0.3048 -0.2032)
						)
						(arc
							(start -0.3048 0.2032)
							(mid -0.275042 0.275042)
							(end -0.2032 0.3048)
						)
						(arc
							(start 0.2032 0.3048)
							(mid 0.275042 0.275042)
							(end 0.3048 0.2032)
						)
					)
					(width 0)
					(fill yes)
				)
			)
		)
		(pad "2" smd custom
			(at 0 0.4445 270)
			(size 0.1524 0.1524)
			(layers "F.Cu" "F.Mask" "F.Paste")
			(net "P3V3_STBY_VFB")
			(options
				(clearance outline)
				(anchor circle)
			)
			(primitives
				(gr_poly
					(pts
						(arc
							(start 0.3048 -0.2032)
							(mid 0.275042 -0.275042)
							(end 0.2032 -0.3048)
						)
						(arc
							(start -0.2032 -0.3048)
							(mid -0.275042 -0.275042)
							(end -0.3048 -0.2032)
						)
						(arc
							(start -0.3048 0.2032)
							(mid -0.275042 0.275042)
							(end -0.2032 0.3048)
						)
						(arc
							(start 0.2032 0.3048)
							(mid 0.275042 0.275042)
							(end 0.3048 0.2032)
						)
					)
					(width 0)
					(fill yes)
				)
			)
		)
	)
	(footprint ""
		(layer "F.Cu")
		(at 224.934272 -81.366614)
		(property "Reference" "R622"
			(at 0 0 0)
			(layer "F.SilkS")
			(hide yes)
			(effects
				(font
					(size 1.27 1.27)
				)
			)
		)
		(property "Value" "150R2F-1-GP"
			(at 0.064008 -3.993896 0)
			(unlocked yes)
			(layer "F.Fab")
			(hide yes)
			(effects
				(font
					(size 1.016 1.016)
					(thickness 0.1524)
				)
			)
		)
		(property "Device Type" "R402H16"
			(at 0.064008 -5.517896 0)
			(unlocked yes)
			(layer "F.Fab")
			(hide yes)
			(effects
				(font
					(size 1.016 1.016)
					(thickness 0.1524)
				)
			)
		)
		(duplicate_pad_numbers_are_jumpers no)
		(fp_line
			(start -0.508 -0.9398)
			(end -0.508 0.9398)
			(stroke
				(width 0.1524)
				(type default)
			)
			(layer "F.SilkS")
		)
		(fp_line
			(start 0.508 -0.9398)
			(end -0.508 -0.9398)
			(stroke
				(width 0.1524)
				(type default)
			)
			(layer "F.SilkS")
		)
		(fp_rect
			(start -0.508 0.9398)
			(end 0.508 -0.9398)
			(stroke
				(width 0)
				(type default)
			)
			(fill no)
			(layer "F.CrtYd")
		)
		(fp_rect
			(start -0.508 0.9398)
			(end 0.508 -0.9398)
			(stroke
				(width 0)
				(type default)
			)
			(fill no)
			(layer "F.Fab")
		)
		(pad "1" smd custom
			(at 0 -0.4445)
			(size 0.1397 0.1397)
			(layers "F.Cu" "F.Mask" "F.Paste")
			(net "P3V3")
			(options
				(clearance outline)
				(anchor circle)
			)
			(primitives
				(gr_poly
					(pts
						(arc
							(start -0.1778 -0.2794)
							(mid -0.249642 -0.249642)
							(end -0.2794 -0.1778)
						)
						(arc
							(start -0.2794 0.1778)
							(mid -0.249642 0.249642)
							(end -0.1778 0.2794)
						)
						(arc
							(start 0.1778 0.2794)
							(mid 0.249642 0.249642)
							(end 0.2794 0.1778)
						)
						(arc
							(start 0.2794 -0.1778)
							(mid 0.249642 -0.249642)
							(end 0.1778 -0.2794)
						)
					)
					(width 0)
					(fill yes)
				)
			)
		)
		(pad "2" smd custom
			(at 0 0.4445)
			(size 0.1397 0.1397)
			(layers "F.Cu" "F.Mask" "F.Paste")
			(net "SYS_ERROR_LED_R")
			(options
				(clearance outline)
				(anchor circle)
			)
			(primitives
				(gr_poly
					(pts
						(arc
							(start -0.1778 -0.2794)
							(mid -0.249642 -0.249642)
							(end -0.2794 -0.1778)
						)
						(arc
							(start -0.2794 0.1778)
							(mid -0.249642 0.249642)
							(end -0.1778 0.2794)
						)
						(arc
							(start 0.1778 0.2794)
							(mid 0.249642 0.249642)
							(end 0.2794 0.1778)
						)
						(arc
							(start 0.2794 -0.1778)
							(mid 0.249642 -0.249642)
							(end 0.1778 -0.2794)
						)
					)
					(width 0)
					(fill yes)
				)
			)
		)
	)
	(footprint ""
		(layer "F.Cu")
		(at 62.015624 -156.333698)
		(property "Reference" "R335"
			(at 0 0 0)
			(layer "F.SilkS")
			(hide yes)
			(effects
				(font
					(size 1.27 1.27)
				)
			)
		)
		(property "Value" "0R2J-2-GP"
			(at 0.064008 -3.993896 0)
			(unlocked yes)
			(layer "F.Fab")
			(hide yes)
			(effects
				(font
					(size 1.016 1.016)
					(thickness 0.1524)
				)
			)
		)
		(property "Device Type" "R402H16"
			(at 0.064008 -5.517896 0)
			(unlocked yes)
			(layer "F.Fab")
			(hide yes)
			(effects
				(font
					(size 1.016 1.016)
					(thickness 0.1524)
				)
			)
		)
		(duplicate_pad_numbers_are_jumpers no)
		(fp_line
			(start -0.508 -0.9398)
			(end -0.508 0.9398)
			(stroke
				(width 0.1524)
				(type default)
			)
			(layer "F.SilkS")
		)
		(fp_line
			(start 0.508 -0.9398)
			(end -0.508 -0.9398)
			(stroke
				(width 0.1524)
				(type default)
			)
			(layer "F.SilkS")
		)
		(fp_rect
			(start -0.508 0.9398)
			(end 0.508 -0.9398)
			(stroke
				(width 0)
				(type default)
			)
			(fill no)
			(layer "F.CrtYd")
		)
		(fp_rect
			(start -0.508 0.9398)
			(end 0.508 -0.9398)
			(stroke
				(width 0)
				(type default)
			)
			(fill no)
			(layer "F.Fab")
		)
		(pad "1" smd custom
			(at 0 -0.4445)
			(size 0.1397 0.1397)
			(layers "F.Cu" "F.Mask" "F.Paste")
			(net "NCSI_TXD1")
			(options
				(clearance outline)
				(anchor circle)
			)
			(primitives
				(gr_poly
					(pts
						(arc
							(start -0.1778 -0.2794)
							(mid -0.249642 -0.249642)
							(end -0.2794 -0.1778)
						)
						(arc
							(start -0.2794 0.1778)
							(mid -0.249642 0.249642)
							(end -0.1778 0.2794)
						)
						(arc
							(start 0.1778 0.2794)
							(mid 0.249642 0.249642)
							(end 0.2794 0.1778)
						)
						(arc
							(start 0.2794 -0.1778)
							(mid 0.249642 -0.249642)
							(end 0.1778 -0.2794)
						)
					)
					(width 0)
					(fill yes)
				)
			)
		)
		(pad "2" smd custom
			(at 0 0.4445)
			(size 0.1397 0.1397)
			(layers "F.Cu" "F.Mask" "F.Paste")
			(net "NCSI_TXD1_R")
			(options
				(clearance outline)
				(anchor circle)
			)
			(primitives
				(gr_poly
					(pts
						(arc
							(start -0.1778 -0.2794)
							(mid -0.249642 -0.249642)
							(end -0.2794 -0.1778)
						)
						(arc
							(start -0.2794 0.1778)
							(mid -0.249642 0.249642)
							(end -0.1778 0.2794)
						)
						(arc
							(start 0.1778 0.2794)
							(mid 0.249642 0.249642)
							(end 0.2794 0.1778)
						)
						(arc
							(start 0.2794 -0.1778)
							(mid 0.249642 -0.249642)
							(end 0.1778 -0.2794)
						)
					)
					(width 0)
					(fill yes)
				)
			)
		)
	)
	(footprint ""
		(layer "F.Cu")
		(at 79.801974 -149.2885)
		(property "Reference" "R596"
			(at 0 0 0)
			(layer "F.SilkS")
			(hide yes)
			(effects
				(font
					(size 1.27 1.27)
				)
			)
		)
		(property "Value" "4K7R2F-GP"
			(at 0.064008 -3.993896 0)
			(unlocked yes)
			(layer "F.Fab")
			(hide yes)
			(effects
				(font
					(size 1.016 1.016)
					(thickness 0.1524)
				)
			)
		)
		(property "Device Type" "R402H16"
			(at 0.064008 -5.517896 0)
			(unlocked yes)
			(layer "F.Fab")
			(hide yes)
			(effects
				(font
					(size 1.016 1.016)
					(thickness 0.1524)
				)
			)
		)
		(duplicate_pad_numbers_are_jumpers no)
		(fp_line
			(start -0.508 -0.9398)
			(end -0.508 0.9398)
			(stroke
				(width 0.1524)
				(type default)
			)
			(layer "F.SilkS")
		)
		(fp_line
			(start 0.508 -0.9398)
			(end -0.508 -0.9398)
			(stroke
				(width 0.1524)
				(type default)
			)
			(layer "F.SilkS")
		)
		(fp_rect
			(start -0.508 0.9398)
			(end 0.508 -0.9398)
			(stroke
				(width 0)
				(type default)
			)
			(fill no)
			(layer "F.CrtYd")
		)
		(fp_rect
			(start -0.508 0.9398)
			(end 0.508 -0.9398)
			(stroke
				(width 0)
				(type default)
			)
			(fill no)
			(layer "F.Fab")
		)
		(pad "1" smd custom
			(at 0 -0.4445)
			(size 0.1397 0.1397)
			(layers "F.Cu" "F.Mask" "F.Paste")
			(net "COMP_TO_BMC_RESET_R")
			(options
				(clearance outline)
				(anchor circle)
			)
			(primitives
				(gr_poly
					(pts
						(arc
							(start -0.1778 -0.2794)
							(mid -0.249642 -0.249642)
							(end -0.2794 -0.1778)
						)
						(arc
							(start -0.2794 0.1778)
							(mid -0.249642 0.249642)
							(end -0.1778 0.2794)
						)
						(arc
							(start 0.1778 0.2794)
							(mid 0.249642 0.249642)
							(end 0.2794 0.1778)
						)
						(arc
							(start 0.2794 -0.1778)
							(mid 0.249642 -0.249642)
							(end 0.1778 -0.2794)
						)
					)
					(width 0)
					(fill yes)
				)
			)
		)
		(pad "2" smd custom
			(at 0 0.4445)
			(size 0.1397 0.1397)
			(layers "F.Cu" "F.Mask" "F.Paste")
			(net "GND")
			(options
				(clearance outline)
				(anchor circle)
			)
			(primitives
				(gr_poly
					(pts
						(arc
							(start -0.1778 -0.2794)
							(mid -0.249642 -0.249642)
							(end -0.2794 -0.1778)
						)
						(arc
							(start -0.2794 0.1778)
							(mid -0.249642 0.249642)
							(end -0.1778 0.2794)
						)
						(arc
							(start 0.1778 0.2794)
							(mid 0.249642 0.249642)
							(end 0.2794 0.1778)
						)
						(arc
							(start 0.2794 -0.1778)
							(mid 0.249642 -0.249642)
							(end 0.1778 -0.2794)
						)
					)
					(width 0)
					(fill yes)
				)
			)
		)
	)
	(footprint ""
		(layer "F.Cu")
		(at 209.302096 -10.668 -90)
		(property "Reference" "R745"
			(at 0 0 270)
			(layer "F.SilkS")
			(hide yes)
			(effects
				(font
					(size 1.27 1.27)
				)
			)
		)
		(property "Value" "120R3F-L-GP"
			(at -0.0254 -2.5146 270)
			(unlocked yes)
			(layer "F.Fab")
			(hide yes)
			(effects
				(font
					(size 1.016 1.016)
					(thickness 0.1524)
				)
			)
		)
		(property "Device Type" "R603H22"
			(at -0.0254 -4.0386 270)
			(unlocked yes)
			(layer "F.Fab")
			(hide yes)
			(effects
				(font
					(size 1.016 1.016)
					(thickness 0.1524)
				)
			)
		)
		(duplicate_pad_numbers_are_jumpers no)
		(fp_line
			(start -0.4826 0)
			(end -0.2032 0)
			(stroke
				(width 0.2032)
				(type default)
			)
			(layer "F.SilkS")
		)
		(fp_line
			(start 0.2032 0)
			(end 0.4826 0)
			(stroke
				(width 0.2032)
				(type default)
			)
			(layer "F.SilkS")
		)
		(fp_rect
			(start -0.5842 1.3335)
			(end 0.5842 -1.3335)
			(stroke
				(width 0)
				(type default)
			)
			(fill no)
			(layer "F.CrtYd")
		)
		(fp_rect
			(start -0.5842 1.3335)
			(end 0.5842 -1.3335)
			(stroke
				(width 0)
				(type default)
			)
			(fill no)
			(layer "F.Fab")
		)
		(pad "1" smd custom
			(at 0 -0.762 270)
			(size 0.2159 0.2159)
			(layers "F.Cu" "F.Mask" "F.Paste")
			(net "ML_PWR_YELLOW_LED")
			(options
				(clearance outline)
				(anchor circle)
			)
			(primitives
				(gr_poly
					(pts
						(arc
							(start -0.3302 -0.4318)
							(mid -0.402042 -0.402042)
							(end -0.4318 -0.3302)
						)
						(arc
							(start -0.4318 0.3302)
							(mid -0.402042 0.402042)
							(end -0.3302 0.4318)
						)
						(arc
							(start 0.3302 0.4318)
							(mid 0.402042 0.402042)
							(end 0.4318 0.3302)
						)
						(arc
							(start 0.4318 -0.3302)
							(mid 0.402042 -0.402042)
							(end 0.3302 -0.4318)
						)
					)
					(width 0)
					(fill yes)
				)
			)
		)
		(pad "2" smd custom
			(at 0 0.762 270)
			(size 0.2159 0.2159)
			(layers "F.Cu" "F.Mask" "F.Paste")
			(net "ML_PWR_YELLOW_LED_R")
			(options
				(clearance outline)
				(anchor circle)
			)
			(primitives
				(gr_poly
					(pts
						(arc
							(start -0.3302 -0.4318)
							(mid -0.402042 -0.402042)
							(end -0.4318 -0.3302)
						)
						(arc
							(start -0.4318 0.3302)
							(mid -0.402042 0.402042)
							(end -0.3302 0.4318)
						)
						(arc
							(start 0.3302 0.4318)
							(mid 0.402042 0.402042)
							(end 0.4318 0.3302)
						)
						(arc
							(start 0.4318 -0.3302)
							(mid 0.402042 -0.402042)
							(end 0.3302 -0.4318)
						)
					)
					(width 0)
					(fill yes)
				)
			)
		)
	)
	(footprint ""
		(layer "F.Cu")
		(at 90.50782 -122.31878 90)
		(property "Reference" "R796"
			(at 0 0 90)
			(layer "F.SilkS")
			(hide yes)
			(effects
				(font
					(size 1.27 1.27)
				)
			)
		)
		(property "Value" "0R2J-2-GP"
			(at 0.064008 -3.993896 90)
			(unlocked yes)
			(layer "F.Fab")
			(hide yes)
			(effects
				(font
					(size 1.016 1.016)
					(thickness 0.1524)
				)
			)
		)
		(property "Device Type" "R402H16"
			(at 0.064008 -5.517896 90)
			(unlocked yes)
			(layer "F.Fab")
			(hide yes)
			(effects
				(font
					(size 1.016 1.016)
					(thickness 0.1524)
				)
			)
		)
		(duplicate_pad_numbers_are_jumpers no)
		(fp_line
			(start 0.508 -0.9398)
			(end -0.508 -0.9398)
			(stroke
				(width 0.1524)
				(type default)
			)
			(layer "F.SilkS")
		)
		(fp_line
			(start -0.508 -0.9398)
			(end -0.508 0.9398)
			(stroke
				(width 0.1524)
				(type default)
			)
			(layer "F.SilkS")
		)
		(fp_rect
			(start -0.508 0.9398)
			(end 0.508 -0.9398)
			(stroke
				(width 0)
				(type default)
			)
			(fill no)
			(layer "F.CrtYd")
		)
		(fp_rect
			(start -0.508 0.9398)
			(end 0.508 -0.9398)
			(stroke
				(width 0)
				(type default)
			)
			(fill no)
			(layer "F.Fab")
		)
		(pad "1" smd custom
			(at 0 -0.4445 90)
			(size 0.1397 0.1397)
			(layers "F.Cu" "F.Mask" "F.Paste")
			(net "UART_COMP_IN_RX")
			(options
				(clearance outline)
				(anchor circle)
			)
			(primitives
				(gr_poly
					(pts
						(arc
							(start -0.1778 -0.2794)
							(mid -0.249642 -0.249642)
							(end -0.2794 -0.1778)
						)
						(arc
							(start -0.2794 0.1778)
							(mid -0.249642 0.249642)
							(end -0.1778 0.2794)
						)
						(arc
							(start 0.1778 0.2794)
							(mid 0.249642 0.249642)
							(end 0.2794 0.1778)
						)
						(arc
							(start 0.2794 -0.1778)
							(mid 0.249642 -0.249642)
							(end 0.1778 -0.2794)
						)
					)
					(width 0)
					(fill yes)
				)
			)
		)
		(pad "2" smd custom
			(at 0 0.4445 90)
			(size 0.1397 0.1397)
			(layers "F.Cu" "F.Mask" "F.Paste")
			(net "UART_COMP_IN_R_RX")
			(options
				(clearance outline)
				(anchor circle)
			)
			(primitives
				(gr_poly
					(pts
						(arc
							(start -0.1778 -0.2794)
							(mid -0.249642 -0.249642)
							(end -0.2794 -0.1778)
						)
						(arc
							(start -0.2794 0.1778)
							(mid -0.249642 0.249642)
							(end -0.1778 0.2794)
						)
						(arc
							(start 0.1778 0.2794)
							(mid 0.249642 0.249642)
							(end 0.2794 0.1778)
						)
						(arc
							(start 0.2794 -0.1778)
							(mid 0.249642 -0.249642)
							(end 0.1778 -0.2794)
						)
					)
					(width 0)
					(fill yes)
				)
			)
		)
	)
	(footprint ""
		(layer "F.Cu")
		(at 205.1558 -121.2088 -90)
		(property "Reference" "C246"
			(at 0 0 270)
			(layer "F.SilkS")
			(hide yes)
			(effects
				(font
					(size 1.27 1.27)
				)
			)
		)
		(property "Value" "SC1KP50V2KX-1GP"
			(at 1.1811 -2.7051 270)
			(unlocked yes)
			(layer "F.Fab")
			(hide yes)
			(effects
				(font
					(size 1.016 1.016)
					(thickness 0.1524)
				)
			)
		)
		(property "Device Type" "C402H22"
			(at 1.1811 -4.2291 270)
			(unlocked yes)
			(layer "F.Fab")
			(hide yes)
			(effects
				(font
					(size 1.016 1.016)
					(thickness 0.1524)
				)
			)
		)
		(duplicate_pad_numbers_are_jumpers no)
		(fp_rect
			(start -0.4318 0.9525)
			(end 0.4318 -0.9525)
			(stroke
				(width 0)
				(type default)
			)
			(fill no)
			(layer "F.CrtYd")
		)
		(fp_rect
			(start -0.4318 0.9525)
			(end 0.4318 -0.9525)
			(stroke
				(width 0)
				(type default)
			)
			(fill no)
			(layer "F.Fab")
		)
		(pad "1" smd custom
			(at 0 -0.4445 270)
			(size 0.1524 0.1524)
			(layers "F.Cu" "F.Mask" "F.Paste")
			(net "P1V5_OUT")
			(options
				(clearance outline)
				(anchor circle)
			)
			(primitives
				(gr_poly
					(pts
						(arc
							(start 0.3048 -0.2032)
							(mid 0.275042 -0.275042)
							(end 0.2032 -0.3048)
						)
						(arc
							(start -0.2032 -0.3048)
							(mid -0.275042 -0.275042)
							(end -0.3048 -0.2032)
						)
						(arc
							(start -0.3048 0.2032)
							(mid -0.275042 0.275042)
							(end -0.2032 0.3048)
						)
						(arc
							(start 0.2032 0.3048)
							(mid 0.275042 0.275042)
							(end 0.3048 0.2032)
						)
					)
					(width 0)
					(fill yes)
				)
			)
		)
		(pad "2" smd custom
			(at 0 0.4445 270)
			(size 0.1524 0.1524)
			(layers "F.Cu" "F.Mask" "F.Paste")
			(net "TPS74801_P1V5_FB")
			(options
				(clearance outline)
				(anchor circle)
			)
			(primitives
				(gr_poly
					(pts
						(arc
							(start 0.3048 -0.2032)
							(mid 0.275042 -0.275042)
							(end 0.2032 -0.3048)
						)
						(arc
							(start -0.2032 -0.3048)
							(mid -0.275042 -0.275042)
							(end -0.3048 -0.2032)
						)
						(arc
							(start -0.3048 0.2032)
							(mid -0.275042 0.275042)
							(end -0.2032 0.3048)
						)
						(arc
							(start 0.2032 0.3048)
							(mid 0.275042 0.275042)
							(end 0.3048 0.2032)
						)
					)
					(width 0)
					(fill yes)
				)
			)
		)
	)
	(footprint ""
		(layer "F.Cu")
		(at 164.3634 -137.2362 90)
		(property "Reference" "C202"
			(at 0 0 90)
			(layer "F.SilkS")
			(hide yes)
			(effects
				(font
					(size 1.27 1.27)
				)
			)
		)
		(property "Value" "SC1U16V3KX-5GP"
			(at 0 -2.8194 90)
			(unlocked yes)
			(layer "F.Fab")
			(hide yes)
			(effects
				(font
					(size 1.016 1.016)
					(thickness 0.1524)
				)
			)
		)
		(property "Device Type" "C603H36"
			(at 0 -4.3434 90)
			(unlocked yes)
			(layer "F.Fab")
			(hide yes)
			(effects
				(font
					(size 1.016 1.016)
					(thickness 0.1524)
				)
			)
		)
		(duplicate_pad_numbers_are_jumpers no)
		(fp_line
			(start 0.508 0)
			(end -0.508 0)
			(stroke
				(width 0.2032)
				(type default)
			)
			(layer "F.SilkS")
		)
		(fp_rect
			(start -0.5842 1.3335)
			(end 0.5842 -1.3335)
			(stroke
				(width 0)
				(type default)
			)
			(fill no)
			(layer "F.CrtYd")
		)
		(fp_rect
			(start -0.5842 1.3335)
			(end 0.5842 -1.3335)
			(stroke
				(width 0)
				(type default)
			)
			(fill no)
			(layer "F.Fab")
		)
		(pad "1" smd custom
			(at 0 -0.762 90)
			(size 0.2159 0.2159)
			(layers "F.Cu" "F.Mask" "F.Paste")
			(net "P12V_STBY_VCC_PU4")
			(options
				(clearance outline)
				(anchor circle)
			)
			(primitives
				(gr_poly
					(pts
						(arc
							(start -0.3302 -0.4318)
							(mid -0.402042 -0.402042)
							(end -0.4318 -0.3302)
						)
						(arc
							(start -0.4318 0.3302)
							(mid -0.402042 0.402042)
							(end -0.3302 0.4318)
						)
						(arc
							(start 0.3302 0.4318)
							(mid 0.402042 0.402042)
							(end 0.4318 0.3302)
						)
						(arc
							(start 0.4318 -0.3302)
							(mid 0.402042 -0.402042)
							(end 0.3302 -0.4318)
						)
					)
					(width 0)
					(fill yes)
				)
			)
		)
		(pad "2" smd custom
			(at 0 0.762 90)
			(size 0.2159 0.2159)
			(layers "F.Cu" "F.Mask" "F.Paste")
			(net "GND")
			(options
				(clearance outline)
				(anchor circle)
			)
			(primitives
				(gr_poly
					(pts
						(arc
							(start -0.3302 -0.4318)
							(mid -0.402042 -0.402042)
							(end -0.4318 -0.3302)
						)
						(arc
							(start -0.4318 0.3302)
							(mid -0.402042 0.402042)
							(end -0.3302 0.4318)
						)
						(arc
							(start 0.3302 0.4318)
							(mid 0.402042 0.402042)
							(end 0.4318 0.3302)
						)
						(arc
							(start 0.4318 -0.3302)
							(mid 0.402042 -0.402042)
							(end 0.3302 -0.4318)
						)
					)
					(width 0)
					(fill yes)
				)
			)
		)
	)
	(footprint ""
		(layer "F.Cu")
		(at 84.87791 -137.060686 -90)
		(property "Reference" "R105"
			(at 0 0 270)
			(layer "F.SilkS")
			(hide yes)
			(effects
				(font
					(size 1.27 1.27)
				)
			)
		)
		(property "Value" "4K7R2F-GP"
			(at 0.064008 -3.993896 270)
			(unlocked yes)
			(layer "F.Fab")
			(hide yes)
			(effects
				(font
					(size 1.016 1.016)
					(thickness 0.1524)
				)
			)
		)
		(property "Device Type" "R402H16"
			(at 0.064008 -5.517896 270)
			(unlocked yes)
			(layer "F.Fab")
			(hide yes)
			(effects
				(font
					(size 1.016 1.016)
					(thickness 0.1524)
				)
			)
		)
		(duplicate_pad_numbers_are_jumpers no)
		(fp_line
			(start -0.508 -0.9398)
			(end -0.508 0.9398)
			(stroke
				(width 0.1524)
				(type default)
			)
			(layer "F.SilkS")
		)
		(fp_line
			(start 0.508 -0.9398)
			(end -0.508 -0.9398)
			(stroke
				(width 0.1524)
				(type default)
			)
			(layer "F.SilkS")
		)
		(fp_rect
			(start -0.508 0.9398)
			(end 0.508 -0.9398)
			(stroke
				(width 0)
				(type default)
			)
			(fill no)
			(layer "F.CrtYd")
		)
		(fp_rect
			(start -0.508 0.9398)
			(end 0.508 -0.9398)
			(stroke
				(width 0)
				(type default)
			)
			(fill no)
			(layer "F.Fab")
		)
		(pad "1" smd custom
			(at 0 -0.4445 270)
			(size 0.1397 0.1397)
			(layers "F.Cu" "F.Mask" "F.Paste")
			(net "P3V3_STBY")
			(options
				(clearance outline)
				(anchor circle)
			)
			(primitives
				(gr_poly
					(pts
						(arc
							(start -0.1778 -0.2794)
							(mid -0.249642 -0.249642)
							(end -0.2794 -0.1778)
						)
						(arc
							(start -0.2794 0.1778)
							(mid -0.249642 0.249642)
							(end -0.1778 0.2794)
						)
						(arc
							(start 0.1778 0.2794)
							(mid 0.249642 0.249642)
							(end 0.2794 0.1778)
						)
						(arc
							(start 0.2794 -0.1778)
							(mid 0.249642 -0.249642)
							(end 0.1778 -0.2794)
						)
					)
					(width 0)
					(fill yes)
				)
			)
		)
		(pad "2" smd custom
			(at 0 0.4445 270)
			(size 0.1397 0.1397)
			(layers "F.Cu" "F.Mask" "F.Paste")
			(net "D_FLIP_CLR#")
			(options
				(clearance outline)
				(anchor circle)
			)
			(primitives
				(gr_poly
					(pts
						(arc
							(start -0.1778 -0.2794)
							(mid -0.249642 -0.249642)
							(end -0.2794 -0.1778)
						)
						(arc
							(start -0.2794 0.1778)
							(mid -0.249642 0.249642)
							(end -0.1778 0.2794)
						)
						(arc
							(start 0.1778 0.2794)
							(mid 0.249642 0.249642)
							(end 0.2794 0.1778)
						)
						(arc
							(start 0.2794 -0.1778)
							(mid 0.249642 -0.249642)
							(end 0.1778 -0.2794)
						)
					)
					(width 0)
					(fill yes)
				)
			)
		)
	)
	(footprint ""
		(layer "F.Cu")
		(at 49.09439 -158.1912)
		(property "Reference" "R168"
			(at 0 0 0)
			(layer "F.SilkS")
			(hide yes)
			(effects
				(font
					(size 1.27 1.27)
				)
			)
		)
		(property "Value" "0R2J-2-GP"
			(at 0.064008 -3.993896 0)
			(unlocked yes)
			(layer "F.Fab")
			(hide yes)
			(effects
				(font
					(size 1.016 1.016)
					(thickness 0.1524)
				)
			)
		)
		(property "Device Type" "R402H16"
			(at 0.064008 -5.517896 0)
			(unlocked yes)
			(layer "F.Fab")
			(hide yes)
			(effects
				(font
					(size 1.016 1.016)
					(thickness 0.1524)
				)
			)
		)
		(duplicate_pad_numbers_are_jumpers no)
		(fp_line
			(start -0.508 -0.9398)
			(end -0.508 0.9398)
			(stroke
				(width 0.1524)
				(type default)
			)
			(layer "F.SilkS")
		)
		(fp_line
			(start 0.508 -0.9398)
			(end -0.508 -0.9398)
			(stroke
				(width 0.1524)
				(type default)
			)
			(layer "F.SilkS")
		)
		(fp_rect
			(start -0.508 0.9398)
			(end 0.508 -0.9398)
			(stroke
				(width 0)
				(type default)
			)
			(fill no)
			(layer "F.CrtYd")
		)
		(fp_rect
			(start -0.508 0.9398)
			(end 0.508 -0.9398)
			(stroke
				(width 0)
				(type default)
			)
			(fill no)
			(layer "F.Fab")
		)
		(pad "1" smd custom
			(at 0 -0.4445)
			(size 0.1397 0.1397)
			(layers "F.Cu" "F.Mask" "F.Paste")
			(net "I2C_DPB_MISC_SCL_OUT")
			(options
				(clearance outline)
				(anchor circle)
			)
			(primitives
				(gr_poly
					(pts
						(arc
							(start -0.1778 -0.2794)
							(mid -0.249642 -0.249642)
							(end -0.2794 -0.1778)
						)
						(arc
							(start -0.2794 0.1778)
							(mid -0.249642 0.249642)
							(end -0.1778 0.2794)
						)
						(arc
							(start 0.1778 0.2794)
							(mid 0.249642 0.249642)
							(end 0.2794 0.1778)
						)
						(arc
							(start 0.2794 -0.1778)
							(mid 0.249642 -0.249642)
							(end 0.1778 -0.2794)
						)
					)
					(width 0)
					(fill yes)
				)
			)
		)
		(pad "2" smd custom
			(at 0 0.4445)
			(size 0.1397 0.1397)
			(layers "F.Cu" "F.Mask" "F.Paste")
			(net "BMC_SMB6_CLK")
			(options
				(clearance outline)
				(anchor circle)
			)
			(primitives
				(gr_poly
					(pts
						(arc
							(start -0.1778 -0.2794)
							(mid -0.249642 -0.249642)
							(end -0.2794 -0.1778)
						)
						(arc
							(start -0.2794 0.1778)
							(mid -0.249642 0.249642)
							(end -0.1778 0.2794)
						)
						(arc
							(start 0.1778 0.2794)
							(mid 0.249642 0.249642)
							(end 0.2794 0.1778)
						)
						(arc
							(start 0.2794 -0.1778)
							(mid 0.249642 -0.249642)
							(end 0.1778 -0.2794)
						)
					)
					(width 0)
					(fill yes)
				)
			)
		)
	)
	(footprint ""
		(layer "F.Cu")
		(at 203.3524 -48.2854 180)
		(property "Reference" "R631"
			(at 0 0 180)
			(layer "F.SilkS")
			(hide yes)
			(effects
				(font
					(size 1.27 1.27)
				)
			)
		)
		(property "Value" "4K7R2F-GP"
			(at 0.064008 -3.993896 180)
			(unlocked yes)
			(layer "F.Fab")
			(hide yes)
			(effects
				(font
					(size 1.016 1.016)
					(thickness 0.1524)
				)
			)
		)
		(property "Device Type" "R402H16"
			(at 0.064008 -5.517896 180)
			(unlocked yes)
			(layer "F.Fab")
			(hide yes)
			(effects
				(font
					(size 1.016 1.016)
					(thickness 0.1524)
				)
			)
		)
		(duplicate_pad_numbers_are_jumpers no)
		(fp_line
			(start 0.508 -0.9398)
			(end -0.508 -0.9398)
			(stroke
				(width 0.1524)
				(type default)
			)
			(layer "F.SilkS")
		)
		(fp_line
			(start -0.508 -0.9398)
			(end -0.508 0.9398)
			(stroke
				(width 0.1524)
				(type default)
			)
			(layer "F.SilkS")
		)
		(fp_rect
			(start -0.508 0.9398)
			(end 0.508 -0.9398)
			(stroke
				(width 0)
				(type default)
			)
			(fill no)
			(layer "F.CrtYd")
		)
		(fp_rect
			(start -0.508 0.9398)
			(end 0.508 -0.9398)
			(stroke
				(width 0)
				(type default)
			)
			(fill no)
			(layer "F.Fab")
		)
		(pad "1" smd custom
			(at 0 -0.4445 180)
			(size 0.1397 0.1397)
			(layers "F.Cu" "F.Mask" "F.Paste")
			(net "P1V8")
			(options
				(clearance outline)
				(anchor circle)
			)
			(primitives
				(gr_poly
					(pts
						(arc
							(start -0.1778 -0.2794)
							(mid -0.249642 -0.249642)
							(end -0.2794 -0.1778)
						)
						(arc
							(start -0.2794 0.1778)
							(mid -0.249642 0.249642)
							(end -0.1778 0.2794)
						)
						(arc
							(start 0.1778 0.2794)
							(mid 0.249642 0.249642)
							(end 0.2794 0.1778)
						)
						(arc
							(start 0.2794 -0.1778)
							(mid 0.249642 -0.249642)
							(end 0.1778 -0.2794)
						)
					)
					(width 0)
					(fill yes)
				)
			)
		)
		(pad "2" smd custom
			(at 0 0.4445 180)
			(size 0.1397 0.1397)
			(layers "F.Cu" "F.Mask" "F.Paste")
			(net "ICE1_TMS")
			(options
				(clearance outline)
				(anchor circle)
			)
			(primitives
				(gr_poly
					(pts
						(arc
							(start -0.1778 -0.2794)
							(mid -0.249642 -0.249642)
							(end -0.2794 -0.1778)
						)
						(arc
							(start -0.2794 0.1778)
							(mid -0.249642 0.249642)
							(end -0.1778 0.2794)
						)
						(arc
							(start 0.1778 0.2794)
							(mid 0.249642 0.249642)
							(end 0.2794 0.1778)
						)
						(arc
							(start 0.2794 -0.1778)
							(mid 0.249642 -0.249642)
							(end 0.1778 -0.2794)
						)
					)
					(width 0)
					(fill yes)
				)
			)
		)
	)
	(footprint ""
		(layer "F.Cu")
		(at 84.438744 -160.351216 180)
		(property "Reference" "C237"
			(at 0 0 180)
			(layer "F.SilkS")
			(hide yes)
			(effects
				(font
					(size 1.27 1.27)
				)
			)
		)
		(property "Value" "SC10U6D3V5KX-4GP"
			(at -0.0762 -6.1214 180)
			(unlocked yes)
			(layer "F.Fab")
			(hide yes)
			(effects
				(font
					(size 1.016 1.016)
					(thickness 0.1524)
				)
			)
		)
		(property "Device Type" "C805H58"
			(at -0.0762 -8.1534 180)
			(unlocked yes)
			(layer "F.Fab")
			(hide yes)
			(effects
				(font
					(size 1.016 1.016)
					(thickness 0.1524)
				)
			)
		)
		(duplicate_pad_numbers_are_jumpers no)
		(fp_line
			(start 0.635 0)
			(end -0.635 0)
			(stroke
				(width 0.508)
				(type default)
			)
			(layer "F.SilkS")
		)
		(fp_rect
			(start -0.9652 1.778)
			(end 0.9652 -1.778)
			(stroke
				(width 0)
				(type default)
			)
			(fill no)
			(layer "F.CrtYd")
		)
		(fp_poly
			(pts
				(xy -0.9652 -1.778) (xy 0.9652 -1.778) (xy 0.9652 1.778) (xy -0.9652 1.778)
			)
			(stroke
				(width 0)
				(type default)
			)
			(fill no)
			(layer "F.Fab")
		)
		(pad "1" smd rect
			(at 0 -0.9652 180)
			(size 1.397 1.143)
			(layers "F.Cu" "F.Mask" "F.Paste")
			(net "TPS74801_P1V15_STBY_OUT")
		)
		(pad "2" smd rect
			(at 0 0.9652 180)
			(size 1.397 1.143)
			(layers "F.Cu" "F.Mask" "F.Paste")
			(net "GND")
		)
	)
	(footprint ""
		(layer "F.Cu")
		(at 36.068 -130.5052 180)
		(property "Reference" "R308"
			(at 0 0 180)
			(layer "F.SilkS")
			(hide yes)
			(effects
				(font
					(size 1.27 1.27)
				)
			)
		)
		(property "Value" "4K7R2F-GP"
			(at 0.064008 -3.993896 180)
			(unlocked yes)
			(layer "F.Fab")
			(hide yes)
			(effects
				(font
					(size 1.016 1.016)
					(thickness 0.1524)
				)
			)
		)
		(property "Device Type" "R402H16"
			(at 0.064008 -5.517896 180)
			(unlocked yes)
			(layer "F.Fab")
			(hide yes)
			(effects
				(font
					(size 1.016 1.016)
					(thickness 0.1524)
				)
			)
		)
		(duplicate_pad_numbers_are_jumpers no)
		(fp_line
			(start 0.508 -0.9398)
			(end -0.508 -0.9398)
			(stroke
				(width 0.1524)
				(type default)
			)
			(layer "F.SilkS")
		)
		(fp_line
			(start -0.508 -0.9398)
			(end -0.508 0.9398)
			(stroke
				(width 0.1524)
				(type default)
			)
			(layer "F.SilkS")
		)
		(fp_rect
			(start -0.508 0.9398)
			(end 0.508 -0.9398)
			(stroke
				(width 0)
				(type default)
			)
			(fill no)
			(layer "F.CrtYd")
		)
		(fp_rect
			(start -0.508 0.9398)
			(end 0.508 -0.9398)
			(stroke
				(width 0)
				(type default)
			)
			(fill no)
			(layer "F.Fab")
		)
		(pad "1" smd custom
			(at 0 -0.4445 180)
			(size 0.1397 0.1397)
			(layers "F.Cu" "F.Mask" "F.Paste")
			(net "P3V3_STBY")
			(options
				(clearance outline)
				(anchor circle)
			)
			(primitives
				(gr_poly
					(pts
						(arc
							(start -0.1778 -0.2794)
							(mid -0.249642 -0.249642)
							(end -0.2794 -0.1778)
						)
						(arc
							(start -0.2794 0.1778)
							(mid -0.249642 0.249642)
							(end -0.1778 0.2794)
						)
						(arc
							(start 0.1778 0.2794)
							(mid 0.249642 0.249642)
							(end 0.2794 0.1778)
						)
						(arc
							(start 0.2794 -0.1778)
							(mid 0.249642 -0.249642)
							(end 0.1778 -0.2794)
						)
					)
					(width 0)
					(fill yes)
				)
			)
		)
		(pad "2" smd custom
			(at 0 0.4445 180)
			(size 0.1397 0.1397)
			(layers "F.Cu" "F.Mask" "F.Paste")
			(net "OSC_OE")
			(options
				(clearance outline)
				(anchor circle)
			)
			(primitives
				(gr_poly
					(pts
						(arc
							(start -0.1778 -0.2794)
							(mid -0.249642 -0.249642)
							(end -0.2794 -0.1778)
						)
						(arc
							(start -0.2794 0.1778)
							(mid -0.249642 0.249642)
							(end -0.1778 0.2794)
						)
						(arc
							(start 0.1778 0.2794)
							(mid 0.249642 0.249642)
							(end 0.2794 0.1778)
						)
						(arc
							(start 0.2794 -0.1778)
							(mid 0.249642 -0.249642)
							(end 0.1778 -0.2794)
						)
					)
					(width 0)
					(fill yes)
				)
			)
		)
	)
	(footprint ""
		(layer "F.Cu")
		(at 75.3364 -133.2865 -90)
		(property "Reference" "C513"
			(at 0 0 270)
			(layer "F.SilkS")
			(hide yes)
			(effects
				(font
					(size 1.27 1.27)
				)
			)
		)
		(property "Value" "SCD1U16V2KX-3GP"
			(at 1.1811 -2.7051 270)
			(unlocked yes)
			(layer "F.Fab")
			(hide yes)
			(effects
				(font
					(size 1.016 1.016)
					(thickness 0.1524)
				)
			)
		)
		(property "Device Type" "C402H22"
			(at 1.1811 -4.2291 270)
			(unlocked yes)
			(layer "F.Fab")
			(hide yes)
			(effects
				(font
					(size 1.016 1.016)
					(thickness 0.1524)
				)
			)
		)
		(duplicate_pad_numbers_are_jumpers no)
		(fp_rect
			(start -0.4318 0.9525)
			(end 0.4318 -0.9525)
			(stroke
				(width 0)
				(type default)
			)
			(fill no)
			(layer "F.CrtYd")
		)
		(fp_rect
			(start -0.4318 0.9525)
			(end 0.4318 -0.9525)
			(stroke
				(width 0)
				(type default)
			)
			(fill no)
			(layer "F.Fab")
		)
		(pad "1" smd custom
			(at 0 -0.4445 270)
			(size 0.1524 0.1524)
			(layers "F.Cu" "F.Mask" "F.Paste")
			(net "P3V3_STBY")
			(options
				(clearance outline)
				(anchor circle)
			)
			(primitives
				(gr_poly
					(pts
						(arc
							(start 0.3048 -0.2032)
							(mid 0.275042 -0.275042)
							(end 0.2032 -0.3048)
						)
						(arc
							(start -0.2032 -0.3048)
							(mid -0.275042 -0.275042)
							(end -0.3048 -0.2032)
						)
						(arc
							(start -0.3048 0.2032)
							(mid -0.275042 0.275042)
							(end -0.2032 0.3048)
						)
						(arc
							(start 0.2032 0.3048)
							(mid 0.275042 0.275042)
							(end 0.3048 0.2032)
						)
					)
					(width 0)
					(fill yes)
				)
			)
		)
		(pad "2" smd custom
			(at 0 0.4445 270)
			(size 0.1524 0.1524)
			(layers "F.Cu" "F.Mask" "F.Paste")
			(net "GND")
			(options
				(clearance outline)
				(anchor circle)
			)
			(primitives
				(gr_poly
					(pts
						(arc
							(start 0.3048 -0.2032)
							(mid 0.275042 -0.275042)
							(end 0.2032 -0.3048)
						)
						(arc
							(start -0.2032 -0.3048)
							(mid -0.275042 -0.275042)
							(end -0.3048 -0.2032)
						)
						(arc
							(start -0.3048 0.2032)
							(mid -0.275042 0.275042)
							(end -0.2032 0.3048)
						)
						(arc
							(start 0.2032 0.3048)
							(mid 0.275042 0.275042)
							(end 0.3048 0.2032)
						)
					)
					(width 0)
					(fill yes)
				)
			)
		)
	)
	(footprint ""
		(layer "F.Cu")
		(at 214.63 -69.088 -45)
		(property "Reference" "VIA45"
			(at 0 0 315)
			(layer "F.SilkS")
			(hide yes)
			(effects
				(font
					(size 1.27 1.27)
				)
			)
		)
		(property "Value" "100OHM-8L-1D6MM-L18L16-GP"
			(at -3.721059 -4.508373 315)
			(unlocked yes)
			(layer "F.Fab")
			(hide yes)
			(effects
				(font
					(size 1.016 1.016)
					(thickness 0.1524)
				)
			)
		)
		(property "Device Type" "VIA-PCIE-4P-394076"
			(at -3.721059 -6.032502 315)
			(unlocked yes)
			(layer "F.Fab")
			(hide yes)
			(effects
				(font
					(size 1.016 1.016)
					(thickness 0.1524)
				)
			)
		)
		(duplicate_pad_numbers_are_jumpers no)
		(fp_poly
			(pts
				(xy -1.968472 -0.380877) (xy 1.968528 -0.380878) (xy 1.968527 0.381122) (xy -1.968472 0.381122)
			)
			(stroke
				(width 0)
				(type default)
			)
			(fill no)
			(layer "F.CrtYd")
		)
		(fp_poly
			(pts
				(xy -1.968472 -0.380877) (xy 1.968528 -0.380878) (xy 1.968527 0.381122) (xy -1.968472 0.381122)
			)
			(stroke
				(width 0)
				(type default)
			)
			(fill no)
			(layer "F.Fab")
		)
		(pad "1" thru_hole circle
			(at -1.5875 0 315)
			(size 0.508 0.508)
			(drill 0.254)
			(layers "*.Cu" "*.Mask")
			(remove_unused_layers no)
			(net "GND")
			(clearance 0.127)
			(thermal_gap 0.127)
		)
		(pad "2" thru_hole circle
			(at -0.571501 0 315)
			(size 0.508 0.508)
			(drill 0.254)
			(layers "*.Cu" "*.Mask")
			(remove_unused_layers no)
			(net "PHY_IOC_TO_CON_B_0_DP")
			(clearance 0.127)
			(thermal_gap 0.127)
		)
		(pad "3" thru_hole circle
			(at 0.571501 0 315)
			(size 0.508 0.508)
			(drill 0.254)
			(layers "*.Cu" "*.Mask")
			(remove_unused_layers no)
			(net "PHY_IOC_TO_CON_B_0_DN")
			(clearance 0.127)
			(thermal_gap 0.127)
		)
		(pad "4" thru_hole circle
			(at 1.5875 0 315)
			(size 0.508 0.508)
			(drill 0.254)
			(layers "*.Cu" "*.Mask")
			(remove_unused_layers no)
			(net "GND")
			(clearance 0.127)
			(thermal_gap 0.127)
		)
	)
	(footprint ""
		(layer "F.Cu")
		(at 81.65338 -178.453796 180)
		(property "Reference" "C192"
			(at 0 0 180)
			(layer "F.SilkS")
			(hide yes)
			(effects
				(font
					(size 1.27 1.27)
				)
			)
		)
		(property "Value" "SC10U6D3V5KX-4GP"
			(at -0.0762 -6.1214 180)
			(unlocked yes)
			(layer "F.Fab")
			(hide yes)
			(effects
				(font
					(size 1.016 1.016)
					(thickness 0.1524)
				)
			)
		)
		(property "Device Type" "C805H58"
			(at -0.0762 -8.1534 180)
			(unlocked yes)
			(layer "F.Fab")
			(hide yes)
			(effects
				(font
					(size 1.016 1.016)
					(thickness 0.1524)
				)
			)
		)
		(duplicate_pad_numbers_are_jumpers no)
		(fp_line
			(start 0.635 0)
			(end -0.635 0)
			(stroke
				(width 0.508)
				(type default)
			)
			(layer "F.SilkS")
		)
		(fp_rect
			(start -0.9652 1.778)
			(end 0.9652 -1.778)
			(stroke
				(width 0)
				(type default)
			)
			(fill no)
			(layer "F.CrtYd")
		)
		(fp_poly
			(pts
				(xy -0.9652 -1.778) (xy 0.9652 -1.778) (xy 0.9652 1.778) (xy -0.9652 1.778)
			)
			(stroke
				(width 0)
				(type default)
			)
			(fill no)
			(layer "F.Fab")
		)
		(pad "1" smd rect
			(at 0 -0.9652 180)
			(size 1.397 1.143)
			(layers "F.Cu" "F.Mask" "F.Paste")
			(net "TPS74801_P2V5_STBY_OUT")
		)
		(pad "2" smd rect
			(at 0 0.9652 180)
			(size 1.397 1.143)
			(layers "F.Cu" "F.Mask" "F.Paste")
			(net "GND")
		)
	)
	(footprint ""
		(layer "F.Cu")
		(at 206.000096 -6.199886)
		(property "Reference" "LED7"
			(at 0 0 0)
			(layer "F.SilkS")
			(hide yes)
			(effects
				(font
					(size 1.27 1.27)
				)
			)
		)
		(property "Value" "LED-BY-14-GP"
			(at -4.7752 -2.1844 0)
			(unlocked yes)
			(layer "F.Fab")
			(hide yes)
			(effects
				(font
					(size 1.016 1.016)
					(thickness 0.1524)
				)
			)
		)
		(property "Device Type" "LED-100-3PH206"
			(at -4.7752 -3.7084 0)
			(unlocked yes)
			(layer "F.Fab")
			(hide yes)
			(effects
				(font
					(size 1.016 1.016)
					(thickness 0.1524)
				)
			)
		)
		(duplicate_pad_numbers_are_jumpers no)
		(fp_line
			(start -3.7592 -1.524)
			(end 3.7592 -1.524)
			(stroke
				(width 0.1524)
				(type default)
			)
			(layer "F.SilkS")
		)
		(fp_line
			(start -3.7592 8.0264)
			(end -3.7592 -1.524)
			(stroke
				(width 0.1524)
				(type default)
			)
			(layer "F.SilkS")
		)
		(fp_line
			(start -1.75387 1.04394)
			(end -1.75387 3.63474)
			(stroke
				(width 0.1524)
				(type default)
			)
			(layer "F.SilkS")
		)
		(fp_line
			(start -1.75387 2.33934)
			(end -3.45567 2.33934)
			(stroke
				(width 0.1524)
				(type default)
			)
			(layer "F.SilkS")
		)
		(fp_line
			(start -1.75387 3.63474)
			(end -0.45847 2.33934)
			(stroke
				(width 0.1524)
				(type default)
			)
			(layer "F.SilkS")
		)
		(fp_line
			(start -0.45847 2.33934)
			(end -1.75387 1.04394)
			(stroke
				(width 0.1524)
				(type default)
			)
			(layer "F.SilkS")
		)
		(fp_line
			(start -0.45847 2.33934)
			(end 0.58293 2.33934)
			(stroke
				(width 0.1524)
				(type default)
			)
			(layer "F.SilkS")
		)
		(fp_line
			(start -0.45847 3.05054)
			(end -0.45847 1.42494)
			(stroke
				(width 0.1524)
				(type default)
			)
			(layer "F.SilkS")
		)
		(fp_line
			(start 0.58293 2.33934)
			(end 1.87833 1.04394)
			(stroke
				(width 0.1524)
				(type default)
			)
			(layer "F.SilkS")
		)
		(fp_line
			(start 0.58293 3.05054)
			(end 0.58293 1.42494)
			(stroke
				(width 0.1524)
				(type default)
			)
			(layer "F.SilkS")
		)
		(fp_line
			(start 1.87833 1.04394)
			(end 1.87833 3.63474)
			(stroke
				(width 0.1524)
				(type default)
			)
			(layer "F.SilkS")
		)
		(fp_line
			(start 1.87833 2.33934)
			(end 2.81813 2.33934)
			(stroke
				(width 0.1524)
				(type default)
			)
			(layer "F.SilkS")
		)
		(fp_line
			(start 1.87833 3.63474)
			(end 0.58293 2.33934)
			(stroke
				(width 0.1524)
				(type default)
			)
			(layer "F.SilkS")
		)
		(fp_line
			(start 3.7592 -1.524)
			(end 3.7592 8.0264)
			(stroke
				(width 0.1524)
				(type default)
			)
			(layer "F.SilkS")
		)
		(fp_line
			(start 3.7592 8.0264)
			(end -3.7592 8.0264)
			(stroke
				(width 0.1524)
				(type default)
			)
			(layer "F.SilkS")
		)
		(fp_circle
			(center -2.54 0)
			(end -1.5494 0)
			(stroke
				(width 0.3048)
				(type default)
			)
			(fill no)
			(layer "F.SilkS")
		)
		(fp_circle
			(center 0 0)
			(end 0.9906 0)
			(stroke
				(width 0.3048)
				(type default)
			)
			(fill no)
			(layer "F.SilkS")
		)
		(fp_circle
			(center 2.54 0)
			(end 3.5306 0)
			(stroke
				(width 0.3048)
				(type default)
			)
			(fill no)
			(layer "F.SilkS")
		)
		(fp_rect
			(start -3.5052 7.7724)
			(end 3.5052 -1.27)
			(stroke
				(width 0)
				(type default)
			)
			(fill no)
			(layer "F.CrtYd")
		)
		(fp_poly
			(pts
				(xy -4.0132 8.2804) (xy -4.0132 -1.778) (xy -3.5052 -1.778) (xy -3.5052 7.7724) (xy 3.5052 7.7724)
				(xy 3.5052 -1.27) (xy -3.50012 -1.27) (xy -3.50012 -1.778) (xy 4.0132 -1.778) (xy 4.0132 8.2804)
			)
			(stroke
				(width 0)
				(type default)
			)
			(fill no)
			(layer "F.CrtYd")
		)
		(fp_rect
			(start -4.0132 8.2804)
			(end 4.0132 -1.778)
			(stroke
				(width 0)
				(type default)
			)
			(fill no)
			(layer "F.Fab")
		)
		(pad "1" thru_hole circle
			(at -2.54 0)
			(size 1.27 1.27)
			(drill 0.889)
			(layers "*.Cu" "*.Mask")
			(remove_unused_layers no)
			(net "ML_PWR_BLUE_LED_R")
			(clearance 0.1651)
			(thermal_gap 0.1651)
		)
		(pad "2" thru_hole circle
			(at 0 0)
			(size 1.27 1.27)
			(drill 0.889)
			(layers "*.Cu" "*.Mask")
			(remove_unused_layers no)
			(net "GND")
			(clearance 0.1651)
			(thermal_gap 0.1651)
		)
		(pad "3" thru_hole circle
			(at 2.54 0)
			(size 1.27 1.27)
			(drill 0.889)
			(layers "*.Cu" "*.Mask")
			(remove_unused_layers no)
			(net "ML_PWR_YELLOW_LED_R")
			(clearance 0.1651)
			(thermal_gap 0.1651)
		)
	)
	(footprint ""
		(layer "F.Cu")
		(at 51.0159 -163.7538)
		(property "Reference" "R409"
			(at 0 0 0)
			(layer "F.SilkS")
			(hide yes)
			(effects
				(font
					(size 1.27 1.27)
				)
			)
		)
		(property "Value" "1K4R2F-1-GP"
			(at 0.064008 -3.993896 0)
			(unlocked yes)
			(layer "F.Fab")
			(hide yes)
			(effects
				(font
					(size 1.016 1.016)
					(thickness 0.1524)
				)
			)
		)
		(property "Device Type" "R402H16"
			(at 0.064008 -5.517896 0)
			(unlocked yes)
			(layer "F.Fab")
			(hide yes)
			(effects
				(font
					(size 1.016 1.016)
					(thickness 0.1524)
				)
			)
		)
		(duplicate_pad_numbers_are_jumpers no)
		(fp_line
			(start -0.508 -0.9398)
			(end -0.508 0.9398)
			(stroke
				(width 0.1524)
				(type default)
			)
			(layer "F.SilkS")
		)
		(fp_line
			(start 0.508 -0.9398)
			(end -0.508 -0.9398)
			(stroke
				(width 0.1524)
				(type default)
			)
			(layer "F.SilkS")
		)
		(fp_rect
			(start -0.508 0.9398)
			(end 0.508 -0.9398)
			(stroke
				(width 0)
				(type default)
			)
			(fill no)
			(layer "F.CrtYd")
		)
		(fp_rect
			(start -0.508 0.9398)
			(end 0.508 -0.9398)
			(stroke
				(width 0)
				(type default)
			)
			(fill no)
			(layer "F.Fab")
		)
		(pad "1" smd custom
			(at 0 -0.4445)
			(size 0.1397 0.1397)
			(layers "F.Cu" "F.Mask" "F.Paste")
			(net "P3V3")
			(options
				(clearance outline)
				(anchor circle)
			)
			(primitives
				(gr_poly
					(pts
						(arc
							(start -0.1778 -0.2794)
							(mid -0.249642 -0.249642)
							(end -0.2794 -0.1778)
						)
						(arc
							(start -0.2794 0.1778)
							(mid -0.249642 0.249642)
							(end -0.1778 0.2794)
						)
						(arc
							(start 0.1778 0.2794)
							(mid 0.249642 0.249642)
							(end 0.2794 0.1778)
						)
						(arc
							(start 0.2794 -0.1778)
							(mid 0.249642 -0.249642)
							(end 0.1778 -0.2794)
						)
					)
					(width 0)
					(fill yes)
				)
			)
		)
		(pad "2" smd custom
			(at 0 0.4445)
			(size 0.1397 0.1397)
			(layers "F.Cu" "F.Mask" "F.Paste")
			(net "ADC_P3V3")
			(options
				(clearance outline)
				(anchor circle)
			)
			(primitives
				(gr_poly
					(pts
						(arc
							(start -0.1778 -0.2794)
							(mid -0.249642 -0.249642)
							(end -0.2794 -0.1778)
						)
						(arc
							(start -0.2794 0.1778)
							(mid -0.249642 0.249642)
							(end -0.1778 0.2794)
						)
						(arc
							(start 0.1778 0.2794)
							(mid 0.249642 0.249642)
							(end 0.2794 0.1778)
						)
						(arc
							(start 0.2794 -0.1778)
							(mid 0.249642 -0.249642)
							(end 0.1778 -0.2794)
						)
					)
					(width 0)
					(fill yes)
				)
			)
		)
	)
	(footprint ""
		(layer "F.Cu")
		(at 79.155544 -168.225216 180)
		(property "Reference" "C244"
			(at 0 0 180)
			(layer "F.SilkS")
			(hide yes)
			(effects
				(font
					(size 1.27 1.27)
				)
			)
		)
		(property "Value" "SC10U6D3V5KX-4GP"
			(at -0.0762 -6.1214 180)
			(unlocked yes)
			(layer "F.Fab")
			(hide yes)
			(effects
				(font
					(size 1.016 1.016)
					(thickness 0.1524)
				)
			)
		)
		(property "Device Type" "C805H58"
			(at -0.0762 -8.1534 180)
			(unlocked yes)
			(layer "F.Fab")
			(hide yes)
			(effects
				(font
					(size 1.016 1.016)
					(thickness 0.1524)
				)
			)
		)
		(duplicate_pad_numbers_are_jumpers no)
		(fp_line
			(start 0.635 0)
			(end -0.635 0)
			(stroke
				(width 0.508)
				(type default)
			)
			(layer "F.SilkS")
		)
		(fp_rect
			(start -0.9652 1.778)
			(end 0.9652 -1.778)
			(stroke
				(width 0)
				(type default)
			)
			(fill no)
			(layer "F.CrtYd")
		)
		(fp_poly
			(pts
				(xy -0.9652 -1.778) (xy 0.9652 -1.778) (xy 0.9652 1.778) (xy -0.9652 1.778)
			)
			(stroke
				(width 0)
				(type default)
			)
			(fill no)
			(layer "F.Fab")
		)
		(pad "1" smd rect
			(at 0 -0.9652 180)
			(size 1.397 1.143)
			(layers "F.Cu" "F.Mask" "F.Paste")
			(net "P1V8_STBY")
		)
		(pad "2" smd rect
			(at 0 0.9652 180)
			(size 1.397 1.143)
			(layers "F.Cu" "F.Mask" "F.Paste")
			(net "GND")
		)
	)
	(footprint ""
		(layer "F.Cu")
		(at 50.27168 -184.020714)
		(property "Reference" "C175"
			(at 0 0 0)
			(layer "F.SilkS")
			(hide yes)
			(effects
				(font
					(size 1.27 1.27)
				)
			)
		)
		(property "Value" "ST150U6D3VDM-28-GP"
			(at 0 -9.6012 0)
			(unlocked yes)
			(layer "F.Fab")
			(hide yes)
			(effects
				(font
					(size 1.016 1.016)
					(thickness 0.1524)
				)
			)
		)
		(property "Device Type" "CT7343H83"
			(at 0 -11.1252 0)
			(unlocked yes)
			(layer "F.Fab")
			(hide yes)
			(effects
				(font
					(size 1.016 1.016)
					(thickness 0.1524)
				)
			)
		)
		(duplicate_pad_numbers_are_jumpers no)
		(fp_line
			(start -2.286 -4.8768)
			(end -2.286 -2.032)
			(stroke
				(width 0.1524)
				(type default)
			)
			(layer "F.SilkS")
		)
		(fp_line
			(start -2.286 4.8768)
			(end -2.286 2.032)
			(stroke
				(width 0.1524)
				(type default)
			)
			(layer "F.SilkS")
		)
		(fp_line
			(start 2.1082 -4.699)
			(end -2.1082 -4.699)
			(stroke
				(width 0.508)
				(type default)
			)
			(layer "F.SilkS")
		)
		(fp_line
			(start 2.286 -4.8768)
			(end -2.286 -4.8768)
			(stroke
				(width 0.1524)
				(type default)
			)
			(layer "F.SilkS")
		)
		(fp_line
			(start 2.286 -2.032)
			(end 2.286 -4.8768)
			(stroke
				(width 0.1524)
				(type default)
			)
			(layer "F.SilkS")
		)
		(fp_line
			(start 2.286 2.032)
			(end 2.286 4.8768)
			(stroke
				(width 0.1524)
				(type default)
			)
			(layer "F.SilkS")
		)
		(fp_line
			(start 2.286 4.8768)
			(end -2.286 4.8768)
			(stroke
				(width 0.1524)
				(type default)
			)
			(layer "F.SilkS")
		)
		(fp_rect
			(start -2.1463 3.6449)
			(end 2.1463 -3.6449)
			(stroke
				(width 0)
				(type default)
			)
			(fill no)
			(layer "F.CrtYd")
		)
		(fp_poly
			(pts
				(xy -2.54 4.953) (xy -2.54 4.2926) (xy -3.81 4.2926) (xy -3.81 -4.2926) (xy -2.54 -4.2926) (xy -2.54 -4.953)
				(xy 2.54 -4.953) (xy 2.54 -4.2926) (xy 3.81 -4.2926) (xy 3.81 -1.6256) (xy 2.1463 -1.6256) (xy 2.1463 -3.6449)
				(xy -2.1463 -3.6449) (xy -2.1463 3.6449) (xy 2.1463 3.6449) (xy 2.1463 -1.6129) (xy 3.81 -1.6129)
				(xy 3.81 4.2926) (xy 2.54 4.2926) (xy 2.54 4.953)
			)
			(stroke
				(width 0)
				(type default)
			)
			(fill no)
			(layer "F.CrtYd")
		)
		(fp_rect
			(start -3.81 4.2926)
			(end -2.54 -4.2926)
			(stroke
				(width 0)
				(type default)
			)
			(fill no)
			(layer "F.Fab")
		)
		(fp_rect
			(start -2.54 4.953)
			(end 2.54 -4.953)
			(stroke
				(width 0)
				(type default)
			)
			(fill no)
			(layer "F.Fab")
		)
		(fp_rect
			(start 2.54 4.2926)
			(end 3.81 -4.2926)
			(stroke
				(width 0)
				(type default)
			)
			(fill no)
			(layer "F.Fab")
		)
		(pad "1" smd rect
			(at 0 -3.1496)
			(size 2.413 2.286)
			(layers "F.Cu" "F.Mask" "F.Paste")
			(net "P3V3_STBY_OUT")
		)
		(pad "2" smd rect
			(at 0 3.1496)
			(size 2.413 2.286)
			(layers "F.Cu" "F.Mask" "F.Paste")
			(net "GND")
		)
		(zone
			(layer "F.Cu")
			(hatch none 0.5)
			(connect_pads
				(clearance 0)
			)
			(min_thickness 0.25)
			(keepout
				(tracks allowed)
				(vias not_allowed)
				(pads allowed)
				(copperpour not_allowed)
				(footprints allowed)
			)
			(placement
				(enabled no)
				(sheetname "")
			)
			(fill
				(thermal_gap 0.5)
				(thermal_bridge_width 0.5)
				(island_removal_mode 0)
			)
			(polygon
				(pts
					(xy 48.76038 -179.423314) (xy 51.78298 -179.423314) (xy 51.78298 -182.318914) (xy 51.78298 -182.649114)
					(xy 48.76038 -182.649114) (xy 48.76038 -182.318914)
				)
			)
		)
		(zone
			(layer "F.Cu")
			(hatch none 0.5)
			(connect_pads
				(clearance 0)
			)
			(min_thickness 0.25)
			(keepout
				(tracks allowed)
				(vias not_allowed)
				(pads allowed)
				(copperpour not_allowed)
				(footprints allowed)
			)
			(placement
				(enabled no)
				(sheetname "")
			)
			(fill
				(thermal_gap 0.5)
				(thermal_bridge_width 0.5)
				(island_removal_mode 0)
			)
			(polygon
				(pts
					(xy 51.78298 -185.709814) (xy 51.78298 -188.618114) (xy 48.76038 -188.618114) (xy 48.76038 -185.722514)
					(xy 48.76038 -185.392314) (xy 51.78298 -185.392314)
				)
			)
		)
	)
	(footprint ""
		(layer "F.Cu")
		(at 88.5444 -161.8742 180)
		(property "Reference" "R28"
			(at 0 0 180)
			(layer "F.SilkS")
			(hide yes)
			(effects
				(font
					(size 1.27 1.27)
				)
			)
		)
		(property "Value" "12KR2J-L-GP"
			(at 0.064008 -3.993896 180)
			(unlocked yes)
			(layer "F.Fab")
			(hide yes)
			(effects
				(font
					(size 1.016 1.016)
					(thickness 0.1524)
				)
			)
		)
		(property "Device Type" "R402H16"
			(at 0.064008 -5.517896 180)
			(unlocked yes)
			(layer "F.Fab")
			(hide yes)
			(effects
				(font
					(size 1.016 1.016)
					(thickness 0.1524)
				)
			)
		)
		(duplicate_pad_numbers_are_jumpers no)
		(fp_line
			(start 0.508 -0.9398)
			(end -0.508 -0.9398)
			(stroke
				(width 0.1524)
				(type default)
			)
			(layer "F.SilkS")
		)
		(fp_line
			(start -0.508 -0.9398)
			(end -0.508 0.9398)
			(stroke
				(width 0.1524)
				(type default)
			)
			(layer "F.SilkS")
		)
		(fp_rect
			(start -0.508 0.9398)
			(end 0.508 -0.9398)
			(stroke
				(width 0)
				(type default)
			)
			(fill no)
			(layer "F.CrtYd")
		)
		(fp_rect
			(start -0.508 0.9398)
			(end 0.508 -0.9398)
			(stroke
				(width 0)
				(type default)
			)
			(fill no)
			(layer "F.Fab")
		)
		(pad "1" smd custom
			(at 0 -0.4445 180)
			(size 0.1397 0.1397)
			(layers "F.Cu" "F.Mask" "F.Paste")
			(net "RBIAS")
			(options
				(clearance outline)
				(anchor circle)
			)
			(primitives
				(gr_poly
					(pts
						(arc
							(start -0.1778 -0.2794)
							(mid -0.249642 -0.249642)
							(end -0.2794 -0.1778)
						)
						(arc
							(start -0.2794 0.1778)
							(mid -0.249642 0.249642)
							(end -0.1778 0.2794)
						)
						(arc
							(start 0.1778 0.2794)
							(mid 0.249642 0.249642)
							(end 0.2794 0.1778)
						)
						(arc
							(start 0.2794 -0.1778)
							(mid 0.249642 -0.249642)
							(end 0.1778 -0.2794)
						)
					)
					(width 0)
					(fill yes)
				)
			)
		)
		(pad "2" smd custom
			(at 0 0.4445 180)
			(size 0.1397 0.1397)
			(layers "F.Cu" "F.Mask" "F.Paste")
			(net "GND")
			(options
				(clearance outline)
				(anchor circle)
			)
			(primitives
				(gr_poly
					(pts
						(arc
							(start -0.1778 -0.2794)
							(mid -0.249642 -0.249642)
							(end -0.2794 -0.1778)
						)
						(arc
							(start -0.2794 0.1778)
							(mid -0.249642 0.249642)
							(end -0.1778 0.2794)
						)
						(arc
							(start 0.1778 0.2794)
							(mid 0.249642 0.249642)
							(end 0.2794 0.1778)
						)
						(arc
							(start 0.2794 -0.1778)
							(mid 0.249642 -0.249642)
							(end 0.1778 -0.2794)
						)
					)
					(width 0)
					(fill yes)
				)
			)
		)
	)
	(footprint ""
		(layer "F.Cu")
		(at 92.070936 -50.398426 180)
		(property "Reference" "R502"
			(at 0 0 180)
			(layer "F.SilkS")
			(hide yes)
			(effects
				(font
					(size 1.27 1.27)
				)
			)
		)
		(property "Value" "1MR2F-GP"
			(at 0.064008 -3.993896 180)
			(unlocked yes)
			(layer "F.Fab")
			(hide yes)
			(effects
				(font
					(size 1.016 1.016)
					(thickness 0.1524)
				)
			)
		)
		(property "Device Type" "R402H16"
			(at 0.064008 -5.517896 180)
			(unlocked yes)
			(layer "F.Fab")
			(hide yes)
			(effects
				(font
					(size 1.016 1.016)
					(thickness 0.1524)
				)
			)
		)
		(duplicate_pad_numbers_are_jumpers no)
		(fp_line
			(start 0.508 -0.9398)
			(end -0.508 -0.9398)
			(stroke
				(width 0.1524)
				(type default)
			)
			(layer "F.SilkS")
		)
		(fp_line
			(start -0.508 -0.9398)
			(end -0.508 0.9398)
			(stroke
				(width 0.1524)
				(type default)
			)
			(layer "F.SilkS")
		)
		(fp_rect
			(start -0.508 0.9398)
			(end 0.508 -0.9398)
			(stroke
				(width 0)
				(type default)
			)
			(fill no)
			(layer "F.CrtYd")
		)
		(fp_rect
			(start -0.508 0.9398)
			(end 0.508 -0.9398)
			(stroke
				(width 0)
				(type default)
			)
			(fill no)
			(layer "F.Fab")
		)
		(pad "1" smd custom
			(at 0 -0.4445 180)
			(size 0.1397 0.1397)
			(layers "F.Cu" "F.Mask" "F.Paste")
			(net "PQ2_D")
			(options
				(clearance outline)
				(anchor circle)
			)
			(primitives
				(gr_poly
					(pts
						(arc
							(start -0.1778 -0.2794)
							(mid -0.249642 -0.249642)
							(end -0.2794 -0.1778)
						)
						(arc
							(start -0.2794 0.1778)
							(mid -0.249642 0.249642)
							(end -0.1778 0.2794)
						)
						(arc
							(start 0.1778 0.2794)
							(mid 0.249642 0.249642)
							(end 0.2794 0.1778)
						)
						(arc
							(start 0.2794 -0.1778)
							(mid 0.249642 -0.249642)
							(end 0.1778 -0.2794)
						)
					)
					(width 0)
					(fill yes)
				)
			)
		)
		(pad "2" smd custom
			(at 0 0.4445 180)
			(size 0.1397 0.1397)
			(layers "F.Cu" "F.Mask" "F.Paste")
			(net "P12V_STBY")
			(options
				(clearance outline)
				(anchor circle)
			)
			(primitives
				(gr_poly
					(pts
						(arc
							(start -0.1778 -0.2794)
							(mid -0.249642 -0.249642)
							(end -0.2794 -0.1778)
						)
						(arc
							(start -0.2794 0.1778)
							(mid -0.249642 0.249642)
							(end -0.1778 0.2794)
						)
						(arc
							(start 0.1778 0.2794)
							(mid 0.249642 0.249642)
							(end 0.2794 0.1778)
						)
						(arc
							(start 0.2794 -0.1778)
							(mid 0.249642 -0.249642)
							(end 0.1778 -0.2794)
						)
					)
					(width 0)
					(fill yes)
				)
			)
		)
	)
	(footprint ""
		(layer "F.Cu")
		(at 28.194 -154.686 -90)
		(property "Reference" "R770"
			(at 0 0 270)
			(layer "F.SilkS")
			(hide yes)
			(effects
				(font
					(size 1.27 1.27)
				)
			)
		)
		(property "Value" "0R2J-2-GP"
			(at 0.064008 -3.993896 270)
			(unlocked yes)
			(layer "F.Fab")
			(hide yes)
			(effects
				(font
					(size 1.016 1.016)
					(thickness 0.1524)
				)
			)
		)
		(property "Device Type" "R402H16"
			(at 0.064008 -5.517896 270)
			(unlocked yes)
			(layer "F.Fab")
			(hide yes)
			(effects
				(font
					(size 1.016 1.016)
					(thickness 0.1524)
				)
			)
		)
		(duplicate_pad_numbers_are_jumpers no)
		(fp_line
			(start -0.508 -0.9398)
			(end -0.508 0.9398)
			(stroke
				(width 0.1524)
				(type default)
			)
			(layer "F.SilkS")
		)
		(fp_line
			(start 0.508 -0.9398)
			(end -0.508 -0.9398)
			(stroke
				(width 0.1524)
				(type default)
			)
			(layer "F.SilkS")
		)
		(fp_rect
			(start -0.508 0.9398)
			(end 0.508 -0.9398)
			(stroke
				(width 0)
				(type default)
			)
			(fill no)
			(layer "F.CrtYd")
		)
		(fp_rect
			(start -0.508 0.9398)
			(end 0.508 -0.9398)
			(stroke
				(width 0)
				(type default)
			)
			(fill no)
			(layer "F.Fab")
		)
		(pad "1" smd custom
			(at 0 -0.4445 270)
			(size 0.1397 0.1397)
			(layers "F.Cu" "F.Mask" "F.Paste")
			(net "DEBUG_GPIO_BMC_R_3")
			(options
				(clearance outline)
				(anchor circle)
			)
			(primitives
				(gr_poly
					(pts
						(arc
							(start -0.1778 -0.2794)
							(mid -0.249642 -0.249642)
							(end -0.2794 -0.1778)
						)
						(arc
							(start -0.2794 0.1778)
							(mid -0.249642 0.249642)
							(end -0.1778 0.2794)
						)
						(arc
							(start 0.1778 0.2794)
							(mid 0.249642 0.249642)
							(end 0.2794 0.1778)
						)
						(arc
							(start 0.2794 -0.1778)
							(mid 0.249642 -0.249642)
							(end 0.1778 -0.2794)
						)
					)
					(width 0)
					(fill yes)
				)
			)
		)
		(pad "2" smd custom
			(at 0 0.4445 270)
			(size 0.1397 0.1397)
			(layers "F.Cu" "F.Mask" "F.Paste")
			(net "DEBUG_GPIO_BMC_3")
			(options
				(clearance outline)
				(anchor circle)
			)
			(primitives
				(gr_poly
					(pts
						(arc
							(start -0.1778 -0.2794)
							(mid -0.249642 -0.249642)
							(end -0.2794 -0.1778)
						)
						(arc
							(start -0.2794 0.1778)
							(mid -0.249642 0.249642)
							(end -0.1778 0.2794)
						)
						(arc
							(start 0.1778 0.2794)
							(mid 0.249642 0.249642)
							(end 0.2794 0.1778)
						)
						(arc
							(start 0.2794 -0.1778)
							(mid 0.249642 -0.249642)
							(end 0.1778 -0.2794)
						)
					)
					(width 0)
					(fill yes)
				)
			)
		)
	)
	(footprint ""
		(layer "F.Cu")
		(at 25.6794 -130.4544 180)
		(property "Reference" "R231"
			(at 0 0 180)
			(layer "F.SilkS")
			(hide yes)
			(effects
				(font
					(size 1.27 1.27)
				)
			)
		)
		(property "Value" "120R2F-GP"
			(at 0.064008 -3.993896 180)
			(unlocked yes)
			(layer "F.Fab")
			(hide yes)
			(effects
				(font
					(size 1.016 1.016)
					(thickness 0.1524)
				)
			)
		)
		(property "Device Type" "R402H16"
			(at 0.064008 -5.517896 180)
			(unlocked yes)
			(layer "F.Fab")
			(hide yes)
			(effects
				(font
					(size 1.016 1.016)
					(thickness 0.1524)
				)
			)
		)
		(duplicate_pad_numbers_are_jumpers no)
		(fp_line
			(start 0.508 -0.9398)
			(end -0.508 -0.9398)
			(stroke
				(width 0.1524)
				(type default)
			)
			(layer "F.SilkS")
		)
		(fp_line
			(start -0.508 -0.9398)
			(end -0.508 0.9398)
			(stroke
				(width 0.1524)
				(type default)
			)
			(layer "F.SilkS")
		)
		(fp_rect
			(start -0.508 0.9398)
			(end 0.508 -0.9398)
			(stroke
				(width 0)
				(type default)
			)
			(fill no)
			(layer "F.CrtYd")
		)
		(fp_rect
			(start -0.508 0.9398)
			(end 0.508 -0.9398)
			(stroke
				(width 0)
				(type default)
			)
			(fill no)
			(layer "F.Fab")
		)
		(pad "1" smd custom
			(at 0 -0.4445 180)
			(size 0.1397 0.1397)
			(layers "F.Cu" "F.Mask" "F.Paste")
			(net "GND")
			(options
				(clearance outline)
				(anchor circle)
			)
			(primitives
				(gr_poly
					(pts
						(arc
							(start -0.1778 -0.2794)
							(mid -0.249642 -0.249642)
							(end -0.2794 -0.1778)
						)
						(arc
							(start -0.2794 0.1778)
							(mid -0.249642 0.249642)
							(end -0.1778 0.2794)
						)
						(arc
							(start 0.1778 0.2794)
							(mid 0.249642 0.249642)
							(end 0.2794 0.1778)
						)
						(arc
							(start 0.2794 -0.1778)
							(mid 0.249642 -0.249642)
							(end 0.1778 -0.2794)
						)
					)
					(width 0)
					(fill yes)
				)
			)
		)
		(pad "2" smd custom
			(at 0 0.4445 180)
			(size 0.1397 0.1397)
			(layers "F.Cu" "F.Mask" "F.Paste")
			(net "MEMBA_1")
			(options
				(clearance outline)
				(anchor circle)
			)
			(primitives
				(gr_poly
					(pts
						(arc
							(start -0.1778 -0.2794)
							(mid -0.249642 -0.249642)
							(end -0.2794 -0.1778)
						)
						(arc
							(start -0.2794 0.1778)
							(mid -0.249642 0.249642)
							(end -0.1778 0.2794)
						)
						(arc
							(start 0.1778 0.2794)
							(mid 0.249642 0.249642)
							(end 0.2794 0.1778)
						)
						(arc
							(start 0.2794 -0.1778)
							(mid 0.249642 -0.249642)
							(end 0.1778 -0.2794)
						)
					)
					(width 0)
					(fill yes)
				)
			)
		)
	)
	(footprint ""
		(layer "F.Cu")
		(at 87.576914 -69.318124 -90)
		(property "Reference" "R15"
			(at 0 0 270)
			(layer "F.SilkS")
			(hide yes)
			(effects
				(font
					(size 1.27 1.27)
				)
			)
		)
		(property "Value" "0R2J-2-GP"
			(at 0.064008 -3.993896 270)
			(unlocked yes)
			(layer "F.Fab")
			(hide yes)
			(effects
				(font
					(size 1.016 1.016)
					(thickness 0.1524)
				)
			)
		)
		(property "Device Type" "R402H16"
			(at 0.064008 -5.517896 270)
			(unlocked yes)
			(layer "F.Fab")
			(hide yes)
			(effects
				(font
					(size 1.016 1.016)
					(thickness 0.1524)
				)
			)
		)
		(duplicate_pad_numbers_are_jumpers no)
		(fp_line
			(start -0.508 -0.9398)
			(end -0.508 0.9398)
			(stroke
				(width 0.1524)
				(type default)
			)
			(layer "F.SilkS")
		)
		(fp_line
			(start 0.508 -0.9398)
			(end -0.508 -0.9398)
			(stroke
				(width 0.1524)
				(type default)
			)
			(layer "F.SilkS")
		)
		(fp_rect
			(start -0.508 0.9398)
			(end 0.508 -0.9398)
			(stroke
				(width 0)
				(type default)
			)
			(fill no)
			(layer "F.CrtYd")
		)
		(fp_rect
			(start -0.508 0.9398)
			(end 0.508 -0.9398)
			(stroke
				(width 0)
				(type default)
			)
			(fill no)
			(layer "F.Fab")
		)
		(pad "1" smd custom
			(at 0 -0.4445 270)
			(size 0.1397 0.1397)
			(layers "F.Cu" "F.Mask" "F.Paste")
			(net "NCSI_RXD1")
			(options
				(clearance outline)
				(anchor circle)
			)
			(primitives
				(gr_poly
					(pts
						(arc
							(start -0.1778 -0.2794)
							(mid -0.249642 -0.249642)
							(end -0.2794 -0.1778)
						)
						(arc
							(start -0.2794 0.1778)
							(mid -0.249642 0.249642)
							(end -0.1778 0.2794)
						)
						(arc
							(start 0.1778 0.2794)
							(mid 0.249642 0.249642)
							(end 0.2794 0.1778)
						)
						(arc
							(start 0.2794 -0.1778)
							(mid 0.249642 -0.249642)
							(end 0.1778 -0.2794)
						)
					)
					(width 0)
					(fill yes)
				)
			)
		)
		(pad "2" smd custom
			(at 0 0.4445 270)
			(size 0.1397 0.1397)
			(layers "F.Cu" "F.Mask" "F.Paste")
			(net "NCSI_RXD1_R")
			(options
				(clearance outline)
				(anchor circle)
			)
			(primitives
				(gr_poly
					(pts
						(arc
							(start -0.1778 -0.2794)
							(mid -0.249642 -0.249642)
							(end -0.2794 -0.1778)
						)
						(arc
							(start -0.2794 0.1778)
							(mid -0.249642 0.249642)
							(end -0.1778 0.2794)
						)
						(arc
							(start 0.1778 0.2794)
							(mid 0.249642 0.249642)
							(end 0.2794 0.1778)
						)
						(arc
							(start 0.2794 -0.1778)
							(mid 0.249642 -0.249642)
							(end 0.1778 -0.2794)
						)
					)
					(width 0)
					(fill yes)
				)
			)
		)
	)
	(footprint ""
		(layer "F.Cu")
		(at 26.90368 -124.820172)
		(property "Reference" "R789"
			(at 0 0 0)
			(layer "F.SilkS")
			(hide yes)
			(effects
				(font
					(size 1.27 1.27)
				)
			)
		)
		(property "Value" "0R2J-2-GP"
			(at 0.064008 -3.993896 0)
			(unlocked yes)
			(layer "F.Fab")
			(hide yes)
			(effects
				(font
					(size 1.016 1.016)
					(thickness 0.1524)
				)
			)
		)
		(property "Device Type" "R402H16"
			(at 0.064008 -5.517896 0)
			(unlocked yes)
			(layer "F.Fab")
			(hide yes)
			(effects
				(font
					(size 1.016 1.016)
					(thickness 0.1524)
				)
			)
		)
		(duplicate_pad_numbers_are_jumpers no)
		(fp_line
			(start -0.508 -0.9398)
			(end -0.508 0.9398)
			(stroke
				(width 0.1524)
				(type default)
			)
			(layer "F.SilkS")
		)
		(fp_line
			(start 0.508 -0.9398)
			(end -0.508 -0.9398)
			(stroke
				(width 0.1524)
				(type default)
			)
			(layer "F.SilkS")
		)
		(fp_rect
			(start -0.508 0.9398)
			(end 0.508 -0.9398)
			(stroke
				(width 0)
				(type default)
			)
			(fill no)
			(layer "F.CrtYd")
		)
		(fp_rect
			(start -0.508 0.9398)
			(end 0.508 -0.9398)
			(stroke
				(width 0)
				(type default)
			)
			(fill no)
			(layer "F.Fab")
		)
		(pad "1" smd custom
			(at 0 -0.4445)
			(size 0.1397 0.1397)
			(layers "F.Cu" "F.Mask" "F.Paste")
			(net "FLA0_WP_N")
			(options
				(clearance outline)
				(anchor circle)
			)
			(primitives
				(gr_poly
					(pts
						(arc
							(start -0.1778 -0.2794)
							(mid -0.249642 -0.249642)
							(end -0.2794 -0.1778)
						)
						(arc
							(start -0.2794 0.1778)
							(mid -0.249642 0.249642)
							(end -0.1778 0.2794)
						)
						(arc
							(start 0.1778 0.2794)
							(mid 0.249642 0.249642)
							(end 0.2794 0.1778)
						)
						(arc
							(start 0.2794 -0.1778)
							(mid 0.249642 -0.249642)
							(end 0.1778 -0.2794)
						)
					)
					(width 0)
					(fill yes)
				)
			)
		)
		(pad "2" smd custom
			(at 0 0.4445)
			(size 0.1397 0.1397)
			(layers "F.Cu" "F.Mask" "F.Paste")
			(net "WP_DISABLE")
			(options
				(clearance outline)
				(anchor circle)
			)
			(primitives
				(gr_poly
					(pts
						(arc
							(start -0.1778 -0.2794)
							(mid -0.249642 -0.249642)
							(end -0.2794 -0.1778)
						)
						(arc
							(start -0.2794 0.1778)
							(mid -0.249642 0.249642)
							(end -0.1778 0.2794)
						)
						(arc
							(start 0.1778 0.2794)
							(mid 0.249642 0.249642)
							(end 0.2794 0.1778)
						)
						(arc
							(start 0.2794 -0.1778)
							(mid 0.249642 -0.249642)
							(end 0.1778 -0.2794)
						)
					)
					(width 0)
					(fill yes)
				)
			)
		)
	)
	(footprint ""
		(layer "F.Cu")
		(at 52.963064 -166.421054)
		(property "Reference" "R776"
			(at 0 0 0)
			(layer "F.SilkS")
			(hide yes)
			(effects
				(font
					(size 1.27 1.27)
				)
			)
		)
		(property "Value" "1KR2F-3-GP"
			(at 0.064008 -3.993896 0)
			(unlocked yes)
			(layer "F.Fab")
			(hide yes)
			(effects
				(font
					(size 1.016 1.016)
					(thickness 0.1524)
				)
			)
		)
		(property "Device Type" "R402H16"
			(at 0.064008 -5.517896 0)
			(unlocked yes)
			(layer "F.Fab")
			(hide yes)
			(effects
				(font
					(size 1.016 1.016)
					(thickness 0.1524)
				)
			)
		)
		(duplicate_pad_numbers_are_jumpers no)
		(fp_line
			(start -0.508 -0.9398)
			(end -0.508 0.9398)
			(stroke
				(width 0.1524)
				(type default)
			)
			(layer "F.SilkS")
		)
		(fp_line
			(start 0.508 -0.9398)
			(end -0.508 -0.9398)
			(stroke
				(width 0.1524)
				(type default)
			)
			(layer "F.SilkS")
		)
		(fp_rect
			(start -0.508 0.9398)
			(end 0.508 -0.9398)
			(stroke
				(width 0)
				(type default)
			)
			(fill no)
			(layer "F.CrtYd")
		)
		(fp_rect
			(start -0.508 0.9398)
			(end 0.508 -0.9398)
			(stroke
				(width 0)
				(type default)
			)
			(fill no)
			(layer "F.Fab")
		)
		(pad "1" smd custom
			(at 0 -0.4445)
			(size 0.1397 0.1397)
			(layers "F.Cu" "F.Mask" "F.Paste")
			(net "P1V2_STBY")
			(options
				(clearance outline)
				(anchor circle)
			)
			(primitives
				(gr_poly
					(pts
						(arc
							(start -0.1778 -0.2794)
							(mid -0.249642 -0.249642)
							(end -0.2794 -0.1778)
						)
						(arc
							(start -0.2794 0.1778)
							(mid -0.249642 0.249642)
							(end -0.1778 0.2794)
						)
						(arc
							(start 0.1778 0.2794)
							(mid 0.249642 0.249642)
							(end 0.2794 0.1778)
						)
						(arc
							(start 0.2794 -0.1778)
							(mid 0.249642 -0.249642)
							(end 0.1778 -0.2794)
						)
					)
					(width 0)
					(fill yes)
				)
			)
		)
		(pad "2" smd custom
			(at 0 0.4445)
			(size 0.1397 0.1397)
			(layers "F.Cu" "F.Mask" "F.Paste")
			(net "ADC_P1V2_STBY")
			(options
				(clearance outline)
				(anchor circle)
			)
			(primitives
				(gr_poly
					(pts
						(arc
							(start -0.1778 -0.2794)
							(mid -0.249642 -0.249642)
							(end -0.2794 -0.1778)
						)
						(arc
							(start -0.2794 0.1778)
							(mid -0.249642 0.249642)
							(end -0.1778 0.2794)
						)
						(arc
							(start 0.1778 0.2794)
							(mid 0.249642 0.249642)
							(end 0.2794 0.1778)
						)
						(arc
							(start 0.2794 -0.1778)
							(mid 0.249642 -0.249642)
							(end 0.1778 -0.2794)
						)
					)
					(width 0)
					(fill yes)
				)
			)
		)
	)
	(footprint ""
		(layer "F.Cu")
		(at 197.210172 -85.6488 135)
		(property "Reference" "VIA20"
			(at 0 0 135)
			(layer "F.SilkS")
			(hide yes)
			(effects
				(font
					(size 1.27 1.27)
				)
			)
		)
		(property "Value" "85OHM-8L-1D6MM-L16L18-GP"
			(at 4.064105 0.609655 135)
			(unlocked yes)
			(layer "F.Fab")
			(hide yes)
			(effects
				(font
					(size 1.016 1.016)
					(thickness 0.1524)
				)
			)
		)
		(property "Device Type" "VIA-PCIE-4P-368076"
			(at 4.064105 -0.914474 135)
			(unlocked yes)
			(layer "F.Fab")
			(hide yes)
			(effects
				(font
					(size 1.016 1.016)
					(thickness 0.1524)
				)
			)
		)
		(duplicate_pad_numbers_are_jumpers no)
		(fp_poly
			(pts
				(xy -1.841491 -0.381057) (xy 1.841509 -0.381058) (xy 1.841508 0.380942) (xy -1.841491 0.380942)
			)
			(stroke
				(width 0)
				(type default)
			)
			(fill no)
			(layer "F.CrtYd")
		)
		(fp_poly
			(pts
				(xy -1.841491 -0.381057) (xy 1.841509 -0.381058) (xy 1.841508 0.380942) (xy -1.841491 0.380942)
			)
			(stroke
				(width 0)
				(type default)
			)
			(fill no)
			(layer "F.Fab")
		)
		(pad "1" thru_hole circle
			(at -1.460499 0 135)
			(size 0.508 0.508)
			(drill 0.254)
			(layers "*.Cu" "*.Mask")
			(remove_unused_layers no)
			(net "GND")
			(clearance 0.127)
			(thermal_gap 0.127)
		)
		(pad "2" thru_hole circle
			(at -0.4445 0 135)
			(size 0.508 0.508)
			(drill 0.254)
			(layers "*.Cu" "*.Mask")
			(remove_unused_layers no)
			(net "PCIE_COMP_TO_IOM_11_DP")
			(clearance 0.127)
			(thermal_gap 0.127)
		)
		(pad "3" thru_hole circle
			(at 0.4445 0 135)
			(size 0.508 0.508)
			(drill 0.254)
			(layers "*.Cu" "*.Mask")
			(remove_unused_layers no)
			(net "PCIE_COMP_TO_IOM_11_DN")
			(clearance 0.127)
			(thermal_gap 0.127)
		)
		(pad "4" thru_hole circle
			(at 1.460499 0 135)
			(size 0.508 0.508)
			(drill 0.254)
			(layers "*.Cu" "*.Mask")
			(remove_unused_layers no)
			(net "GND")
			(clearance 0.127)
			(thermal_gap 0.127)
		)
	)
	(footprint ""
		(layer "F.Cu")
		(at 177.6222 -77.9526)
		(property "Reference" "TP107"
			(at 0 0 0)
			(layer "F.SilkS")
			(hide yes)
			(effects
				(font
					(size 1.27 1.27)
				)
			)
		)
		(property "Value" "TPAD28-2-GP"
			(at -0.0127 -1.6637 0)
			(unlocked yes)
			(layer "F.Fab")
			(hide yes)
			(effects
				(font
					(size 1.016 1.016)
					(thickness 0.1524)
				)
			)
		)
		(property "Device Type" "TPAD28"
			(at -0.0127 -3.1877 0)
			(unlocked yes)
			(layer "F.Fab")
			(hide yes)
			(effects
				(font
					(size 1.016 1.016)
					(thickness 0.1524)
				)
			)
		)
		(duplicate_pad_numbers_are_jumpers no)
		(fp_poly
			(pts
				(arc
					(start 0.3556 0)
					(mid -0.3556 0)
					(end 0.3556 0)
				)
			)
			(stroke
				(width 0)
				(type default)
			)
			(fill no)
			(layer "F.CrtYd")
		)
		(fp_poly
			(pts
				(arc
					(start 0.6096 0)
					(mid -0.6096 0)
					(end 0.6096 0)
				)
			)
			(stroke
				(width 0)
				(type default)
			)
			(fill no)
			(layer "F.Fab")
		)
		(pad "1" smd circle
			(at 0 0)
			(size 0.7112 0.7112)
			(layers "F.Cu" "F.Mask" "F.Paste")
			(net "IOC_GPIO_22")
		)
	)
	(footprint ""
		(layer "F.Cu")
		(at 16.013684 -164.5539 90)
		(property "Reference" "R531"
			(at 0 0 90)
			(layer "F.SilkS")
			(hide yes)
			(effects
				(font
					(size 1.27 1.27)
				)
			)
		)
		(property "Value" "4K99R2F-L-GP"
			(at 0.064008 -3.993896 90)
			(unlocked yes)
			(layer "F.Fab")
			(hide yes)
			(effects
				(font
					(size 1.016 1.016)
					(thickness 0.1524)
				)
			)
		)
		(property "Device Type" "R402H16"
			(at 0.064008 -5.517896 90)
			(unlocked yes)
			(layer "F.Fab")
			(hide yes)
			(effects
				(font
					(size 1.016 1.016)
					(thickness 0.1524)
				)
			)
		)
		(duplicate_pad_numbers_are_jumpers no)
		(fp_line
			(start 0.508 -0.9398)
			(end -0.508 -0.9398)
			(stroke
				(width 0.1524)
				(type default)
			)
			(layer "F.SilkS")
		)
		(fp_line
			(start -0.508 -0.9398)
			(end -0.508 0.9398)
			(stroke
				(width 0.1524)
				(type default)
			)
			(layer "F.SilkS")
		)
		(fp_rect
			(start -0.508 0.9398)
			(end 0.508 -0.9398)
			(stroke
				(width 0)
				(type default)
			)
			(fill no)
			(layer "F.CrtYd")
		)
		(fp_rect
			(start -0.508 0.9398)
			(end 0.508 -0.9398)
			(stroke
				(width 0)
				(type default)
			)
			(fill no)
			(layer "F.Fab")
		)
		(pad "1" smd custom
			(at 0 -0.4445 90)
			(size 0.1397 0.1397)
			(layers "F.Cu" "F.Mask" "F.Paste")
			(net "TPS74801_P1V2_STBY_FB")
			(options
				(clearance outline)
				(anchor circle)
			)
			(primitives
				(gr_poly
					(pts
						(arc
							(start -0.1778 -0.2794)
							(mid -0.249642 -0.249642)
							(end -0.2794 -0.1778)
						)
						(arc
							(start -0.2794 0.1778)
							(mid -0.249642 0.249642)
							(end -0.1778 0.2794)
						)
						(arc
							(start 0.1778 0.2794)
							(mid 0.249642 0.249642)
							(end 0.2794 0.1778)
						)
						(arc
							(start 0.2794 -0.1778)
							(mid 0.249642 -0.249642)
							(end 0.1778 -0.2794)
						)
					)
					(width 0)
					(fill yes)
				)
			)
		)
		(pad "2" smd custom
			(at 0 0.4445 90)
			(size 0.1397 0.1397)
			(layers "F.Cu" "F.Mask" "F.Paste")
			(net "GND")
			(options
				(clearance outline)
				(anchor circle)
			)
			(primitives
				(gr_poly
					(pts
						(arc
							(start -0.1778 -0.2794)
							(mid -0.249642 -0.249642)
							(end -0.2794 -0.1778)
						)
						(arc
							(start -0.2794 0.1778)
							(mid -0.249642 0.249642)
							(end -0.1778 0.2794)
						)
						(arc
							(start 0.1778 0.2794)
							(mid 0.249642 0.249642)
							(end 0.2794 0.1778)
						)
						(arc
							(start 0.2794 -0.1778)
							(mid 0.249642 -0.249642)
							(end 0.1778 -0.2794)
						)
					)
					(width 0)
					(fill yes)
				)
			)
		)
	)
	(footprint ""
		(layer "F.Cu")
		(at 208.055972 -66.0908 90)
		(property "Reference" "C320"
			(at 0 0 90)
			(layer "F.SilkS")
			(hide yes)
			(effects
				(font
					(size 1.27 1.27)
				)
			)
		)
		(property "Value" "SCD01U16V1KX-GP"
			(at -2.8321 -1.7399 90)
			(unlocked yes)
			(layer "F.Fab")
			(hide yes)
			(effects
				(font
					(size 1.016 1.016)
					(thickness 0.1524)
				)
			)
		)
		(property "Device Type" "C0201H13"
			(at -2.8321 -3.2639 90)
			(unlocked yes)
			(layer "F.Fab")
			(hide yes)
			(effects
				(font
					(size 1.016 1.016)
					(thickness 0.1524)
				)
			)
		)
		(duplicate_pad_numbers_are_jumpers no)
		(fp_rect
			(start -0.2794 0.6477)
			(end 0.2794 -0.6477)
			(stroke
				(width 0)
				(type default)
			)
			(fill no)
			(layer "F.CrtYd")
		)
		(fp_rect
			(start -0.2794 0.6477)
			(end 0.2794 -0.6477)
			(stroke
				(width 0)
				(type default)
			)
			(fill no)
			(layer "F.Fab")
		)
		(pad "1" smd custom
			(at 0 -0.2794 90)
			(size 0.0762 0.0762)
			(layers "F.Cu" "F.Mask" "F.Paste")
			(net "PHY_IOC_TO_CON_B_2_DN_C")
			(options
				(clearance outline)
				(anchor circle)
			)
			(primitives
				(gr_poly
					(pts
						(arc
							(start 0.1524 -0.127)
							(mid 0.137521 -0.162921)
							(end 0.1016 -0.1778)
						)
						(arc
							(start -0.1016 -0.1778)
							(mid -0.137521 -0.162921)
							(end -0.1524 -0.127)
						)
						(arc
							(start -0.1524 0.127)
							(mid -0.137521 0.162921)
							(end -0.1016 0.1778)
						)
						(arc
							(start 0.1016 0.1778)
							(mid 0.137521 0.162921)
							(end 0.1524 0.127)
						)
					)
					(width 0)
					(fill yes)
				)
			)
		)
		(pad "2" smd custom
			(at 0 0.2794 90)
			(size 0.0762 0.0762)
			(layers "F.Cu" "F.Mask" "F.Paste")
			(net "PHY_IOC_TO_CON_B_2_DN")
			(options
				(clearance outline)
				(anchor circle)
			)
			(primitives
				(gr_poly
					(pts
						(arc
							(start 0.1524 -0.127)
							(mid 0.137521 -0.162921)
							(end 0.1016 -0.1778)
						)
						(arc
							(start -0.1016 -0.1778)
							(mid -0.137521 -0.162921)
							(end -0.1524 -0.127)
						)
						(arc
							(start -0.1524 0.127)
							(mid -0.137521 0.162921)
							(end -0.1016 0.1778)
						)
						(arc
							(start 0.1016 0.1778)
							(mid 0.137521 0.162921)
							(end 0.1524 0.127)
						)
					)
					(width 0)
					(fill yes)
				)
			)
		)
	)
	(footprint ""
		(layer "F.Cu")
		(at 88.9 -132.7658)
		(property "Reference" "R138"
			(at 0 0 0)
			(layer "F.SilkS")
			(hide yes)
			(effects
				(font
					(size 1.27 1.27)
				)
			)
		)
		(property "Value" "8K2R2J-3-GP"
			(at 0.064008 -3.993896 0)
			(unlocked yes)
			(layer "F.Fab")
			(hide yes)
			(effects
				(font
					(size 1.016 1.016)
					(thickness 0.1524)
				)
			)
		)
		(property "Device Type" "R402H16"
			(at 0.064008 -5.517896 0)
			(unlocked yes)
			(layer "F.Fab")
			(hide yes)
			(effects
				(font
					(size 1.016 1.016)
					(thickness 0.1524)
				)
			)
		)
		(duplicate_pad_numbers_are_jumpers no)
		(fp_line
			(start -0.508 -0.9398)
			(end -0.508 0.9398)
			(stroke
				(width 0.1524)
				(type default)
			)
			(layer "F.SilkS")
		)
		(fp_line
			(start 0.508 -0.9398)
			(end -0.508 -0.9398)
			(stroke
				(width 0.1524)
				(type default)
			)
			(layer "F.SilkS")
		)
		(fp_rect
			(start -0.508 0.9398)
			(end 0.508 -0.9398)
			(stroke
				(width 0)
				(type default)
			)
			(fill no)
			(layer "F.CrtYd")
		)
		(fp_rect
			(start -0.508 0.9398)
			(end 0.508 -0.9398)
			(stroke
				(width 0)
				(type default)
			)
			(fill no)
			(layer "F.Fab")
		)
		(pad "1" smd custom
			(at 0 -0.4445)
			(size 0.1397 0.1397)
			(layers "F.Cu" "F.Mask" "F.Paste")
			(net "EEPROM_A2")
			(options
				(clearance outline)
				(anchor circle)
			)
			(primitives
				(gr_poly
					(pts
						(arc
							(start -0.1778 -0.2794)
							(mid -0.249642 -0.249642)
							(end -0.2794 -0.1778)
						)
						(arc
							(start -0.2794 0.1778)
							(mid -0.249642 0.249642)
							(end -0.1778 0.2794)
						)
						(arc
							(start 0.1778 0.2794)
							(mid 0.249642 0.249642)
							(end 0.2794 0.1778)
						)
						(arc
							(start 0.2794 -0.1778)
							(mid 0.249642 -0.249642)
							(end 0.1778 -0.2794)
						)
					)
					(width 0)
					(fill yes)
				)
			)
		)
		(pad "2" smd custom
			(at 0 0.4445)
			(size 0.1397 0.1397)
			(layers "F.Cu" "F.Mask" "F.Paste")
			(net "GND")
			(options
				(clearance outline)
				(anchor circle)
			)
			(primitives
				(gr_poly
					(pts
						(arc
							(start -0.1778 -0.2794)
							(mid -0.249642 -0.249642)
							(end -0.2794 -0.1778)
						)
						(arc
							(start -0.2794 0.1778)
							(mid -0.249642 0.249642)
							(end -0.1778 0.2794)
						)
						(arc
							(start 0.1778 0.2794)
							(mid 0.249642 0.249642)
							(end 0.2794 0.1778)
						)
						(arc
							(start 0.2794 -0.1778)
							(mid 0.249642 -0.249642)
							(end 0.1778 -0.2794)
						)
					)
					(width 0)
					(fill yes)
				)
			)
		)
	)
	(footprint ""
		(layer "F.Cu")
		(at 172.5168 -117.094 180)
		(property "Reference" "C221"
			(at 0 0 180)
			(layer "F.SilkS")
			(hide yes)
			(effects
				(font
					(size 1.27 1.27)
				)
			)
		)
		(property "Value" "SCD1U25V2KX-2-GP"
			(at 1.1811 -2.7051 180)
			(unlocked yes)
			(layer "F.Fab")
			(hide yes)
			(effects
				(font
					(size 1.016 1.016)
					(thickness 0.1524)
				)
			)
		)
		(property "Device Type" "C402H22"
			(at 1.1811 -4.2291 180)
			(unlocked yes)
			(layer "F.Fab")
			(hide yes)
			(effects
				(font
					(size 1.016 1.016)
					(thickness 0.1524)
				)
			)
		)
		(duplicate_pad_numbers_are_jumpers no)
		(fp_rect
			(start -0.4318 0.9525)
			(end 0.4318 -0.9525)
			(stroke
				(width 0)
				(type default)
			)
			(fill no)
			(layer "F.CrtYd")
		)
		(fp_rect
			(start -0.4318 0.9525)
			(end 0.4318 -0.9525)
			(stroke
				(width 0)
				(type default)
			)
			(fill no)
			(layer "F.Fab")
		)
		(pad "1" smd custom
			(at 0 -0.4445 180)
			(size 0.1524 0.1524)
			(layers "F.Cu" "F.Mask" "F.Paste")
			(net "P1V8")
			(options
				(clearance outline)
				(anchor circle)
			)
			(primitives
				(gr_poly
					(pts
						(arc
							(start 0.3048 -0.2032)
							(mid 0.275042 -0.275042)
							(end 0.2032 -0.3048)
						)
						(arc
							(start -0.2032 -0.3048)
							(mid -0.275042 -0.275042)
							(end -0.3048 -0.2032)
						)
						(arc
							(start -0.3048 0.2032)
							(mid -0.275042 0.275042)
							(end -0.2032 0.3048)
						)
						(arc
							(start 0.2032 0.3048)
							(mid 0.275042 0.275042)
							(end 0.3048 0.2032)
						)
					)
					(width 0)
					(fill yes)
				)
			)
		)
		(pad "2" smd custom
			(at 0 0.4445 180)
			(size 0.1524 0.1524)
			(layers "F.Cu" "F.Mask" "F.Paste")
			(net "GND")
			(options
				(clearance outline)
				(anchor circle)
			)
			(primitives
				(gr_poly
					(pts
						(arc
							(start 0.3048 -0.2032)
							(mid 0.275042 -0.275042)
							(end 0.2032 -0.3048)
						)
						(arc
							(start -0.2032 -0.3048)
							(mid -0.275042 -0.275042)
							(end -0.3048 -0.2032)
						)
						(arc
							(start -0.3048 0.2032)
							(mid -0.275042 0.275042)
							(end -0.2032 0.3048)
						)
						(arc
							(start 0.2032 0.3048)
							(mid 0.275042 0.275042)
							(end 0.3048 0.2032)
						)
					)
					(width 0)
					(fill yes)
				)
			)
		)
	)
	(footprint ""
		(layer "F.Cu")
		(at 174.4472 -64.8716 90)
		(property "Reference" "R581"
			(at 0 0 90)
			(layer "F.SilkS")
			(hide yes)
			(effects
				(font
					(size 1.27 1.27)
				)
			)
		)
		(property "Value" "2K2R2F-GP"
			(at 0.064008 -3.993896 90)
			(unlocked yes)
			(layer "F.Fab")
			(hide yes)
			(effects
				(font
					(size 1.016 1.016)
					(thickness 0.1524)
				)
			)
		)
		(property "Device Type" "R402H16"
			(at 0.064008 -5.517896 90)
			(unlocked yes)
			(layer "F.Fab")
			(hide yes)
			(effects
				(font
					(size 1.016 1.016)
					(thickness 0.1524)
				)
			)
		)
		(duplicate_pad_numbers_are_jumpers no)
		(fp_line
			(start 0.508 -0.9398)
			(end -0.508 -0.9398)
			(stroke
				(width 0.1524)
				(type default)
			)
			(layer "F.SilkS")
		)
		(fp_line
			(start -0.508 -0.9398)
			(end -0.508 0.9398)
			(stroke
				(width 0.1524)
				(type default)
			)
			(layer "F.SilkS")
		)
		(fp_rect
			(start -0.508 0.9398)
			(end 0.508 -0.9398)
			(stroke
				(width 0)
				(type default)
			)
			(fill no)
			(layer "F.CrtYd")
		)
		(fp_rect
			(start -0.508 0.9398)
			(end 0.508 -0.9398)
			(stroke
				(width 0)
				(type default)
			)
			(fill no)
			(layer "F.Fab")
		)
		(pad "1" smd custom
			(at 0 -0.4445 90)
			(size 0.1397 0.1397)
			(layers "F.Cu" "F.Mask" "F.Paste")
			(net "P1V8")
			(options
				(clearance outline)
				(anchor circle)
			)
			(primitives
				(gr_poly
					(pts
						(arc
							(start -0.1778 -0.2794)
							(mid -0.249642 -0.249642)
							(end -0.2794 -0.1778)
						)
						(arc
							(start -0.2794 0.1778)
							(mid -0.249642 0.249642)
							(end -0.1778 0.2794)
						)
						(arc
							(start 0.1778 0.2794)
							(mid 0.249642 0.249642)
							(end 0.2794 0.1778)
						)
						(arc
							(start 0.2794 -0.1778)
							(mid 0.249642 -0.249642)
							(end 0.1778 -0.2794)
						)
					)
					(width 0)
					(fill yes)
				)
			)
		)
		(pad "2" smd custom
			(at 0 0.4445 90)
			(size 0.1397 0.1397)
			(layers "F.Cu" "F.Mask" "F.Paste")
			(net "IOC_SDA_0")
			(options
				(clearance outline)
				(anchor circle)
			)
			(primitives
				(gr_poly
					(pts
						(arc
							(start -0.1778 -0.2794)
							(mid -0.249642 -0.249642)
							(end -0.2794 -0.1778)
						)
						(arc
							(start -0.2794 0.1778)
							(mid -0.249642 0.249642)
							(end -0.1778 0.2794)
						)
						(arc
							(start 0.1778 0.2794)
							(mid 0.249642 0.249642)
							(end 0.2794 0.1778)
						)
						(arc
							(start 0.2794 -0.1778)
							(mid 0.249642 -0.249642)
							(end 0.1778 -0.2794)
						)
					)
					(width 0)
					(fill yes)
				)
			)
		)
	)
	(footprint ""
		(layer "F.Cu")
		(at 207.333088 -99.984306 -90)
		(property "Reference" "R602"
			(at 0 0 270)
			(layer "F.SilkS")
			(hide yes)
			(effects
				(font
					(size 1.27 1.27)
				)
			)
		)
		(property "Value" "0R2J-2-GP"
			(at 0.064008 -3.993896 270)
			(unlocked yes)
			(layer "F.Fab")
			(hide yes)
			(effects
				(font
					(size 1.016 1.016)
					(thickness 0.1524)
				)
			)
		)
		(property "Device Type" "R402H16"
			(at 0.064008 -5.517896 270)
			(unlocked yes)
			(layer "F.Fab")
			(hide yes)
			(effects
				(font
					(size 1.016 1.016)
					(thickness 0.1524)
				)
			)
		)
		(duplicate_pad_numbers_are_jumpers no)
		(fp_line
			(start -0.508 -0.9398)
			(end -0.508 0.9398)
			(stroke
				(width 0.1524)
				(type default)
			)
			(layer "F.SilkS")
		)
		(fp_line
			(start 0.508 -0.9398)
			(end -0.508 -0.9398)
			(stroke
				(width 0.1524)
				(type default)
			)
			(layer "F.SilkS")
		)
		(fp_rect
			(start -0.508 0.9398)
			(end 0.508 -0.9398)
			(stroke
				(width 0)
				(type default)
			)
			(fill no)
			(layer "F.CrtYd")
		)
		(fp_rect
			(start -0.508 0.9398)
			(end 0.508 -0.9398)
			(stroke
				(width 0)
				(type default)
			)
			(fill no)
			(layer "F.Fab")
		)
		(pad "1" smd custom
			(at 0 -0.4445 270)
			(size 0.1397 0.1397)
			(layers "F.Cu" "F.Mask" "F.Paste")
			(net "IOC_EEPROM_WP")
			(options
				(clearance outline)
				(anchor circle)
			)
			(primitives
				(gr_poly
					(pts
						(arc
							(start -0.1778 -0.2794)
							(mid -0.249642 -0.249642)
							(end -0.2794 -0.1778)
						)
						(arc
							(start -0.2794 0.1778)
							(mid -0.249642 0.249642)
							(end -0.1778 0.2794)
						)
						(arc
							(start 0.1778 0.2794)
							(mid 0.249642 0.249642)
							(end 0.2794 0.1778)
						)
						(arc
							(start 0.2794 -0.1778)
							(mid 0.249642 -0.249642)
							(end 0.1778 -0.2794)
						)
					)
					(width 0)
					(fill yes)
				)
			)
		)
		(pad "2" smd custom
			(at 0 0.4445 270)
			(size 0.1397 0.1397)
			(layers "F.Cu" "F.Mask" "F.Paste")
			(net "GND")
			(options
				(clearance outline)
				(anchor circle)
			)
			(primitives
				(gr_poly
					(pts
						(arc
							(start -0.1778 -0.2794)
							(mid -0.249642 -0.249642)
							(end -0.2794 -0.1778)
						)
						(arc
							(start -0.2794 0.1778)
							(mid -0.249642 0.249642)
							(end -0.1778 0.2794)
						)
						(arc
							(start 0.1778 0.2794)
							(mid 0.249642 0.249642)
							(end 0.2794 0.1778)
						)
						(arc
							(start 0.2794 -0.1778)
							(mid 0.249642 -0.249642)
							(end 0.1778 -0.2794)
						)
					)
					(width 0)
					(fill yes)
				)
			)
		)
	)
	(footprint ""
		(layer "F.Cu")
		(at 208.055972 -69.4436 90)
		(property "Reference" "C316"
			(at 0 0 90)
			(layer "F.SilkS")
			(hide yes)
			(effects
				(font
					(size 1.27 1.27)
				)
			)
		)
		(property "Value" "SCD01U16V1KX-GP"
			(at -2.8321 -1.7399 90)
			(unlocked yes)
			(layer "F.Fab")
			(hide yes)
			(effects
				(font
					(size 1.016 1.016)
					(thickness 0.1524)
				)
			)
		)
		(property "Device Type" "C0201H13"
			(at -2.8321 -3.2639 90)
			(unlocked yes)
			(layer "F.Fab")
			(hide yes)
			(effects
				(font
					(size 1.016 1.016)
					(thickness 0.1524)
				)
			)
		)
		(duplicate_pad_numbers_are_jumpers no)
		(fp_rect
			(start -0.2794 0.6477)
			(end 0.2794 -0.6477)
			(stroke
				(width 0)
				(type default)
			)
			(fill no)
			(layer "F.CrtYd")
		)
		(fp_rect
			(start -0.2794 0.6477)
			(end 0.2794 -0.6477)
			(stroke
				(width 0)
				(type default)
			)
			(fill no)
			(layer "F.Fab")
		)
		(pad "1" smd custom
			(at 0 -0.2794 90)
			(size 0.0762 0.0762)
			(layers "F.Cu" "F.Mask" "F.Paste")
			(net "PHY_IOC_TO_CON_B_0_DN_C")
			(options
				(clearance outline)
				(anchor circle)
			)
			(primitives
				(gr_poly
					(pts
						(arc
							(start 0.1524 -0.127)
							(mid 0.137521 -0.162921)
							(end 0.1016 -0.1778)
						)
						(arc
							(start -0.1016 -0.1778)
							(mid -0.137521 -0.162921)
							(end -0.1524 -0.127)
						)
						(arc
							(start -0.1524 0.127)
							(mid -0.137521 0.162921)
							(end -0.1016 0.1778)
						)
						(arc
							(start 0.1016 0.1778)
							(mid 0.137521 0.162921)
							(end 0.1524 0.127)
						)
					)
					(width 0)
					(fill yes)
				)
			)
		)
		(pad "2" smd custom
			(at 0 0.2794 90)
			(size 0.0762 0.0762)
			(layers "F.Cu" "F.Mask" "F.Paste")
			(net "PHY_IOC_TO_CON_B_0_DN")
			(options
				(clearance outline)
				(anchor circle)
			)
			(primitives
				(gr_poly
					(pts
						(arc
							(start 0.1524 -0.127)
							(mid 0.137521 -0.162921)
							(end 0.1016 -0.1778)
						)
						(arc
							(start -0.1016 -0.1778)
							(mid -0.137521 -0.162921)
							(end -0.1524 -0.127)
						)
						(arc
							(start -0.1524 0.127)
							(mid -0.137521 0.162921)
							(end -0.1016 0.1778)
						)
						(arc
							(start 0.1016 0.1778)
							(mid 0.137521 0.162921)
							(end 0.1524 0.127)
						)
					)
					(width 0)
					(fill yes)
				)
			)
		)
	)
	(footprint ""
		(layer "F.Cu")
		(at 83.43392 -134.97052 -90)
		(property "Reference" "R50"
			(at 0 0 270)
			(layer "F.SilkS")
			(hide yes)
			(effects
				(font
					(size 1.27 1.27)
				)
			)
		)
		(property "Value" "4K7R2F-GP"
			(at 0.064008 -3.993896 270)
			(unlocked yes)
			(layer "F.Fab")
			(hide yes)
			(effects
				(font
					(size 1.016 1.016)
					(thickness 0.1524)
				)
			)
		)
		(property "Device Type" "R402H16"
			(at 0.064008 -5.517896 270)
			(unlocked yes)
			(layer "F.Fab")
			(hide yes)
			(effects
				(font
					(size 1.016 1.016)
					(thickness 0.1524)
				)
			)
		)
		(duplicate_pad_numbers_are_jumpers no)
		(fp_line
			(start -0.508 -0.9398)
			(end -0.508 0.9398)
			(stroke
				(width 0.1524)
				(type default)
			)
			(layer "F.SilkS")
		)
		(fp_line
			(start 0.508 -0.9398)
			(end -0.508 -0.9398)
			(stroke
				(width 0.1524)
				(type default)
			)
			(layer "F.SilkS")
		)
		(fp_rect
			(start -0.508 0.9398)
			(end 0.508 -0.9398)
			(stroke
				(width 0)
				(type default)
			)
			(fill no)
			(layer "F.CrtYd")
		)
		(fp_rect
			(start -0.508 0.9398)
			(end 0.508 -0.9398)
			(stroke
				(width 0)
				(type default)
			)
			(fill no)
			(layer "F.Fab")
		)
		(pad "1" smd custom
			(at 0 -0.4445 270)
			(size 0.1397 0.1397)
			(layers "F.Cu" "F.Mask" "F.Paste")
			(net "P3V3_STBY")
			(options
				(clearance outline)
				(anchor circle)
			)
			(primitives
				(gr_poly
					(pts
						(arc
							(start -0.1778 -0.2794)
							(mid -0.249642 -0.249642)
							(end -0.2794 -0.1778)
						)
						(arc
							(start -0.2794 0.1778)
							(mid -0.249642 0.249642)
							(end -0.1778 0.2794)
						)
						(arc
							(start 0.1778 0.2794)
							(mid 0.249642 0.249642)
							(end 0.2794 0.1778)
						)
						(arc
							(start 0.2794 -0.1778)
							(mid 0.249642 -0.249642)
							(end 0.1778 -0.2794)
						)
					)
					(width 0)
					(fill yes)
				)
			)
		)
		(pad "2" smd custom
			(at 0 0.4445 270)
			(size 0.1397 0.1397)
			(layers "F.Cu" "F.Mask" "F.Paste")
			(net "I2C_DEBUG_SDA")
			(options
				(clearance outline)
				(anchor circle)
			)
			(primitives
				(gr_poly
					(pts
						(arc
							(start -0.1778 -0.2794)
							(mid -0.249642 -0.249642)
							(end -0.2794 -0.1778)
						)
						(arc
							(start -0.2794 0.1778)
							(mid -0.249642 0.249642)
							(end -0.1778 0.2794)
						)
						(arc
							(start 0.1778 0.2794)
							(mid 0.249642 0.249642)
							(end 0.2794 0.1778)
						)
						(arc
							(start 0.2794 -0.1778)
							(mid 0.249642 -0.249642)
							(end 0.1778 -0.2794)
						)
					)
					(width 0)
					(fill yes)
				)
			)
		)
	)
	(footprint ""
		(layer "F.Cu")
		(at 47.01159 -158.1912)
		(property "Reference" "R171"
			(at 0 0 0)
			(layer "F.SilkS")
			(hide yes)
			(effects
				(font
					(size 1.27 1.27)
				)
			)
		)
		(property "Value" "0R2J-2-GP"
			(at 0.064008 -3.993896 0)
			(unlocked yes)
			(layer "F.Fab")
			(hide yes)
			(effects
				(font
					(size 1.016 1.016)
					(thickness 0.1524)
				)
			)
		)
		(property "Device Type" "R402H16"
			(at 0.064008 -5.517896 0)
			(unlocked yes)
			(layer "F.Fab")
			(hide yes)
			(effects
				(font
					(size 1.016 1.016)
					(thickness 0.1524)
				)
			)
		)
		(duplicate_pad_numbers_are_jumpers no)
		(fp_line
			(start -0.508 -0.9398)
			(end -0.508 0.9398)
			(stroke
				(width 0.1524)
				(type default)
			)
			(layer "F.SilkS")
		)
		(fp_line
			(start 0.508 -0.9398)
			(end -0.508 -0.9398)
			(stroke
				(width 0.1524)
				(type default)
			)
			(layer "F.SilkS")
		)
		(fp_rect
			(start -0.508 0.9398)
			(end 0.508 -0.9398)
			(stroke
				(width 0)
				(type default)
			)
			(fill no)
			(layer "F.CrtYd")
		)
		(fp_rect
			(start -0.508 0.9398)
			(end 0.508 -0.9398)
			(stroke
				(width 0)
				(type default)
			)
			(fill no)
			(layer "F.Fab")
		)
		(pad "1" smd custom
			(at 0 -0.4445)
			(size 0.1397 0.1397)
			(layers "F.Cu" "F.Mask" "F.Paste")
			(net "I2C_DPB_SCL_OUT")
			(options
				(clearance outline)
				(anchor circle)
			)
			(primitives
				(gr_poly
					(pts
						(arc
							(start -0.1778 -0.2794)
							(mid -0.249642 -0.249642)
							(end -0.2794 -0.1778)
						)
						(arc
							(start -0.2794 0.1778)
							(mid -0.249642 0.249642)
							(end -0.1778 0.2794)
						)
						(arc
							(start 0.1778 0.2794)
							(mid 0.249642 0.249642)
							(end 0.2794 0.1778)
						)
						(arc
							(start 0.2794 -0.1778)
							(mid 0.249642 -0.249642)
							(end 0.1778 -0.2794)
						)
					)
					(width 0)
					(fill yes)
				)
			)
		)
		(pad "2" smd custom
			(at 0 0.4445)
			(size 0.1397 0.1397)
			(layers "F.Cu" "F.Mask" "F.Paste")
			(net "BMC_SMB7_CLK")
			(options
				(clearance outline)
				(anchor circle)
			)
			(primitives
				(gr_poly
					(pts
						(arc
							(start -0.1778 -0.2794)
							(mid -0.249642 -0.249642)
							(end -0.2794 -0.1778)
						)
						(arc
							(start -0.2794 0.1778)
							(mid -0.249642 0.249642)
							(end -0.1778 0.2794)
						)
						(arc
							(start 0.1778 0.2794)
							(mid 0.249642 0.249642)
							(end 0.2794 0.1778)
						)
						(arc
							(start 0.2794 -0.1778)
							(mid 0.249642 -0.249642)
							(end 0.1778 -0.2794)
						)
					)
					(width 0)
					(fill yes)
				)
			)
		)
	)
	(footprint ""
		(layer "F.Cu")
		(at 98.552 -146.431 -90)
		(property "Reference" "R426"
			(at 0 0 270)
			(layer "F.SilkS")
			(hide yes)
			(effects
				(font
					(size 1.27 1.27)
				)
			)
		)
		(property "Value" "0R2J-2-GP"
			(at 0.064008 -3.993896 270)
			(unlocked yes)
			(layer "F.Fab")
			(hide yes)
			(effects
				(font
					(size 1.016 1.016)
					(thickness 0.1524)
				)
			)
		)
		(property "Device Type" "R402H16"
			(at 0.064008 -5.517896 270)
			(unlocked yes)
			(layer "F.Fab")
			(hide yes)
			(effects
				(font
					(size 1.016 1.016)
					(thickness 0.1524)
				)
			)
		)
		(duplicate_pad_numbers_are_jumpers no)
		(fp_line
			(start -0.508 -0.9398)
			(end -0.508 0.9398)
			(stroke
				(width 0.1524)
				(type default)
			)
			(layer "F.SilkS")
		)
		(fp_line
			(start 0.508 -0.9398)
			(end -0.508 -0.9398)
			(stroke
				(width 0.1524)
				(type default)
			)
			(layer "F.SilkS")
		)
		(fp_rect
			(start -0.508 0.9398)
			(end 0.508 -0.9398)
			(stroke
				(width 0)
				(type default)
			)
			(fill no)
			(layer "F.CrtYd")
		)
		(fp_rect
			(start -0.508 0.9398)
			(end 0.508 -0.9398)
			(stroke
				(width 0)
				(type default)
			)
			(fill no)
			(layer "F.Fab")
		)
		(pad "1" smd custom
			(at 0 -0.4445 270)
			(size 0.1397 0.1397)
			(layers "F.Cu" "F.Mask" "F.Paste")
			(net "I2C_DEBUG_SDA_L")
			(options
				(clearance outline)
				(anchor circle)
			)
			(primitives
				(gr_poly
					(pts
						(arc
							(start -0.1778 -0.2794)
							(mid -0.249642 -0.249642)
							(end -0.2794 -0.1778)
						)
						(arc
							(start -0.2794 0.1778)
							(mid -0.249642 0.249642)
							(end -0.1778 0.2794)
						)
						(arc
							(start 0.1778 0.2794)
							(mid 0.249642 0.249642)
							(end 0.2794 0.1778)
						)
						(arc
							(start 0.2794 -0.1778)
							(mid 0.249642 -0.249642)
							(end 0.1778 -0.2794)
						)
					)
					(width 0)
					(fill yes)
				)
			)
		)
		(pad "2" smd custom
			(at 0 0.4445 270)
			(size 0.1397 0.1397)
			(layers "F.Cu" "F.Mask" "F.Paste")
			(net "I2C_DEBUG_SDA_R")
			(options
				(clearance outline)
				(anchor circle)
			)
			(primitives
				(gr_poly
					(pts
						(arc
							(start -0.1778 -0.2794)
							(mid -0.249642 -0.249642)
							(end -0.2794 -0.1778)
						)
						(arc
							(start -0.2794 0.1778)
							(mid -0.249642 0.249642)
							(end -0.1778 0.2794)
						)
						(arc
							(start 0.1778 0.2794)
							(mid 0.249642 0.249642)
							(end 0.2794 0.1778)
						)
						(arc
							(start 0.2794 -0.1778)
							(mid 0.249642 -0.249642)
							(end 0.1778 -0.2794)
						)
					)
					(width 0)
					(fill yes)
				)
			)
		)
	)
	(footprint ""
		(layer "F.Cu")
		(at 39.807134 -131.696968 180)
		(property "Reference" "R378"
			(at 0 0 180)
			(layer "F.SilkS")
			(hide yes)
			(effects
				(font
					(size 1.27 1.27)
				)
			)
		)
		(property "Value" "4K7R2F-GP"
			(at 0.064008 -3.993896 180)
			(unlocked yes)
			(layer "F.Fab")
			(hide yes)
			(effects
				(font
					(size 1.016 1.016)
					(thickness 0.1524)
				)
			)
		)
		(property "Device Type" "R402H16"
			(at 0.064008 -5.517896 180)
			(unlocked yes)
			(layer "F.Fab")
			(hide yes)
			(effects
				(font
					(size 1.016 1.016)
					(thickness 0.1524)
				)
			)
		)
		(duplicate_pad_numbers_are_jumpers no)
		(fp_line
			(start 0.508 -0.9398)
			(end -0.508 -0.9398)
			(stroke
				(width 0.1524)
				(type default)
			)
			(layer "F.SilkS")
		)
		(fp_line
			(start -0.508 -0.9398)
			(end -0.508 0.9398)
			(stroke
				(width 0.1524)
				(type default)
			)
			(layer "F.SilkS")
		)
		(fp_rect
			(start -0.508 0.9398)
			(end 0.508 -0.9398)
			(stroke
				(width 0)
				(type default)
			)
			(fill no)
			(layer "F.CrtYd")
		)
		(fp_rect
			(start -0.508 0.9398)
			(end 0.508 -0.9398)
			(stroke
				(width 0)
				(type default)
			)
			(fill no)
			(layer "F.Fab")
		)
		(pad "1" smd custom
			(at 0 -0.4445 180)
			(size 0.1397 0.1397)
			(layers "F.Cu" "F.Mask" "F.Paste")
			(net "P3V3_STBY")
			(options
				(clearance outline)
				(anchor circle)
			)
			(primitives
				(gr_poly
					(pts
						(arc
							(start -0.1778 -0.2794)
							(mid -0.249642 -0.249642)
							(end -0.2794 -0.1778)
						)
						(arc
							(start -0.2794 0.1778)
							(mid -0.249642 0.249642)
							(end -0.1778 0.2794)
						)
						(arc
							(start 0.1778 0.2794)
							(mid 0.249642 0.249642)
							(end 0.2794 0.1778)
						)
						(arc
							(start 0.2794 -0.1778)
							(mid 0.249642 -0.249642)
							(end 0.1778 -0.2794)
						)
					)
					(width 0)
					(fill yes)
				)
			)
		)
		(pad "2" smd custom
			(at 0 0.4445 180)
			(size 0.1397 0.1397)
			(layers "F.Cu" "F.Mask" "F.Paste")
			(net "BMC_GPIOZ6")
			(options
				(clearance outline)
				(anchor circle)
			)
			(primitives
				(gr_poly
					(pts
						(arc
							(start -0.1778 -0.2794)
							(mid -0.249642 -0.249642)
							(end -0.2794 -0.1778)
						)
						(arc
							(start -0.2794 0.1778)
							(mid -0.249642 0.249642)
							(end -0.1778 0.2794)
						)
						(arc
							(start 0.1778 0.2794)
							(mid 0.249642 0.249642)
							(end 0.2794 0.1778)
						)
						(arc
							(start 0.2794 -0.1778)
							(mid 0.249642 -0.249642)
							(end 0.1778 -0.2794)
						)
					)
					(width 0)
					(fill yes)
				)
			)
		)
	)
	(footprint ""
		(layer "F.Cu")
		(at 46.011084 -161.368232 180)
		(property "Reference" "R180"
			(at 0 0 180)
			(layer "F.SilkS")
			(hide yes)
			(effects
				(font
					(size 1.27 1.27)
				)
			)
		)
		(property "Value" "2K2R2F-GP"
			(at 0.064008 -3.993896 180)
			(unlocked yes)
			(layer "F.Fab")
			(hide yes)
			(effects
				(font
					(size 1.016 1.016)
					(thickness 0.1524)
				)
			)
		)
		(property "Device Type" "R402H16"
			(at 0.064008 -5.517896 180)
			(unlocked yes)
			(layer "F.Fab")
			(hide yes)
			(effects
				(font
					(size 1.016 1.016)
					(thickness 0.1524)
				)
			)
		)
		(duplicate_pad_numbers_are_jumpers no)
		(fp_line
			(start 0.508 -0.9398)
			(end -0.508 -0.9398)
			(stroke
				(width 0.1524)
				(type default)
			)
			(layer "F.SilkS")
		)
		(fp_line
			(start -0.508 -0.9398)
			(end -0.508 0.9398)
			(stroke
				(width 0.1524)
				(type default)
			)
			(layer "F.SilkS")
		)
		(fp_rect
			(start -0.508 0.9398)
			(end 0.508 -0.9398)
			(stroke
				(width 0)
				(type default)
			)
			(fill no)
			(layer "F.CrtYd")
		)
		(fp_rect
			(start -0.508 0.9398)
			(end 0.508 -0.9398)
			(stroke
				(width 0)
				(type default)
			)
			(fill no)
			(layer "F.Fab")
		)
		(pad "1" smd custom
			(at 0 -0.4445 180)
			(size 0.1397 0.1397)
			(layers "F.Cu" "F.Mask" "F.Paste")
			(net "I2C_DPB_SDA_OUT")
			(options
				(clearance outline)
				(anchor circle)
			)
			(primitives
				(gr_poly
					(pts
						(arc
							(start -0.1778 -0.2794)
							(mid -0.249642 -0.249642)
							(end -0.2794 -0.1778)
						)
						(arc
							(start -0.2794 0.1778)
							(mid -0.249642 0.249642)
							(end -0.1778 0.2794)
						)
						(arc
							(start 0.1778 0.2794)
							(mid 0.249642 0.249642)
							(end 0.2794 0.1778)
						)
						(arc
							(start 0.2794 -0.1778)
							(mid 0.249642 -0.249642)
							(end 0.1778 -0.2794)
						)
					)
					(width 0)
					(fill yes)
				)
			)
		)
		(pad "2" smd custom
			(at 0 0.4445 180)
			(size 0.1397 0.1397)
			(layers "F.Cu" "F.Mask" "F.Paste")
			(net "P3V3_STBY")
			(options
				(clearance outline)
				(anchor circle)
			)
			(primitives
				(gr_poly
					(pts
						(arc
							(start -0.1778 -0.2794)
							(mid -0.249642 -0.249642)
							(end -0.2794 -0.1778)
						)
						(arc
							(start -0.2794 0.1778)
							(mid -0.249642 0.249642)
							(end -0.1778 0.2794)
						)
						(arc
							(start 0.1778 0.2794)
							(mid 0.249642 0.249642)
							(end 0.2794 0.1778)
						)
						(arc
							(start 0.2794 -0.1778)
							(mid 0.249642 -0.249642)
							(end 0.1778 -0.2794)
						)
					)
					(width 0)
					(fill yes)
				)
			)
		)
	)
	(footprint ""
		(layer "F.Cu")
		(at 77.283818 -93.355668 90)
		(property "Reference" "VIA8"
			(at 0 0 90)
			(layer "F.SilkS")
			(hide yes)
			(effects
				(font
					(size 1.27 1.27)
				)
			)
		)
		(property "Value" "85OHM-8L-1D6MM-L16L18-GP"
			(at 4.064 0.6096 90)
			(unlocked yes)
			(layer "F.Fab")
			(hide yes)
			(effects
				(font
					(size 1.016 1.016)
					(thickness 0.1524)
				)
			)
		)
		(property "Device Type" "VIA-PCIE-4P-368076"
			(at 4.064 -0.9144 90)
			(unlocked yes)
			(layer "F.Fab")
			(hide yes)
			(effects
				(font
					(size 1.016 1.016)
					(thickness 0.1524)
				)
			)
		)
		(duplicate_pad_numbers_are_jumpers no)
		(fp_rect
			(start -1.8415 0.381)
			(end 1.8415 -0.381)
			(stroke
				(width 0)
				(type default)
			)
			(fill no)
			(layer "F.CrtYd")
		)
		(fp_rect
			(start -1.8415 0.381)
			(end 1.8415 -0.381)
			(stroke
				(width 0)
				(type default)
			)
			(fill no)
			(layer "F.Fab")
		)
		(pad "1" thru_hole circle
			(at -1.4605 0 90)
			(size 0.508 0.508)
			(drill 0.254)
			(layers "*.Cu" "*.Mask")
			(remove_unused_layers no)
			(net "GND")
			(clearance 0.127)
			(thermal_gap 0.127)
		)
		(pad "2" thru_hole circle
			(at -0.4445 0 90)
			(size 0.508 0.508)
			(drill 0.254)
			(layers "*.Cu" "*.Mask")
			(remove_unused_layers no)
			(net "PCIE_COMP_TO_IOM_23_DP")
			(clearance 0.127)
			(thermal_gap 0.127)
		)
		(pad "3" thru_hole circle
			(at 0.4445 0 90)
			(size 0.508 0.508)
			(drill 0.254)
			(layers "*.Cu" "*.Mask")
			(remove_unused_layers no)
			(net "PCIE_COMP_TO_IOM_23_DN")
			(clearance 0.127)
			(thermal_gap 0.127)
		)
		(pad "4" thru_hole circle
			(at 1.4605 0 90)
			(size 0.508 0.508)
			(drill 0.254)
			(layers "*.Cu" "*.Mask")
			(remove_unused_layers no)
			(net "GND")
			(clearance 0.127)
			(thermal_gap 0.127)
		)
	)
	(footprint ""
		(layer "F.Cu")
		(at 197.379336 -133.2865 180)
		(property "Reference" "R552"
			(at 0 0 180)
			(layer "F.SilkS")
			(hide yes)
			(effects
				(font
					(size 1.27 1.27)
				)
			)
		)
		(property "Value" "4K7R2F-GP"
			(at 0.064008 -3.993896 180)
			(unlocked yes)
			(layer "F.Fab")
			(hide yes)
			(effects
				(font
					(size 1.016 1.016)
					(thickness 0.1524)
				)
			)
		)
		(property "Device Type" "R402H16"
			(at 0.064008 -5.517896 180)
			(unlocked yes)
			(layer "F.Fab")
			(hide yes)
			(effects
				(font
					(size 1.016 1.016)
					(thickness 0.1524)
				)
			)
		)
		(duplicate_pad_numbers_are_jumpers no)
		(fp_line
			(start 0.508 -0.9398)
			(end -0.508 -0.9398)
			(stroke
				(width 0.1524)
				(type default)
			)
			(layer "F.SilkS")
		)
		(fp_line
			(start -0.508 -0.9398)
			(end -0.508 0.9398)
			(stroke
				(width 0.1524)
				(type default)
			)
			(layer "F.SilkS")
		)
		(fp_rect
			(start -0.508 0.9398)
			(end 0.508 -0.9398)
			(stroke
				(width 0)
				(type default)
			)
			(fill no)
			(layer "F.CrtYd")
		)
		(fp_rect
			(start -0.508 0.9398)
			(end 0.508 -0.9398)
			(stroke
				(width 0)
				(type default)
			)
			(fill no)
			(layer "F.Fab")
		)
		(pad "1" smd custom
			(at 0 -0.4445 180)
			(size 0.1397 0.1397)
			(layers "F.Cu" "F.Mask" "F.Paste")
			(net "P1V8")
			(options
				(clearance outline)
				(anchor circle)
			)
			(primitives
				(gr_poly
					(pts
						(arc
							(start -0.1778 -0.2794)
							(mid -0.249642 -0.249642)
							(end -0.2794 -0.1778)
						)
						(arc
							(start -0.2794 0.1778)
							(mid -0.249642 0.249642)
							(end -0.1778 0.2794)
						)
						(arc
							(start 0.1778 0.2794)
							(mid 0.249642 0.249642)
							(end 0.2794 0.1778)
						)
						(arc
							(start 0.2794 -0.1778)
							(mid 0.249642 -0.249642)
							(end 0.1778 -0.2794)
						)
					)
					(width 0)
					(fill yes)
				)
			)
		)
		(pad "2" smd custom
			(at 0 0.4445 180)
			(size 0.1397 0.1397)
			(layers "F.Cu" "F.Mask" "F.Paste")
			(net "Q9_G")
			(options
				(clearance outline)
				(anchor circle)
			)
			(primitives
				(gr_poly
					(pts
						(arc
							(start -0.1778 -0.2794)
							(mid -0.249642 -0.249642)
							(end -0.2794 -0.1778)
						)
						(arc
							(start -0.2794 0.1778)
							(mid -0.249642 0.249642)
							(end -0.1778 0.2794)
						)
						(arc
							(start 0.1778 0.2794)
							(mid 0.249642 0.249642)
							(end 0.2794 0.1778)
						)
						(arc
							(start 0.2794 -0.1778)
							(mid 0.249642 -0.249642)
							(end 0.1778 -0.2794)
						)
					)
					(width 0)
					(fill yes)
				)
			)
		)
	)
	(footprint ""
		(layer "F.Cu")
		(at 75.1332 -144.7038 90)
		(property "Reference" "R132"
			(at 0 0 90)
			(layer "F.SilkS")
			(hide yes)
			(effects
				(font
					(size 1.27 1.27)
				)
			)
		)
		(property "Value" "0R2J-2-GP"
			(at 0.064008 -3.993896 90)
			(unlocked yes)
			(layer "F.Fab")
			(hide yes)
			(effects
				(font
					(size 1.016 1.016)
					(thickness 0.1524)
				)
			)
		)
		(property "Device Type" "R402H16"
			(at 0.064008 -5.517896 90)
			(unlocked yes)
			(layer "F.Fab")
			(hide yes)
			(effects
				(font
					(size 1.016 1.016)
					(thickness 0.1524)
				)
			)
		)
		(duplicate_pad_numbers_are_jumpers no)
		(fp_line
			(start 0.508 -0.9398)
			(end -0.508 -0.9398)
			(stroke
				(width 0.1524)
				(type default)
			)
			(layer "F.SilkS")
		)
		(fp_line
			(start -0.508 -0.9398)
			(end -0.508 0.9398)
			(stroke
				(width 0.1524)
				(type default)
			)
			(layer "F.SilkS")
		)
		(fp_rect
			(start -0.508 0.9398)
			(end 0.508 -0.9398)
			(stroke
				(width 0)
				(type default)
			)
			(fill no)
			(layer "F.CrtYd")
		)
		(fp_rect
			(start -0.508 0.9398)
			(end 0.508 -0.9398)
			(stroke
				(width 0)
				(type default)
			)
			(fill no)
			(layer "F.Fab")
		)
		(pad "1" smd custom
			(at 0 -0.4445 90)
			(size 0.1397 0.1397)
			(layers "F.Cu" "F.Mask" "F.Paste")
			(net "I2C_SCC_SDA")
			(options
				(clearance outline)
				(anchor circle)
			)
			(primitives
				(gr_poly
					(pts
						(arc
							(start -0.1778 -0.2794)
							(mid -0.249642 -0.249642)
							(end -0.2794 -0.1778)
						)
						(arc
							(start -0.2794 0.1778)
							(mid -0.249642 0.249642)
							(end -0.1778 0.2794)
						)
						(arc
							(start 0.1778 0.2794)
							(mid 0.249642 0.249642)
							(end 0.2794 0.1778)
						)
						(arc
							(start 0.2794 -0.1778)
							(mid 0.249642 -0.249642)
							(end 0.1778 -0.2794)
						)
					)
					(width 0)
					(fill yes)
				)
			)
		)
		(pad "2" smd custom
			(at 0 0.4445 90)
			(size 0.1397 0.1397)
			(layers "F.Cu" "F.Mask" "F.Paste")
			(net "I2C_SCC_SDA_R")
			(options
				(clearance outline)
				(anchor circle)
			)
			(primitives
				(gr_poly
					(pts
						(arc
							(start -0.1778 -0.2794)
							(mid -0.249642 -0.249642)
							(end -0.2794 -0.1778)
						)
						(arc
							(start -0.2794 0.1778)
							(mid -0.249642 0.249642)
							(end -0.1778 0.2794)
						)
						(arc
							(start 0.1778 0.2794)
							(mid 0.249642 0.249642)
							(end 0.2794 0.1778)
						)
						(arc
							(start 0.2794 -0.1778)
							(mid 0.249642 -0.249642)
							(end 0.1778 -0.2794)
						)
					)
					(width 0)
					(fill yes)
				)
			)
		)
	)
	(footprint ""
		(layer "F.Cu")
		(at 23.999952 -8.750046)
		(property "Reference" "PWR1"
			(at 0 0 0)
			(layer "F.SilkS")
			(hide yes)
			(effects
				(font
					(size 1.27 1.27)
				)
			)
		)
		(property "Value" "SW-TACT-4P-169-GP"
			(at -5.715 -0.8509 0)
			(unlocked yes)
			(layer "F.Fab")
			(hide yes)
			(effects
				(font
					(size 1.016 1.016)
					(thickness 0.1524)
				)
			)
		)
		(property "Device Type" "DTSA-65N-K-S-V-676-K"
			(at -5.715 -2.3749 0)
			(unlocked yes)
			(layer "F.Fab")
			(hide yes)
			(effects
				(font
					(size 1.016 1.016)
					(thickness 0.1524)
				)
			)
		)
		(duplicate_pad_numbers_are_jumpers no)
		(fp_line
			(start -4.4958 -4.2418)
			(end -2.54 -4.2418)
			(stroke
				(width 0.1524)
				(type default)
			)
			(layer "F.SilkS")
		)
		(fp_line
			(start -4.4958 -1.5367)
			(end -4.4958 -4.2418)
			(stroke
				(width 0.1524)
				(type default)
			)
			(layer "F.SilkS")
		)
		(fp_line
			(start -3.9497 -1.5367)
			(end -4.4958 -1.5367)
			(stroke
				(width 0.1524)
				(type default)
			)
			(layer "F.SilkS")
		)
		(fp_line
			(start -3.9497 3.2004)
			(end -3.9497 -1.5367)
			(stroke
				(width 0.1524)
				(type default)
			)
			(layer "F.SilkS")
		)
		(fp_line
			(start -2.54 -4.2418)
			(end -2.54 -2.0574)
			(stroke
				(width 0.1524)
				(type default)
			)
			(layer "F.SilkS")
		)
		(fp_line
			(start -2.54 -2.0574)
			(end 2.54 -2.0574)
			(stroke
				(width 0.1524)
				(type default)
			)
			(layer "F.SilkS")
		)
		(fp_line
			(start -2.0066 3.2004)
			(end -3.9497 3.2004)
			(stroke
				(width 0.1524)
				(type default)
			)
			(layer "F.SilkS")
		)
		(fp_line
			(start -2.0066 8.6106)
			(end -2.0066 3.2004)
			(stroke
				(width 0.1524)
				(type default)
			)
			(layer "F.SilkS")
		)
		(fp_line
			(start 2.0066 3.2004)
			(end 2.0066 8.6106)
			(stroke
				(width 0.1524)
				(type default)
			)
			(layer "F.SilkS")
		)
		(fp_line
			(start 2.0066 8.6106)
			(end -2.0066 8.6106)
			(stroke
				(width 0.1524)
				(type default)
			)
			(layer "F.SilkS")
		)
		(fp_line
			(start 2.54 -4.2418)
			(end 4.4958 -4.2418)
			(stroke
				(width 0.1524)
				(type default)
			)
			(layer "F.SilkS")
		)
		(fp_line
			(start 2.54 -2.0574)
			(end 2.54 -4.2418)
			(stroke
				(width 0.1524)
				(type default)
			)
			(layer "F.SilkS")
		)
		(fp_line
			(start 3.9497 -1.5367)
			(end 3.9497 3.2004)
			(stroke
				(width 0.1524)
				(type default)
			)
			(layer "F.SilkS")
		)
		(fp_line
			(start 3.9497 3.2004)
			(end 2.0066 3.2004)
			(stroke
				(width 0.1524)
				(type default)
			)
			(layer "F.SilkS")
		)
		(fp_line
			(start 4.4958 -4.2418)
			(end 4.4958 -1.5367)
			(stroke
				(width 0.1524)
				(type default)
			)
			(layer "F.SilkS")
		)
		(fp_line
			(start 4.4958 -1.5367)
			(end 3.9497 -1.5367)
			(stroke
				(width 0.1524)
				(type default)
			)
			(layer "F.SilkS")
		)
		(fp_circle
			(center -3.50012 -2.500122)
			(end -2.43332 -2.500122)
			(stroke
				(width 0.3048)
				(type default)
			)
			(fill no)
			(layer "F.SilkS")
		)
		(fp_circle
			(center -2.249932 0)
			(end -1.183132 0)
			(stroke
				(width 0.3048)
				(type default)
			)
			(fill no)
			(layer "F.SilkS")
		)
		(fp_circle
			(center 2.249932 0)
			(end 3.316732 0)
			(stroke
				(width 0.3048)
				(type default)
			)
			(fill no)
			(layer "F.SilkS")
		)
		(fp_circle
			(center 3.50012 -2.500122)
			(end 4.56692 -2.500122)
			(stroke
				(width 0.3048)
				(type default)
			)
			(fill no)
			(layer "F.SilkS")
		)
		(fp_poly
			(pts
				(xy -1.7526 8.3566) (xy -1.7526 2.9464) (xy -3.6957 2.9464) (xy -3.6957 -2.144522) (xy -4.2418 -2.144522)
				(xy -4.2418 -2.855722) (xy -3.6957 -2.855722) (xy -3.6957 -3.9878) (xy -3.302 -3.9878) (xy -3.302 -1.7907)
				(xy 3.302 -1.7907) (xy 3.302 -3.9878) (xy 3.6957 -3.9878) (xy 3.6957 -2.855722) (xy 4.2418 -2.855722)
				(xy 4.2418 -2.144522) (xy 3.6957 -2.144522) (xy 3.6957 2.9464) (xy 1.7526 2.9464) (xy 1.7526 8.3566)
			)
			(stroke
				(width 0)
				(type default)
			)
			(fill no)
			(layer "F.CrtYd")
		)
		(fp_poly
			(pts
				(xy -2.2606 8.8646) (xy -2.2606 3.4544) (xy -4.2037 3.4544) (xy -4.2037 -1.2827) (xy -4.7498 -1.2827)
				(xy -4.7498 -4.4958) (xy -2.286 -4.4958) (xy -2.286 -2.3114) (xy 2.286 -2.3114) (xy 2.286 -4.4958)
				(xy 4.7498 -4.4958) (xy 4.7498 -1.2827) (xy 4.2037 -1.2827) (xy 4.2037 -0.5588) (xy 3.695954 -0.5588)
				(xy 3.695954 -2.144268) (xy 4.2418 -2.144268) (xy 4.2418 -2.855976) (xy 3.695954 -2.855976) (xy 3.695954 -3.988054)
				(xy 3.301746 -3.988054) (xy 3.301746 -1.7907) (xy -3.301746 -1.7907) (xy -3.301746 -3.988054) (xy -3.695954 -3.988054)
				(xy -3.695954 -2.855976) (xy -4.2418 -2.855976) (xy -4.2418 -2.144268) (xy -3.695954 -2.144268)
				(xy -3.695954 2.9464) (xy -1.752854 2.9464) (xy -1.752854 8.3566) (xy 1.752854 8.3566) (xy 1.752854 2.9464)
				(xy 3.695954 2.9464) (xy 3.695954 -0.5461) (xy 4.2037 -0.5461) (xy 4.2037 3.4544) (xy 2.2606 3.4544)
				(xy 2.2606 8.8646)
			)
			(stroke
				(width 0)
				(type default)
			)
			(fill no)
			(layer "F.CrtYd")
		)
		(fp_poly
			(pts
				(xy 2.2606 8.8646) (xy -2.2606 8.8646) (xy -2.2606 3.4544) (xy -4.2037 3.4544) (xy -4.2037 -1.2827)
				(xy -4.7498 -1.2827) (xy -4.7498 -4.4958) (xy -2.286 -4.4958) (xy -2.286 -2.3114) (xy 2.286 -2.3114)
				(xy 2.286 -4.4958) (xy 4.7498 -4.4958) (xy 4.7498 -1.2827) (xy 4.2037 -1.2827) (xy 4.2037 3.4544)
				(xy 2.2606 3.4544)
			)
			(stroke
				(width 0)
				(type default)
			)
			(fill no)
			(layer "F.Fab")
		)
		(pad "1" thru_hole circle
			(at -2.249932 0)
			(size 1.4224 1.4224)
			(drill 1.016)
			(layers "*.Cu" "*.Mask")
			(remove_unused_layers no)
			(net "FP_PWR_BTN_N")
			(clearance 0.1524)
			(thermal_gap 0.1524)
		)
		(pad "2" thru_hole circle
			(at 2.249932 0)
			(size 1.4224 1.4224)
			(drill 1.016)
			(layers "*.Cu" "*.Mask")
			(remove_unused_layers no)
			(net "GND")
			(clearance 0.1524)
			(thermal_gap 0.1524)
		)
		(pad "3" thru_hole circle
			(at -3.50012 -2.500122)
			(size 1.4224 1.4224)
			(drill 1.016)
			(layers "*.Cu" "*.Mask")
			(remove_unused_layers no)
			(net "PWR_BTN_GND")
			(clearance 0.1524)
			(thermal_gap 0.1524)
		)
		(pad "4" thru_hole circle
			(at 3.50012 -2.500122)
			(size 1.4224 1.4224)
			(drill 1.016)
			(layers "*.Cu" "*.Mask")
			(remove_unused_layers no)
			(net "PWR_BTN_GND")
			(clearance 0.1524)
			(thermal_gap 0.1524)
		)
	)
	(footprint ""
		(layer "F.Cu")
		(at 194.00012 -6.199886)
		(property "Reference" "LED2"
			(at 0 0 0)
			(layer "F.SilkS")
			(hide yes)
			(effects
				(font
					(size 1.27 1.27)
				)
			)
		)
		(property "Value" "LED-BY-14-GP"
			(at -4.7752 -2.1844 0)
			(unlocked yes)
			(layer "F.Fab")
			(hide yes)
			(effects
				(font
					(size 1.016 1.016)
					(thickness 0.1524)
				)
			)
		)
		(property "Device Type" "LED-100-3PH206"
			(at -4.7752 -3.7084 0)
			(unlocked yes)
			(layer "F.Fab")
			(hide yes)
			(effects
				(font
					(size 1.016 1.016)
					(thickness 0.1524)
				)
			)
		)
		(duplicate_pad_numbers_are_jumpers no)
		(fp_line
			(start -3.7592 -1.524)
			(end 3.7592 -1.524)
			(stroke
				(width 0.1524)
				(type default)
			)
			(layer "F.SilkS")
		)
		(fp_line
			(start -3.7592 8.0264)
			(end -3.7592 -1.524)
			(stroke
				(width 0.1524)
				(type default)
			)
			(layer "F.SilkS")
		)
		(fp_line
			(start -1.75387 1.04394)
			(end -1.75387 3.63474)
			(stroke
				(width 0.1524)
				(type default)
			)
			(layer "F.SilkS")
		)
		(fp_line
			(start -1.75387 2.33934)
			(end -3.45567 2.33934)
			(stroke
				(width 0.1524)
				(type default)
			)
			(layer "F.SilkS")
		)
		(fp_line
			(start -1.75387 3.63474)
			(end -0.45847 2.33934)
			(stroke
				(width 0.1524)
				(type default)
			)
			(layer "F.SilkS")
		)
		(fp_line
			(start -0.45847 2.33934)
			(end -1.75387 1.04394)
			(stroke
				(width 0.1524)
				(type default)
			)
			(layer "F.SilkS")
		)
		(fp_line
			(start -0.45847 2.33934)
			(end 0.58293 2.33934)
			(stroke
				(width 0.1524)
				(type default)
			)
			(layer "F.SilkS")
		)
		(fp_line
			(start -0.45847 3.05054)
			(end -0.45847 1.42494)
			(stroke
				(width 0.1524)
				(type default)
			)
			(layer "F.SilkS")
		)
		(fp_line
			(start 0.58293 2.33934)
			(end 1.87833 1.04394)
			(stroke
				(width 0.1524)
				(type default)
			)
			(layer "F.SilkS")
		)
		(fp_line
			(start 0.58293 3.05054)
			(end 0.58293 1.42494)
			(stroke
				(width 0.1524)
				(type default)
			)
			(layer "F.SilkS")
		)
		(fp_line
			(start 1.87833 1.04394)
			(end 1.87833 3.63474)
			(stroke
				(width 0.1524)
				(type default)
			)
			(layer "F.SilkS")
		)
		(fp_line
			(start 1.87833 2.33934)
			(end 2.81813 2.33934)
			(stroke
				(width 0.1524)
				(type default)
			)
			(layer "F.SilkS")
		)
		(fp_line
			(start 1.87833 3.63474)
			(end 0.58293 2.33934)
			(stroke
				(width 0.1524)
				(type default)
			)
			(layer "F.SilkS")
		)
		(fp_line
			(start 3.7592 -1.524)
			(end 3.7592 8.0264)
			(stroke
				(width 0.1524)
				(type default)
			)
			(layer "F.SilkS")
		)
		(fp_line
			(start 3.7592 8.0264)
			(end -3.7592 8.0264)
			(stroke
				(width 0.1524)
				(type default)
			)
			(layer "F.SilkS")
		)
		(fp_circle
			(center -2.54 0)
			(end -1.5494 0)
			(stroke
				(width 0.3048)
				(type default)
			)
			(fill no)
			(layer "F.SilkS")
		)
		(fp_circle
			(center 0 0)
			(end 0.9906 0)
			(stroke
				(width 0.3048)
				(type default)
			)
			(fill no)
			(layer "F.SilkS")
		)
		(fp_circle
			(center 2.54 0)
			(end 3.5306 0)
			(stroke
				(width 0.3048)
				(type default)
			)
			(fill no)
			(layer "F.SilkS")
		)
		(fp_rect
			(start -3.5052 7.7724)
			(end 3.5052 -1.27)
			(stroke
				(width 0)
				(type default)
			)
			(fill no)
			(layer "F.CrtYd")
		)
		(fp_poly
			(pts
				(xy -4.0132 8.2804) (xy -4.0132 -1.778) (xy -3.5052 -1.778) (xy -3.5052 7.7724) (xy 3.5052 7.7724)
				(xy 3.5052 -1.27) (xy -3.50012 -1.27) (xy -3.50012 -1.778) (xy 4.0132 -1.778) (xy 4.0132 8.2804)
			)
			(stroke
				(width 0)
				(type default)
			)
			(fill no)
			(layer "F.CrtYd")
		)
		(fp_rect
			(start -4.0132 8.2804)
			(end 4.0132 -1.778)
			(stroke
				(width 0)
				(type default)
			)
			(fill no)
			(layer "F.Fab")
		)
		(pad "1" thru_hole circle
			(at -2.54 0)
			(size 1.27 1.27)
			(drill 0.889)
			(layers "*.Cu" "*.Mask")
			(remove_unused_layers no)
			(net "EXT1_LED_BLUE")
			(clearance 0.1651)
			(thermal_gap 0.1651)
		)
		(pad "2" thru_hole circle
			(at 0 0)
			(size 1.27 1.27)
			(drill 0.889)
			(layers "*.Cu" "*.Mask")
			(remove_unused_layers no)
			(net "GND")
			(clearance 0.1651)
			(thermal_gap 0.1651)
		)
		(pad "3" thru_hole circle
			(at 2.54 0)
			(size 1.27 1.27)
			(drill 0.889)
			(layers "*.Cu" "*.Mask")
			(remove_unused_layers no)
			(net "EXT1_LED_YELLOW")
			(clearance 0.1651)
			(thermal_gap 0.1651)
		)
	)
	(footprint ""
		(layer "F.Cu")
		(at 215.9 -79.248 -45)
		(property "Reference" "VIA41"
			(at 0 0 315)
			(layer "F.SilkS")
			(hide yes)
			(effects
				(font
					(size 1.27 1.27)
				)
			)
		)
		(property "Value" "100OHM-8L-1D6MM-L18L16-GP"
			(at -3.721059 -4.508373 315)
			(unlocked yes)
			(layer "F.Fab")
			(hide yes)
			(effects
				(font
					(size 1.016 1.016)
					(thickness 0.1524)
				)
			)
		)
		(property "Device Type" "VIA-PCIE-4P-394076"
			(at -3.721059 -6.032502 315)
			(unlocked yes)
			(layer "F.Fab")
			(hide yes)
			(effects
				(font
					(size 1.016 1.016)
					(thickness 0.1524)
				)
			)
		)
		(duplicate_pad_numbers_are_jumpers no)
		(fp_poly
			(pts
				(xy -1.968472 -0.380877) (xy 1.968528 -0.380878) (xy 1.968527 0.381122) (xy -1.968472 0.381122)
			)
			(stroke
				(width 0)
				(type default)
			)
			(fill no)
			(layer "F.CrtYd")
		)
		(fp_poly
			(pts
				(xy -1.968472 -0.380877) (xy 1.968528 -0.380878) (xy 1.968527 0.381122) (xy -1.968472 0.381122)
			)
			(stroke
				(width 0)
				(type default)
			)
			(fill no)
			(layer "F.Fab")
		)
		(pad "1" thru_hole circle
			(at -1.5875 0 315)
			(size 0.508 0.508)
			(drill 0.254)
			(layers "*.Cu" "*.Mask")
			(remove_unused_layers no)
			(net "GND")
			(clearance 0.127)
			(thermal_gap 0.127)
		)
		(pad "2" thru_hole circle
			(at -0.571501 0 315)
			(size 0.508 0.508)
			(drill 0.254)
			(layers "*.Cu" "*.Mask")
			(remove_unused_layers no)
			(net "PHY_IOC_TO_CON_A_0_DP")
			(clearance 0.127)
			(thermal_gap 0.127)
		)
		(pad "3" thru_hole circle
			(at 0.571501 0 315)
			(size 0.508 0.508)
			(drill 0.254)
			(layers "*.Cu" "*.Mask")
			(remove_unused_layers no)
			(net "PHY_IOC_TO_CON_A_0_DN")
			(clearance 0.127)
			(thermal_gap 0.127)
		)
		(pad "4" thru_hole circle
			(at 1.5875 0 315)
			(size 0.508 0.508)
			(drill 0.254)
			(layers "*.Cu" "*.Mask")
			(remove_unused_layers no)
			(net "GND")
			(clearance 0.127)
			(thermal_gap 0.127)
		)
	)
	(footprint ""
		(layer "F.Cu")
		(at 98.9076 -152.9334 -90)
		(property "Reference" "R31"
			(at 0 0 270)
			(layer "F.SilkS")
			(hide yes)
			(effects
				(font
					(size 1.27 1.27)
				)
			)
		)
		(property "Value" "4K7R2F-GP"
			(at 0.064008 -3.993896 270)
			(unlocked yes)
			(layer "F.Fab")
			(hide yes)
			(effects
				(font
					(size 1.016 1.016)
					(thickness 0.1524)
				)
			)
		)
		(property "Device Type" "R402H16"
			(at 0.064008 -5.517896 270)
			(unlocked yes)
			(layer "F.Fab")
			(hide yes)
			(effects
				(font
					(size 1.016 1.016)
					(thickness 0.1524)
				)
			)
		)
		(duplicate_pad_numbers_are_jumpers no)
		(fp_line
			(start -0.508 -0.9398)
			(end -0.508 0.9398)
			(stroke
				(width 0.1524)
				(type default)
			)
			(layer "F.SilkS")
		)
		(fp_line
			(start 0.508 -0.9398)
			(end -0.508 -0.9398)
			(stroke
				(width 0.1524)
				(type default)
			)
			(layer "F.SilkS")
		)
		(fp_rect
			(start -0.508 0.9398)
			(end 0.508 -0.9398)
			(stroke
				(width 0)
				(type default)
			)
			(fill no)
			(layer "F.CrtYd")
		)
		(fp_rect
			(start -0.508 0.9398)
			(end 0.508 -0.9398)
			(stroke
				(width 0)
				(type default)
			)
			(fill no)
			(layer "F.Fab")
		)
		(pad "1" smd custom
			(at 0 -0.4445 270)
			(size 0.1397 0.1397)
			(layers "F.Cu" "F.Mask" "F.Paste")
			(net "P3V3_STBY")
			(options
				(clearance outline)
				(anchor circle)
			)
			(primitives
				(gr_poly
					(pts
						(arc
							(start -0.1778 -0.2794)
							(mid -0.249642 -0.249642)
							(end -0.2794 -0.1778)
						)
						(arc
							(start -0.2794 0.1778)
							(mid -0.249642 0.249642)
							(end -0.1778 0.2794)
						)
						(arc
							(start 0.1778 0.2794)
							(mid 0.249642 0.249642)
							(end 0.2794 0.1778)
						)
						(arc
							(start 0.2794 -0.1778)
							(mid 0.249642 -0.249642)
							(end 0.1778 -0.2794)
						)
					)
					(width 0)
					(fill yes)
				)
			)
		)
		(pad "2" smd custom
			(at 0 0.4445 270)
			(size 0.1397 0.1397)
			(layers "F.Cu" "F.Mask" "F.Paste")
			(net "USB_OCS_N4")
			(options
				(clearance outline)
				(anchor circle)
			)
			(primitives
				(gr_poly
					(pts
						(arc
							(start -0.1778 -0.2794)
							(mid -0.249642 -0.249642)
							(end -0.2794 -0.1778)
						)
						(arc
							(start -0.2794 0.1778)
							(mid -0.249642 0.249642)
							(end -0.1778 0.2794)
						)
						(arc
							(start 0.1778 0.2794)
							(mid 0.249642 0.249642)
							(end 0.2794 0.1778)
						)
						(arc
							(start 0.2794 -0.1778)
							(mid 0.249642 -0.249642)
							(end 0.1778 -0.2794)
						)
					)
					(width 0)
					(fill yes)
				)
			)
		)
	)
	(footprint ""
		(layer "F.Cu")
		(at 183.813704 -149.714966)
		(property "Reference" "C162"
			(at 0 0 0)
			(layer "F.SilkS")
			(hide yes)
			(effects
				(font
					(size 1.27 1.27)
				)
			)
		)
		(property "Value" "SC1KP50V2KX-1GP"
			(at 1.1811 -2.7051 0)
			(unlocked yes)
			(layer "F.Fab")
			(hide yes)
			(effects
				(font
					(size 1.016 1.016)
					(thickness 0.1524)
				)
			)
		)
		(property "Device Type" "C402H22"
			(at 1.181354 -4.2291 0)
			(unlocked yes)
			(layer "F.Fab")
			(hide yes)
			(effects
				(font
					(size 1.016 1.016)
					(thickness 0.1524)
				)
			)
		)
		(duplicate_pad_numbers_are_jumpers no)
		(fp_rect
			(start -0.4318 0.9525)
			(end 0.4318 -0.9525)
			(stroke
				(width 0)
				(type default)
			)
			(fill no)
			(layer "F.CrtYd")
		)
		(fp_rect
			(start -0.4318 0.9525)
			(end 0.4318 -0.9525)
			(stroke
				(width 0)
				(type default)
			)
			(fill no)
			(layer "F.Fab")
		)
		(pad "1" smd custom
			(at 0 -0.4445)
			(size 0.1524 0.1524)
			(layers "F.Cu" "F.Mask" "F.Paste")
			(net "P5V_LL_R")
			(options
				(clearance outline)
				(anchor circle)
			)
			(primitives
				(gr_poly
					(pts
						(arc
							(start 0.3048 -0.2032)
							(mid 0.275042 -0.275042)
							(end 0.2032 -0.3048)
						)
						(arc
							(start -0.2032 -0.3048)
							(mid -0.275042 -0.275042)
							(end -0.3048 -0.2032)
						)
						(arc
							(start -0.3048 0.2032)
							(mid -0.275042 0.275042)
							(end -0.2032 0.3048)
						)
						(arc
							(start 0.2032 0.3048)
							(mid 0.275042 0.275042)
							(end 0.3048 0.2032)
						)
					)
					(width 0)
					(fill yes)
				)
			)
		)
		(pad "2" smd custom
			(at 0 0.4445)
			(size 0.1524 0.1524)
			(layers "F.Cu" "F.Mask" "F.Paste")
			(net "P5V_VFB")
			(options
				(clearance outline)
				(anchor circle)
			)
			(primitives
				(gr_poly
					(pts
						(arc
							(start 0.3048 -0.2032)
							(mid 0.275042 -0.275042)
							(end 0.2032 -0.3048)
						)
						(arc
							(start -0.2032 -0.3048)
							(mid -0.275042 -0.275042)
							(end -0.3048 -0.2032)
						)
						(arc
							(start -0.3048 0.2032)
							(mid -0.275042 0.275042)
							(end -0.2032 0.3048)
						)
						(arc
							(start 0.2032 0.3048)
							(mid 0.275042 0.275042)
							(end 0.3048 0.2032)
						)
					)
					(width 0)
					(fill yes)
				)
			)
		)
	)
	(footprint ""
		(layer "F.Cu")
		(at 36.791646 -187.96381 -90)
		(property "Reference" "C180"
			(at 0 0 270)
			(layer "F.SilkS")
			(hide yes)
			(effects
				(font
					(size 1.27 1.27)
				)
			)
		)
		(property "Value" "SC2200P50V2KX-2GP"
			(at 1.1811 -2.7051 270)
			(unlocked yes)
			(layer "F.Fab")
			(hide yes)
			(effects
				(font
					(size 1.016 1.016)
					(thickness 0.1524)
				)
			)
		)
		(property "Device Type" "C402H22"
			(at 1.1811 -4.2291 270)
			(unlocked yes)
			(layer "F.Fab")
			(hide yes)
			(effects
				(font
					(size 1.016 1.016)
					(thickness 0.1524)
				)
			)
		)
		(duplicate_pad_numbers_are_jumpers no)
		(fp_rect
			(start -0.4318 0.9525)
			(end 0.4318 -0.9525)
			(stroke
				(width 0)
				(type default)
			)
			(fill no)
			(layer "F.CrtYd")
		)
		(fp_rect
			(start -0.4318 0.9525)
			(end 0.4318 -0.9525)
			(stroke
				(width 0)
				(type default)
			)
			(fill no)
			(layer "F.Fab")
		)
		(pad "1" smd custom
			(at 0 -0.4445 270)
			(size 0.1524 0.1524)
			(layers "F.Cu" "F.Mask" "F.Paste")
			(net "P3V3_STBY_LL")
			(options
				(clearance outline)
				(anchor circle)
			)
			(primitives
				(gr_poly
					(pts
						(arc
							(start 0.3048 -0.2032)
							(mid 0.275042 -0.275042)
							(end 0.2032 -0.3048)
						)
						(arc
							(start -0.2032 -0.3048)
							(mid -0.275042 -0.275042)
							(end -0.3048 -0.2032)
						)
						(arc
							(start -0.3048 0.2032)
							(mid -0.275042 0.275042)
							(end -0.2032 0.3048)
						)
						(arc
							(start 0.2032 0.3048)
							(mid 0.275042 0.275042)
							(end 0.3048 0.2032)
						)
					)
					(width 0)
					(fill yes)
				)
			)
		)
		(pad "2" smd custom
			(at 0 0.4445 270)
			(size 0.1524 0.1524)
			(layers "F.Cu" "F.Mask" "F.Paste")
			(net "P3V3_SNB")
			(options
				(clearance outline)
				(anchor circle)
			)
			(primitives
				(gr_poly
					(pts
						(arc
							(start 0.3048 -0.2032)
							(mid 0.275042 -0.275042)
							(end 0.2032 -0.3048)
						)
						(arc
							(start -0.2032 -0.3048)
							(mid -0.275042 -0.275042)
							(end -0.3048 -0.2032)
						)
						(arc
							(start -0.3048 0.2032)
							(mid -0.275042 0.275042)
							(end -0.2032 0.3048)
						)
						(arc
							(start 0.2032 0.3048)
							(mid 0.275042 0.275042)
							(end 0.3048 0.2032)
						)
					)
					(width 0)
					(fill yes)
				)
			)
		)
	)
	(footprint ""
		(layer "F.Cu")
		(at 173.519338 -61.06922 90)
		(property "Reference" "R582"
			(at 0 0 90)
			(layer "F.SilkS")
			(hide yes)
			(effects
				(font
					(size 1.27 1.27)
				)
			)
		)
		(property "Value" "2K2R2F-GP"
			(at 0.064008 -3.993896 90)
			(unlocked yes)
			(layer "F.Fab")
			(hide yes)
			(effects
				(font
					(size 1.016 1.016)
					(thickness 0.1524)
				)
			)
		)
		(property "Device Type" "R402H16"
			(at 0.064008 -5.517896 90)
			(unlocked yes)
			(layer "F.Fab")
			(hide yes)
			(effects
				(font
					(size 1.016 1.016)
					(thickness 0.1524)
				)
			)
		)
		(duplicate_pad_numbers_are_jumpers no)
		(fp_line
			(start 0.508 -0.9398)
			(end -0.508 -0.9398)
			(stroke
				(width 0.1524)
				(type default)
			)
			(layer "F.SilkS")
		)
		(fp_line
			(start -0.508 -0.9398)
			(end -0.508 0.9398)
			(stroke
				(width 0.1524)
				(type default)
			)
			(layer "F.SilkS")
		)
		(fp_rect
			(start -0.508 0.9398)
			(end 0.508 -0.9398)
			(stroke
				(width 0)
				(type default)
			)
			(fill no)
			(layer "F.CrtYd")
		)
		(fp_rect
			(start -0.508 0.9398)
			(end 0.508 -0.9398)
			(stroke
				(width 0)
				(type default)
			)
			(fill no)
			(layer "F.Fab")
		)
		(pad "1" smd custom
			(at 0 -0.4445 90)
			(size 0.1397 0.1397)
			(layers "F.Cu" "F.Mask" "F.Paste")
			(net "P1V8")
			(options
				(clearance outline)
				(anchor circle)
			)
			(primitives
				(gr_poly
					(pts
						(arc
							(start -0.1778 -0.2794)
							(mid -0.249642 -0.249642)
							(end -0.2794 -0.1778)
						)
						(arc
							(start -0.2794 0.1778)
							(mid -0.249642 0.249642)
							(end -0.1778 0.2794)
						)
						(arc
							(start 0.1778 0.2794)
							(mid 0.249642 0.249642)
							(end 0.2794 0.1778)
						)
						(arc
							(start 0.2794 -0.1778)
							(mid 0.249642 -0.249642)
							(end 0.1778 -0.2794)
						)
					)
					(width 0)
					(fill yes)
				)
			)
		)
		(pad "2" smd custom
			(at 0 0.4445 90)
			(size 0.1397 0.1397)
			(layers "F.Cu" "F.Mask" "F.Paste")
			(net "IOC_SCL_1")
			(options
				(clearance outline)
				(anchor circle)
			)
			(primitives
				(gr_poly
					(pts
						(arc
							(start -0.1778 -0.2794)
							(mid -0.249642 -0.249642)
							(end -0.2794 -0.1778)
						)
						(arc
							(start -0.2794 0.1778)
							(mid -0.249642 0.249642)
							(end -0.1778 0.2794)
						)
						(arc
							(start 0.1778 0.2794)
							(mid 0.249642 0.249642)
							(end 0.2794 0.1778)
						)
						(arc
							(start 0.2794 -0.1778)
							(mid 0.249642 -0.249642)
							(end 0.1778 -0.2794)
						)
					)
					(width 0)
					(fill yes)
				)
			)
		)
	)
	(footprint ""
		(layer "F.Cu")
		(at 60.9092 -121.3612 90)
		(property "Reference" "U29"
			(at 0 0 90)
			(layer "F.SilkS")
			(hide yes)
			(effects
				(font
					(size 1.27 1.27)
				)
			)
		)
		(property "Value" "MX25L25635FMI-10G-GP"
			(at 0 -14.6812 90)
			(unlocked yes)
			(layer "F.Fab")
			(hide yes)
			(effects
				(font
					(size 1.016 1.016)
					(thickness 0.1524)
				)
			)
		)
		(property "Device Type" "SOIC16-6H105"
			(at 0 -16.2052 90)
			(unlocked yes)
			(layer "F.Fab")
			(hide yes)
			(effects
				(font
					(size 1.016 1.016)
					(thickness 0.1524)
				)
			)
		)
		(duplicate_pad_numbers_are_jumpers no)
		(fp_line
			(start 4.7498 -3.2258)
			(end 4.7498 3.2258)
			(stroke
				(width 0.1524)
				(type default)
			)
			(layer "F.SilkS")
		)
		(fp_line
			(start -5.588 -3.2258)
			(end 4.7498 -3.2258)
			(stroke
				(width 0.1524)
				(type default)
			)
			(layer "F.SilkS")
		)
		(fp_line
			(start -5.588 -0.50038)
			(end -5.08762 0)
			(stroke
				(width 0.1524)
				(type default)
			)
			(layer "F.SilkS")
		)
		(fp_line
			(start -5.08762 0)
			(end -5.588 0.50038)
			(stroke
				(width 0.1524)
				(type default)
			)
			(layer "F.SilkS")
		)
		(fp_line
			(start 4.7498 3.2258)
			(end -5.588 3.2258)
			(stroke
				(width 0.1524)
				(type default)
			)
			(layer "F.SilkS")
		)
		(fp_line
			(start -5.4102 3.2258)
			(end -5.4102 5.7912)
			(stroke
				(width 0.508)
				(type default)
			)
			(layer "F.SilkS")
		)
		(fp_line
			(start -5.588 3.2258)
			(end -5.588 -3.2258)
			(stroke
				(width 0.1524)
				(type default)
			)
			(layer "F.SilkS")
		)
		(fp_poly
			(pts
				(xy -4.764786 -3.2258) (xy 4.7625 -3.2258) (xy 4.7625 3.2258) (xy -4.764786 3.2258)
			)
			(stroke
				(width 0)
				(type default)
			)
			(fill yes)
			(layer "F.SilkS")
		)
		(fp_poly
			(pts
				(xy -5.6642 6.0452) (xy 5.6642 6.0452) (xy 5.6642 -6.0452) (xy -5.6642 -6.0452)
			)
			(stroke
				(width 0)
				(type default)
			)
			(fill no)
			(layer "F.CrtYd")
		)
		(fp_poly
			(pts
				(xy -5.6642 -6.0452) (xy 5.6642 -6.0452) (xy 5.6642 6.0452) (xy -5.6642 6.0452)
			)
			(stroke
				(width 0)
				(type default)
			)
			(fill no)
			(layer "F.Fab")
		)
		(pad "1" smd rect
			(at -4.445 4.71805 90)
			(size 0.635 1.651)
			(layers "F.Cu" "F.Mask" "F.Paste")
			(net "PU_IBMC_BT_HOLD_N")
		)
		(pad "2" smd rect
			(at -3.175 4.71805 90)
			(size 0.635 1.651)
			(layers "F.Cu" "F.Mask" "F.Paste")
			(net "P3V3_STBY")
		)
		(pad "3" smd rect
			(at -1.905 4.71805 90)
			(size 0.635 1.651)
			(layers "F.Cu" "F.Mask" "F.Paste")
			(net "FLA1_SPI_RST")
		)
		(pad "4" smd rect
			(at -0.635 4.71805 90)
			(size 0.635 1.651)
			(layers "F.Cu" "F.Mask" "F.Paste")
			(net "Net_334")
		)
		(pad "5" smd rect
			(at 0.635 4.71805 90)
			(size 0.635 1.651)
			(layers "F.Cu" "F.Mask" "F.Paste")
			(net "Net_333")
		)
		(pad "6" smd rect
			(at 1.905 4.71805 90)
			(size 0.635 1.651)
			(layers "F.Cu" "F.Mask" "F.Paste")
			(net "Net_332")
		)
		(pad "7" smd rect
			(at 3.175 4.71805 90)
			(size 0.635 1.651)
			(layers "F.Cu" "F.Mask" "F.Paste")
			(net "FLA_CS_1_R")
		)
		(pad "8" smd rect
			(at 4.445 4.71805 90)
			(size 0.635 1.651)
			(layers "F.Cu" "F.Mask" "F.Paste")
			(net "BMC_SPI_MISO_R")
		)
		(pad "9" smd rect
			(at 4.445 -4.71805 90)
			(size 0.635 1.651)
			(layers "F.Cu" "F.Mask" "F.Paste")
			(net "FLA1_WP_N")
		)
		(pad "10" smd rect
			(at 3.175 -4.71805 90)
			(size 0.635 1.651)
			(layers "F.Cu" "F.Mask" "F.Paste")
			(net "GND")
		)
		(pad "11" smd rect
			(at 1.905 -4.71805 90)
			(size 0.635 1.651)
			(layers "F.Cu" "F.Mask" "F.Paste")
			(net "Net_331")
		)
		(pad "12" smd rect
			(at 0.635 -4.71805 90)
			(size 0.635 1.651)
			(layers "F.Cu" "F.Mask" "F.Paste")
			(net "Net_330")
		)
		(pad "13" smd rect
			(at -0.635 -4.71805 90)
			(size 0.635 1.651)
			(layers "F.Cu" "F.Mask" "F.Paste")
			(net "Net_329")
		)
		(pad "14" smd rect
			(at -1.905 -4.71805 90)
			(size 0.635 1.651)
			(layers "F.Cu" "F.Mask" "F.Paste")
			(net "Net_328")
		)
		(pad "15" smd rect
			(at -3.175 -4.71805 90)
			(size 0.635 1.651)
			(layers "F.Cu" "F.Mask" "F.Paste")
			(net "BMC_SPI_MOSI_R")
		)
		(pad "16" smd rect
			(at -4.445 -4.71805 90)
			(size 0.635 1.651)
			(layers "F.Cu" "F.Mask" "F.Paste")
			(net "BMC_SPI_CLK_R")
		)
	)
	(footprint ""
		(layer "F.Cu")
		(at 208.055972 -76.708 90)
		(property "Reference" "C307"
			(at 0 0 90)
			(layer "F.SilkS")
			(hide yes)
			(effects
				(font
					(size 1.27 1.27)
				)
			)
		)
		(property "Value" "SCD01U16V1KX-GP"
			(at -2.8321 -1.7399 90)
			(unlocked yes)
			(layer "F.Fab")
			(hide yes)
			(effects
				(font
					(size 1.016 1.016)
					(thickness 0.1524)
				)
			)
		)
		(property "Device Type" "C0201H13"
			(at -2.8321 -3.2639 90)
			(unlocked yes)
			(layer "F.Fab")
			(hide yes)
			(effects
				(font
					(size 1.016 1.016)
					(thickness 0.1524)
				)
			)
		)
		(duplicate_pad_numbers_are_jumpers no)
		(fp_rect
			(start -0.2794 0.6477)
			(end 0.2794 -0.6477)
			(stroke
				(width 0)
				(type default)
			)
			(fill no)
			(layer "F.CrtYd")
		)
		(fp_rect
			(start -0.2794 0.6477)
			(end 0.2794 -0.6477)
			(stroke
				(width 0)
				(type default)
			)
			(fill no)
			(layer "F.Fab")
		)
		(pad "1" smd custom
			(at 0 -0.2794 90)
			(size 0.0762 0.0762)
			(layers "F.Cu" "F.Mask" "F.Paste")
			(net "PHY_IOC_TO_CON_A_0_DP_C")
			(options
				(clearance outline)
				(anchor circle)
			)
			(primitives
				(gr_poly
					(pts
						(arc
							(start 0.1524 -0.127)
							(mid 0.137521 -0.162921)
							(end 0.1016 -0.1778)
						)
						(arc
							(start -0.1016 -0.1778)
							(mid -0.137521 -0.162921)
							(end -0.1524 -0.127)
						)
						(arc
							(start -0.1524 0.127)
							(mid -0.137521 0.162921)
							(end -0.1016 0.1778)
						)
						(arc
							(start 0.1016 0.1778)
							(mid 0.137521 0.162921)
							(end 0.1524 0.127)
						)
					)
					(width 0)
					(fill yes)
				)
			)
		)
		(pad "2" smd custom
			(at 0 0.2794 90)
			(size 0.0762 0.0762)
			(layers "F.Cu" "F.Mask" "F.Paste")
			(net "PHY_IOC_TO_CON_A_0_DP")
			(options
				(clearance outline)
				(anchor circle)
			)
			(primitives
				(gr_poly
					(pts
						(arc
							(start 0.1524 -0.127)
							(mid 0.137521 -0.162921)
							(end 0.1016 -0.1778)
						)
						(arc
							(start -0.1016 -0.1778)
							(mid -0.137521 -0.162921)
							(end -0.1524 -0.127)
						)
						(arc
							(start -0.1524 0.127)
							(mid -0.137521 0.162921)
							(end -0.1016 0.1778)
						)
						(arc
							(start 0.1016 0.1778)
							(mid 0.137521 0.162921)
							(end 0.1524 0.127)
						)
					)
					(width 0)
					(fill yes)
				)
			)
		)
	)
	(footprint ""
		(layer "F.Cu")
		(at 98.050858 -17.91716 180)
		(property "Reference" "R46"
			(at 0 0 180)
			(layer "F.SilkS")
			(hide yes)
			(effects
				(font
					(size 1.27 1.27)
				)
			)
		)
		(property "Value" "0R2J-2-GP"
			(at 0.064008 -3.993896 180)
			(unlocked yes)
			(layer "F.Fab")
			(hide yes)
			(effects
				(font
					(size 1.016 1.016)
					(thickness 0.1524)
				)
			)
		)
		(property "Device Type" "R402H16"
			(at 0.064008 -5.517896 180)
			(unlocked yes)
			(layer "F.Fab")
			(hide yes)
			(effects
				(font
					(size 1.016 1.016)
					(thickness 0.1524)
				)
			)
		)
		(duplicate_pad_numbers_are_jumpers no)
		(fp_line
			(start 0.508 -0.9398)
			(end -0.508 -0.9398)
			(stroke
				(width 0.1524)
				(type default)
			)
			(layer "F.SilkS")
		)
		(fp_line
			(start -0.508 -0.9398)
			(end -0.508 0.9398)
			(stroke
				(width 0.1524)
				(type default)
			)
			(layer "F.SilkS")
		)
		(fp_rect
			(start -0.508 0.9398)
			(end 0.508 -0.9398)
			(stroke
				(width 0)
				(type default)
			)
			(fill no)
			(layer "F.CrtYd")
		)
		(fp_rect
			(start -0.508 0.9398)
			(end 0.508 -0.9398)
			(stroke
				(width 0)
				(type default)
			)
			(fill no)
			(layer "F.Fab")
		)
		(pad "1" smd custom
			(at 0 -0.4445 180)
			(size 0.1397 0.1397)
			(layers "F.Cu" "F.Mask" "F.Paste")
			(net "USB_P1_F_DN1")
			(options
				(clearance outline)
				(anchor circle)
			)
			(primitives
				(gr_poly
					(pts
						(arc
							(start -0.1778 -0.2794)
							(mid -0.249642 -0.249642)
							(end -0.2794 -0.1778)
						)
						(arc
							(start -0.2794 0.1778)
							(mid -0.249642 0.249642)
							(end -0.1778 0.2794)
						)
						(arc
							(start 0.1778 0.2794)
							(mid 0.249642 0.249642)
							(end 0.2794 0.1778)
						)
						(arc
							(start 0.2794 -0.1778)
							(mid 0.249642 -0.249642)
							(end 0.1778 -0.2794)
						)
					)
					(width 0)
					(fill yes)
				)
			)
		)
		(pad "2" smd custom
			(at 0 0.4445 180)
			(size 0.1397 0.1397)
			(layers "F.Cu" "F.Mask" "F.Paste")
			(net "USB_P1_DN")
			(options
				(clearance outline)
				(anchor circle)
			)
			(primitives
				(gr_poly
					(pts
						(arc
							(start -0.1778 -0.2794)
							(mid -0.249642 -0.249642)
							(end -0.2794 -0.1778)
						)
						(arc
							(start -0.2794 0.1778)
							(mid -0.249642 0.249642)
							(end -0.1778 0.2794)
						)
						(arc
							(start 0.1778 0.2794)
							(mid 0.249642 0.249642)
							(end 0.2794 0.1778)
						)
						(arc
							(start 0.2794 -0.1778)
							(mid 0.249642 -0.249642)
							(end 0.1778 -0.2794)
						)
					)
					(width 0)
					(fill yes)
				)
			)
		)
	)
	(footprint ""
		(layer "F.Cu")
		(at 39.585646 -177.14341 180)
		(property "Reference" "R482"
			(at 0 0 180)
			(layer "F.SilkS")
			(hide yes)
			(effects
				(font
					(size 1.27 1.27)
				)
			)
		)
		(property "Value" "10KR2J-3-GP"
			(at 0.064008 -3.993896 180)
			(unlocked yes)
			(layer "F.Fab")
			(hide yes)
			(effects
				(font
					(size 1.016 1.016)
					(thickness 0.1524)
				)
			)
		)
		(property "Device Type" "R402H16"
			(at 0.064008 -5.517896 180)
			(unlocked yes)
			(layer "F.Fab")
			(hide yes)
			(effects
				(font
					(size 1.016 1.016)
					(thickness 0.1524)
				)
			)
		)
		(duplicate_pad_numbers_are_jumpers no)
		(fp_line
			(start 0.508 -0.9398)
			(end -0.508 -0.9398)
			(stroke
				(width 0.1524)
				(type default)
			)
			(layer "F.SilkS")
		)
		(fp_line
			(start -0.508 -0.9398)
			(end -0.508 0.9398)
			(stroke
				(width 0.1524)
				(type default)
			)
			(layer "F.SilkS")
		)
		(fp_rect
			(start -0.508 0.9398)
			(end 0.508 -0.9398)
			(stroke
				(width 0)
				(type default)
			)
			(fill no)
			(layer "F.CrtYd")
		)
		(fp_rect
			(start -0.508 0.9398)
			(end 0.508 -0.9398)
			(stroke
				(width 0)
				(type default)
			)
			(fill no)
			(layer "F.Fab")
		)
		(pad "1" smd custom
			(at 0 -0.4445 180)
			(size 0.1397 0.1397)
			(layers "F.Cu" "F.Mask" "F.Paste")
			(net "P12V_STBY")
			(options
				(clearance outline)
				(anchor circle)
			)
			(primitives
				(gr_poly
					(pts
						(arc
							(start -0.1778 -0.2794)
							(mid -0.249642 -0.249642)
							(end -0.2794 -0.1778)
						)
						(arc
							(start -0.2794 0.1778)
							(mid -0.249642 0.249642)
							(end -0.1778 0.2794)
						)
						(arc
							(start 0.1778 0.2794)
							(mid 0.249642 0.249642)
							(end 0.2794 0.1778)
						)
						(arc
							(start 0.2794 -0.1778)
							(mid 0.249642 -0.249642)
							(end 0.1778 -0.2794)
						)
					)
					(width 0)
					(fill yes)
				)
			)
		)
		(pad "2" smd custom
			(at 0 0.4445 180)
			(size 0.1397 0.1397)
			(layers "F.Cu" "F.Mask" "F.Paste")
			(net "P3V3_STBY_EN")
			(options
				(clearance outline)
				(anchor circle)
			)
			(primitives
				(gr_poly
					(pts
						(arc
							(start -0.1778 -0.2794)
							(mid -0.249642 -0.249642)
							(end -0.2794 -0.1778)
						)
						(arc
							(start -0.2794 0.1778)
							(mid -0.249642 0.249642)
							(end -0.1778 0.2794)
						)
						(arc
							(start 0.1778 0.2794)
							(mid 0.249642 0.249642)
							(end 0.2794 0.1778)
						)
						(arc
							(start 0.2794 -0.1778)
							(mid 0.249642 -0.249642)
							(end 0.1778 -0.2794)
						)
					)
					(width 0)
					(fill yes)
				)
			)
		)
	)
	(footprint ""
		(layer "F.Cu")
		(at 59.436 -158.623)
		(property "Reference" "R396"
			(at 0 0 0)
			(layer "F.SilkS")
			(hide yes)
			(effects
				(font
					(size 1.27 1.27)
				)
			)
		)
		(property "Value" "4K7R2F-GP"
			(at 0.064008 -3.993896 0)
			(unlocked yes)
			(layer "F.Fab")
			(hide yes)
			(effects
				(font
					(size 1.016 1.016)
					(thickness 0.1524)
				)
			)
		)
		(property "Device Type" "R402H16"
			(at 0.064008 -5.517896 0)
			(unlocked yes)
			(layer "F.Fab")
			(hide yes)
			(effects
				(font
					(size 1.016 1.016)
					(thickness 0.1524)
				)
			)
		)
		(duplicate_pad_numbers_are_jumpers no)
		(fp_line
			(start -0.508 -0.9398)
			(end -0.508 0.9398)
			(stroke
				(width 0.1524)
				(type default)
			)
			(layer "F.SilkS")
		)
		(fp_line
			(start 0.508 -0.9398)
			(end -0.508 -0.9398)
			(stroke
				(width 0.1524)
				(type default)
			)
			(layer "F.SilkS")
		)
		(fp_rect
			(start -0.508 0.9398)
			(end 0.508 -0.9398)
			(stroke
				(width 0)
				(type default)
			)
			(fill no)
			(layer "F.CrtYd")
		)
		(fp_rect
			(start -0.508 0.9398)
			(end 0.508 -0.9398)
			(stroke
				(width 0)
				(type default)
			)
			(fill no)
			(layer "F.Fab")
		)
		(pad "1" smd custom
			(at 0 -0.4445)
			(size 0.1397 0.1397)
			(layers "F.Cu" "F.Mask" "F.Paste")
			(net "GND")
			(options
				(clearance outline)
				(anchor circle)
			)
			(primitives
				(gr_poly
					(pts
						(arc
							(start -0.1778 -0.2794)
							(mid -0.249642 -0.249642)
							(end -0.2794 -0.1778)
						)
						(arc
							(start -0.2794 0.1778)
							(mid -0.249642 0.249642)
							(end -0.1778 0.2794)
						)
						(arc
							(start 0.1778 0.2794)
							(mid 0.249642 0.249642)
							(end 0.2794 0.1778)
						)
						(arc
							(start 0.2794 -0.1778)
							(mid 0.249642 -0.249642)
							(end 0.1778 -0.2794)
						)
					)
					(width 0)
					(fill yes)
				)
			)
		)
		(pad "2" smd custom
			(at 0 0.4445)
			(size 0.1397 0.1397)
			(layers "F.Cu" "F.Mask" "F.Paste")
			(net "MAC2_TXD0")
			(options
				(clearance outline)
				(anchor circle)
			)
			(primitives
				(gr_poly
					(pts
						(arc
							(start -0.1778 -0.2794)
							(mid -0.249642 -0.249642)
							(end -0.2794 -0.1778)
						)
						(arc
							(start -0.2794 0.1778)
							(mid -0.249642 0.249642)
							(end -0.1778 0.2794)
						)
						(arc
							(start 0.1778 0.2794)
							(mid 0.249642 0.249642)
							(end 0.2794 0.1778)
						)
						(arc
							(start 0.2794 -0.1778)
							(mid 0.249642 -0.249642)
							(end 0.1778 -0.2794)
						)
					)
					(width 0)
					(fill yes)
				)
			)
		)
	)
	(footprint ""
		(layer "F.Cu")
		(at 68.5038 -119.4562 -90)
		(property "Reference" "R266"
			(at 0 0 270)
			(layer "F.SilkS")
			(hide yes)
			(effects
				(font
					(size 1.27 1.27)
				)
			)
		)
		(property "Value" "2K2R2J-2-GP"
			(at 0.064008 -3.993896 270)
			(unlocked yes)
			(layer "F.Fab")
			(hide yes)
			(effects
				(font
					(size 1.016 1.016)
					(thickness 0.1524)
				)
			)
		)
		(property "Device Type" "R402H16"
			(at 0.064008 -5.517896 270)
			(unlocked yes)
			(layer "F.Fab")
			(hide yes)
			(effects
				(font
					(size 1.016 1.016)
					(thickness 0.1524)
				)
			)
		)
		(duplicate_pad_numbers_are_jumpers no)
		(fp_line
			(start -0.508 -0.9398)
			(end -0.508 0.9398)
			(stroke
				(width 0.1524)
				(type default)
			)
			(layer "F.SilkS")
		)
		(fp_line
			(start 0.508 -0.9398)
			(end -0.508 -0.9398)
			(stroke
				(width 0.1524)
				(type default)
			)
			(layer "F.SilkS")
		)
		(fp_rect
			(start -0.508 0.9398)
			(end 0.508 -0.9398)
			(stroke
				(width 0)
				(type default)
			)
			(fill no)
			(layer "F.CrtYd")
		)
		(fp_rect
			(start -0.508 0.9398)
			(end 0.508 -0.9398)
			(stroke
				(width 0)
				(type default)
			)
			(fill no)
			(layer "F.Fab")
		)
		(pad "1" smd custom
			(at 0 -0.4445 270)
			(size 0.1397 0.1397)
			(layers "F.Cu" "F.Mask" "F.Paste")
			(net "P3V3_STBY")
			(options
				(clearance outline)
				(anchor circle)
			)
			(primitives
				(gr_poly
					(pts
						(arc
							(start -0.1778 -0.2794)
							(mid -0.249642 -0.249642)
							(end -0.2794 -0.1778)
						)
						(arc
							(start -0.2794 0.1778)
							(mid -0.249642 0.249642)
							(end -0.1778 0.2794)
						)
						(arc
							(start 0.1778 0.2794)
							(mid 0.249642 0.249642)
							(end 0.2794 0.1778)
						)
						(arc
							(start 0.2794 -0.1778)
							(mid 0.249642 -0.249642)
							(end 0.1778 -0.2794)
						)
					)
					(width 0)
					(fill yes)
				)
			)
		)
		(pad "2" smd custom
			(at 0 0.4445 270)
			(size 0.1397 0.1397)
			(layers "F.Cu" "F.Mask" "F.Paste")
			(net "FLA1_SPI_RST")
			(options
				(clearance outline)
				(anchor circle)
			)
			(primitives
				(gr_poly
					(pts
						(arc
							(start -0.1778 -0.2794)
							(mid -0.249642 -0.249642)
							(end -0.2794 -0.1778)
						)
						(arc
							(start -0.2794 0.1778)
							(mid -0.249642 0.249642)
							(end -0.1778 0.2794)
						)
						(arc
							(start 0.1778 0.2794)
							(mid 0.249642 0.249642)
							(end 0.2794 0.1778)
						)
						(arc
							(start 0.2794 -0.1778)
							(mid 0.249642 -0.249642)
							(end 0.1778 -0.2794)
						)
					)
					(width 0)
					(fill yes)
				)
			)
		)
	)
	(footprint ""
		(layer "F.Cu")
		(at 177.3682 -62.1792 90)
		(property "Reference" "R624"
			(at 0 0 90)
			(layer "F.SilkS")
			(hide yes)
			(effects
				(font
					(size 1.27 1.27)
				)
			)
		)
		(property "Value" "10KR2F-2-GP"
			(at 0.064008 -3.993896 90)
			(unlocked yes)
			(layer "F.Fab")
			(hide yes)
			(effects
				(font
					(size 1.016 1.016)
					(thickness 0.1524)
				)
			)
		)
		(property "Device Type" "R402H16"
			(at 0.064008 -5.517896 90)
			(unlocked yes)
			(layer "F.Fab")
			(hide yes)
			(effects
				(font
					(size 1.016 1.016)
					(thickness 0.1524)
				)
			)
		)
		(duplicate_pad_numbers_are_jumpers no)
		(fp_line
			(start 0.508 -0.9398)
			(end -0.508 -0.9398)
			(stroke
				(width 0.1524)
				(type default)
			)
			(layer "F.SilkS")
		)
		(fp_line
			(start -0.508 -0.9398)
			(end -0.508 0.9398)
			(stroke
				(width 0.1524)
				(type default)
			)
			(layer "F.SilkS")
		)
		(fp_rect
			(start -0.508 0.9398)
			(end 0.508 -0.9398)
			(stroke
				(width 0)
				(type default)
			)
			(fill no)
			(layer "F.CrtYd")
		)
		(fp_rect
			(start -0.508 0.9398)
			(end 0.508 -0.9398)
			(stroke
				(width 0)
				(type default)
			)
			(fill no)
			(layer "F.Fab")
		)
		(pad "1" smd custom
			(at 0 -0.4445 90)
			(size 0.1397 0.1397)
			(layers "F.Cu" "F.Mask" "F.Paste")
			(net "GND")
			(options
				(clearance outline)
				(anchor circle)
			)
			(primitives
				(gr_poly
					(pts
						(arc
							(start -0.1778 -0.2794)
							(mid -0.249642 -0.249642)
							(end -0.2794 -0.1778)
						)
						(arc
							(start -0.2794 0.1778)
							(mid -0.249642 0.249642)
							(end -0.1778 0.2794)
						)
						(arc
							(start 0.1778 0.2794)
							(mid 0.249642 0.249642)
							(end 0.2794 0.1778)
						)
						(arc
							(start 0.2794 -0.1778)
							(mid 0.249642 -0.249642)
							(end 0.1778 -0.2794)
						)
					)
					(width 0)
					(fill yes)
				)
			)
		)
		(pad "2" smd custom
			(at 0 0.4445 90)
			(size 0.1397 0.1397)
			(layers "F.Cu" "F.Mask" "F.Paste")
			(net "MEM_CLK_SEL")
			(options
				(clearance outline)
				(anchor circle)
			)
			(primitives
				(gr_poly
					(pts
						(arc
							(start -0.1778 -0.2794)
							(mid -0.249642 -0.249642)
							(end -0.2794 -0.1778)
						)
						(arc
							(start -0.2794 0.1778)
							(mid -0.249642 0.249642)
							(end -0.1778 0.2794)
						)
						(arc
							(start 0.1778 0.2794)
							(mid 0.249642 0.249642)
							(end 0.2794 0.1778)
						)
						(arc
							(start 0.2794 -0.1778)
							(mid 0.249642 -0.249642)
							(end 0.1778 -0.2794)
						)
					)
					(width 0)
					(fill yes)
				)
			)
		)
	)
	(footprint ""
		(layer "F.Cu")
		(at 77.8002 -162.2044 -90)
		(property "Reference" "PU11"
			(at 0 0 270)
			(layer "F.SilkS")
			(hide yes)
			(effects
				(font
					(size 1.27 1.27)
				)
			)
		)
		(property "Value" "TPS74801RGW-GP"
			(at -4.7244 -6.223 270)
			(unlocked yes)
			(layer "F.Fab")
			(hide yes)
			(effects
				(font
					(size 1.016 1.016)
					(thickness 0.1524)
				)
			)
		)
		(property "Device Type" "QFN20-1G3D15H40"
			(at -4.7244 -7.747 270)
			(unlocked yes)
			(layer "F.Fab")
			(hide yes)
			(effects
				(font
					(size 1.016 1.016)
					(thickness 0.1524)
				)
			)
		)
		(duplicate_pad_numbers_are_jumpers no)
		(fp_line
			(start -3.5179 3.5179)
			(end -2.2479 3.5179)
			(stroke
				(width 0.1524)
				(type default)
			)
			(layer "F.SilkS")
		)
		(fp_line
			(start 2.2479 3.5179)
			(end 3.5179 3.5179)
			(stroke
				(width 0.1524)
				(type default)
			)
			(layer "F.SilkS")
		)
		(fp_line
			(start 3.5179 3.5179)
			(end 3.5179 2.2479)
			(stroke
				(width 0.1524)
				(type default)
			)
			(layer "F.SilkS")
		)
		(fp_line
			(start 1.299972 3.160522)
			(end 1.299972 3.668522)
			(stroke
				(width 0.1524)
				(type default)
			)
			(layer "F.SilkS")
		)
		(fp_line
			(start -3.5179 2.2479)
			(end -3.5179 3.5179)
			(stroke
				(width 0.1524)
				(type default)
			)
			(layer "F.SilkS")
		)
		(fp_line
			(start -3.160522 1.299972)
			(end -3.922522 1.299972)
			(stroke
				(width 0.1524)
				(type default)
			)
			(layer "F.SilkS")
		)
		(fp_line
			(start 3.160522 -1.299972)
			(end 3.922522 -1.299972)
			(stroke
				(width 0.1524)
				(type default)
			)
			(layer "F.SilkS")
		)
		(fp_line
			(start -1.299972 -3.160522)
			(end -1.299972 -3.668522)
			(stroke
				(width 0.1524)
				(type default)
			)
			(layer "F.SilkS")
		)
		(fp_line
			(start -3.5179 -3.5179)
			(end -3.5179 -2.2479)
			(stroke
				(width 0.1524)
				(type default)
			)
			(layer "F.SilkS")
		)
		(fp_line
			(start -2.2479 -3.5179)
			(end -3.5179 -3.5179)
			(stroke
				(width 0.1524)
				(type default)
			)
			(layer "F.SilkS")
		)
		(fp_poly
			(pts
				(xy 3.5179 -3.5179) (xy 2.2479 -3.5179) (xy 3.5179 -2.2479)
			)
			(stroke
				(width 0)
				(type default)
			)
			(fill yes)
			(layer "F.SilkS")
		)
		(fp_rect
			(start -2.5019 2.5019)
			(end 2.5019 -2.5019)
			(stroke
				(width 0)
				(type default)
			)
			(fill no)
			(layer "F.CrtYd")
		)
		(fp_poly
			(pts
				(xy -3.5179 3.5179) (xy -3.5179 -3.5179) (xy 3.5179 -3.5179) (xy 3.5179 -2.5019) (xy -2.5019 -2.5019)
				(xy -2.5019 2.5019) (xy 2.5019 2.5019) (xy 2.5019 -2.49682) (xy 3.5179 -2.49682) (xy 3.5179 3.5179)
			)
			(stroke
				(width 0)
				(type default)
			)
			(fill no)
			(layer "F.CrtYd")
		)
		(fp_rect
			(start -3.5179 3.5179)
			(end 3.5179 -3.5179)
			(stroke
				(width 0)
				(type default)
			)
			(fill no)
			(layer "F.Fab")
		)
		(pad "1" smd rect
			(at 1.299972 -2.474722 270)
			(size 0.3556 1.0668)
			(layers "F.Cu" "F.Mask" "F.Paste")
			(net "TPS74801_P1V15_STBY_OUT")
		)
		(pad "2" smd rect
			(at 0.649986 -2.474722 270)
			(size 0.3556 1.0668)
			(layers "F.Cu" "F.Mask" "F.Paste")
			(net "GND")
		)
		(pad "3" smd rect
			(at 0 -2.474722 270)
			(size 0.3556 1.0668)
			(layers "F.Cu" "F.Mask" "F.Paste")
			(net "GND")
		)
		(pad "4" smd rect
			(at -0.649986 -2.474722 270)
			(size 0.3556 1.0668)
			(layers "F.Cu" "F.Mask" "F.Paste")
			(net "GND")
		)
		(pad "5" smd rect
			(at -1.299972 -2.474722 270)
			(size 0.3556 1.0668)
			(layers "F.Cu" "F.Mask" "F.Paste")
			(net "P1V8_STBY")
		)
		(pad "6" smd rect
			(at -2.474722 -1.299972 270)
			(size 1.0668 0.3556)
			(layers "F.Cu" "F.Mask" "F.Paste")
			(net "P1V8_STBY")
		)
		(pad "7" smd rect
			(at -2.474722 -0.649986 270)
			(size 1.0668 0.3556)
			(layers "F.Cu" "F.Mask" "F.Paste")
			(net "P1V8_STBY")
		)
		(pad "8" smd rect
			(at -2.474722 0 270)
			(size 1.0668 0.3556)
			(layers "F.Cu" "F.Mask" "F.Paste")
			(net "P1V8_STBY")
		)
		(pad "9" smd rect
			(at -2.474722 0.649986 270)
			(size 1.0668 0.3556)
			(layers "F.Cu" "F.Mask" "F.Paste")
			(net "P1V15_STBY_PG")
		)
		(pad "10" smd rect
			(at -2.474722 1.299972 270)
			(size 1.0668 0.3556)
			(layers "F.Cu" "F.Mask" "F.Paste")
			(net "TPS74801_P1V15_STBY_BIAS")
		)
		(pad "11" smd rect
			(at -1.299972 2.474722 270)
			(size 0.3556 1.0668)
			(layers "F.Cu" "F.Mask" "F.Paste")
			(net "TPS74801_P1V15_STBY_EN")
		)
		(pad "12" smd rect
			(at -0.649986 2.474722 270)
			(size 0.3556 1.0668)
			(layers "F.Cu" "F.Mask" "F.Paste")
			(net "GND")
		)
		(pad "13" smd rect
			(at 0 2.474722 270)
			(size 0.3556 1.0668)
			(layers "F.Cu" "F.Mask" "F.Paste")
			(net "GND")
		)
		(pad "14" smd rect
			(at 0.649986 2.474722 270)
			(size 0.3556 1.0668)
			(layers "F.Cu" "F.Mask" "F.Paste")
			(net "GND")
		)
		(pad "15" smd rect
			(at 1.299972 2.474722 270)
			(size 0.3556 1.0668)
			(layers "F.Cu" "F.Mask" "F.Paste")
			(net "TPS74801_P1V15_STBY_SS")
		)
		(pad "16" smd rect
			(at 2.474722 1.299972 270)
			(size 1.0668 0.3556)
			(layers "F.Cu" "F.Mask" "F.Paste")
			(net "TPS74801_P1V15_STBY_FB")
		)
		(pad "17" smd rect
			(at 2.474722 0.649986 270)
			(size 1.0668 0.3556)
			(layers "F.Cu" "F.Mask" "F.Paste")
			(net "GND")
		)
		(pad "18" smd rect
			(at 2.474722 0 270)
			(size 1.0668 0.3556)
			(layers "F.Cu" "F.Mask" "F.Paste")
			(net "TPS74801_P1V15_STBY_OUT")
		)
		(pad "19" smd rect
			(at 2.474722 -0.649986 270)
			(size 1.0668 0.3556)
			(layers "F.Cu" "F.Mask" "F.Paste")
			(net "TPS74801_P1V15_STBY_OUT")
		)
		(pad "20" smd rect
			(at 2.474722 -1.299972 270)
			(size 1.0668 0.3556)
			(layers "F.Cu" "F.Mask" "F.Paste")
			(net "TPS74801_P1V15_STBY_OUT")
		)
		(pad "21" smd rect
			(at 0 0 270)
			(size 3.2512 3.2512)
			(layers "F.Cu" "F.Mask" "F.Paste")
			(net "GND")
		)
	)
	(footprint ""
		(layer "F.Cu")
		(at 93.7006 -124.5362 180)
		(property "Reference" "U46"
			(at 0 0 180)
			(layer "F.SilkS")
			(hide yes)
			(effects
				(font
					(size 1.27 1.27)
				)
			)
		)
		(property "Value" "SN74LVC1G08DCKR-GP"
			(at -2.3368 -8.6868 180)
			(unlocked yes)
			(layer "F.Fab")
			(hide yes)
			(effects
				(font
					(size 1.016 1.016)
					(thickness 0.1524)
				)
			)
		)
		(property "Device Type" "SC70-5H44"
			(at -2.3114 -10.414 180)
			(unlocked yes)
			(layer "F.Fab")
			(hide yes)
			(effects
				(font
					(size 1.016 1.016)
					(thickness 0.1524)
				)
			)
		)
		(duplicate_pad_numbers_are_jumpers no)
		(fp_line
			(start 1.3843 -1.8034)
			(end 1.3843 -1.1176)
			(stroke
				(width 0.3302)
				(type default)
			)
			(layer "F.SilkS")
		)
		(fp_line
			(start 1.27 1.7018)
			(end -1.27 1.7018)
			(stroke
				(width 0.1524)
				(type default)
			)
			(layer "F.SilkS")
		)
		(fp_line
			(start 1.27 -1.7018)
			(end 1.27 1.7018)
			(stroke
				(width 0.1524)
				(type default)
			)
			(layer "F.SilkS")
		)
		(fp_line
			(start 0.6604 -1.8034)
			(end 1.3843 -1.8034)
			(stroke
				(width 0.3302)
				(type default)
			)
			(layer "F.SilkS")
		)
		(fp_line
			(start -1.27 1.7018)
			(end -1.27 -1.7018)
			(stroke
				(width 0.1524)
				(type default)
			)
			(layer "F.SilkS")
		)
		(fp_line
			(start -1.27 -1.7018)
			(end 1.27 -1.7018)
			(stroke
				(width 0.1524)
				(type default)
			)
			(layer "F.SilkS")
		)
		(fp_rect
			(start -1.524 1.9558)
			(end 1.524 -1.9558)
			(stroke
				(width 0)
				(type default)
			)
			(fill no)
			(layer "F.CrtYd")
		)
		(fp_poly
			(pts
				(xy -1.524 -1.9558) (xy 1.524 -1.9558) (xy 1.524 1.9558) (xy -1.524 1.9558)
			)
			(stroke
				(width 0)
				(type default)
			)
			(fill no)
			(layer "F.Fab")
		)
		(pad "1" smd rect
			(at 0.65024 -0.8255 180)
			(size 0.4064 1.2192)
			(layers "F.Cu" "F.Mask" "F.Paste")
			(net "UART_COMP_IN_R_RX")
		)
		(pad "2" smd rect
			(at 0 -0.8255 180)
			(size 0.4064 1.2192)
			(layers "F.Cu" "F.Mask" "F.Paste")
			(net "UART_BMC_COMP_IN_RX_R")
		)
		(pad "3" smd rect
			(at -0.65024 -0.8255 180)
			(size 0.4064 1.2192)
			(layers "F.Cu" "F.Mask" "F.Paste")
			(net "GND")
		)
		(pad "4" smd rect
			(at -0.65024 0.8255 180)
			(size 0.4064 1.2192)
			(layers "F.Cu" "F.Mask" "F.Paste")
			(net "UART_COMP_IN_RX_AND")
		)
		(pad "5" smd rect
			(at 0.65024 0.8255 180)
			(size 0.4064 1.2192)
			(layers "F.Cu" "F.Mask" "F.Paste")
			(net "P3V3_STBY")
		)
	)
	(footprint ""
		(layer "F.Cu")
		(at 177.2158 -128.016 90)
		(property "Reference" "R524"
			(at 0 0 90)
			(layer "F.SilkS")
			(hide yes)
			(effects
				(font
					(size 1.27 1.27)
				)
			)
		)
		(property "Value" "4K7R2F-GP"
			(at 0.064008 -3.993896 90)
			(unlocked yes)
			(layer "F.Fab")
			(hide yes)
			(effects
				(font
					(size 1.016 1.016)
					(thickness 0.1524)
				)
			)
		)
		(property "Device Type" "R402H16"
			(at 0.064008 -5.517896 90)
			(unlocked yes)
			(layer "F.Fab")
			(hide yes)
			(effects
				(font
					(size 1.016 1.016)
					(thickness 0.1524)
				)
			)
		)
		(duplicate_pad_numbers_are_jumpers no)
		(fp_line
			(start 0.508 -0.9398)
			(end -0.508 -0.9398)
			(stroke
				(width 0.1524)
				(type default)
			)
			(layer "F.SilkS")
		)
		(fp_line
			(start -0.508 -0.9398)
			(end -0.508 0.9398)
			(stroke
				(width 0.1524)
				(type default)
			)
			(layer "F.SilkS")
		)
		(fp_rect
			(start -0.508 0.9398)
			(end 0.508 -0.9398)
			(stroke
				(width 0)
				(type default)
			)
			(fill no)
			(layer "F.CrtYd")
		)
		(fp_rect
			(start -0.508 0.9398)
			(end 0.508 -0.9398)
			(stroke
				(width 0)
				(type default)
			)
			(fill no)
			(layer "F.Fab")
		)
		(pad "1" smd custom
			(at 0 -0.4445 90)
			(size 0.1397 0.1397)
			(layers "F.Cu" "F.Mask" "F.Paste")
			(net "P3V3")
			(options
				(clearance outline)
				(anchor circle)
			)
			(primitives
				(gr_poly
					(pts
						(arc
							(start -0.1778 -0.2794)
							(mid -0.249642 -0.249642)
							(end -0.2794 -0.1778)
						)
						(arc
							(start -0.2794 0.1778)
							(mid -0.249642 0.249642)
							(end -0.1778 0.2794)
						)
						(arc
							(start 0.1778 0.2794)
							(mid 0.249642 0.249642)
							(end 0.2794 0.1778)
						)
						(arc
							(start 0.2794 -0.1778)
							(mid 0.249642 -0.249642)
							(end 0.1778 -0.2794)
						)
					)
					(width 0)
					(fill yes)
				)
			)
		)
		(pad "2" smd custom
			(at 0 0.4445 90)
			(size 0.1397 0.1397)
			(layers "F.Cu" "F.Mask" "F.Paste")
			(net "P3V3_PG")
			(options
				(clearance outline)
				(anchor circle)
			)
			(primitives
				(gr_poly
					(pts
						(arc
							(start -0.1778 -0.2794)
							(mid -0.249642 -0.249642)
							(end -0.2794 -0.1778)
						)
						(arc
							(start -0.2794 0.1778)
							(mid -0.249642 0.249642)
							(end -0.1778 0.2794)
						)
						(arc
							(start 0.1778 0.2794)
							(mid 0.249642 0.249642)
							(end 0.2794 0.1778)
						)
						(arc
							(start 0.2794 -0.1778)
							(mid 0.249642 -0.249642)
							(end 0.1778 -0.2794)
						)
					)
					(width 0)
					(fill yes)
				)
			)
		)
	)
	(footprint ""
		(layer "F.Cu")
		(at 93.141546 -51.567334)
		(property "Reference" "C185"
			(at 0 0 0)
			(layer "F.SilkS")
			(hide yes)
			(effects
				(font
					(size 1.27 1.27)
				)
			)
		)
		(property "Value" "SCD1U16V2KX-3GP"
			(at 1.1811 -2.7051 0)
			(unlocked yes)
			(layer "F.Fab")
			(hide yes)
			(effects
				(font
					(size 1.016 1.016)
					(thickness 0.1524)
				)
			)
		)
		(property "Device Type" "C402H22"
			(at 1.1811 -4.2291 0)
			(unlocked yes)
			(layer "F.Fab")
			(hide yes)
			(effects
				(font
					(size 1.016 1.016)
					(thickness 0.1524)
				)
			)
		)
		(duplicate_pad_numbers_are_jumpers no)
		(fp_rect
			(start -0.4318 0.9525)
			(end 0.4318 -0.9525)
			(stroke
				(width 0)
				(type default)
			)
			(fill no)
			(layer "F.CrtYd")
		)
		(fp_rect
			(start -0.4318 0.9525)
			(end 0.4318 -0.9525)
			(stroke
				(width 0)
				(type default)
			)
			(fill no)
			(layer "F.Fab")
		)
		(pad "1" smd custom
			(at 0 -0.4445)
			(size 0.1524 0.1524)
			(layers "F.Cu" "F.Mask" "F.Paste")
			(net "P3V3_STBY")
			(options
				(clearance outline)
				(anchor circle)
			)
			(primitives
				(gr_poly
					(pts
						(arc
							(start 0.3048 -0.2032)
							(mid 0.275042 -0.275042)
							(end 0.2032 -0.3048)
						)
						(arc
							(start -0.2032 -0.3048)
							(mid -0.275042 -0.275042)
							(end -0.3048 -0.2032)
						)
						(arc
							(start -0.3048 0.2032)
							(mid -0.275042 0.275042)
							(end -0.2032 0.3048)
						)
						(arc
							(start 0.2032 0.3048)
							(mid 0.275042 0.275042)
							(end 0.3048 0.2032)
						)
					)
					(width 0)
					(fill yes)
				)
			)
		)
		(pad "2" smd custom
			(at 0 0.4445)
			(size 0.1524 0.1524)
			(layers "F.Cu" "F.Mask" "F.Paste")
			(net "GND")
			(options
				(clearance outline)
				(anchor circle)
			)
			(primitives
				(gr_poly
					(pts
						(arc
							(start 0.3048 -0.2032)
							(mid 0.275042 -0.275042)
							(end 0.2032 -0.3048)
						)
						(arc
							(start -0.2032 -0.3048)
							(mid -0.275042 -0.275042)
							(end -0.3048 -0.2032)
						)
						(arc
							(start -0.3048 0.2032)
							(mid -0.275042 0.275042)
							(end -0.2032 0.3048)
						)
						(arc
							(start 0.2032 0.3048)
							(mid 0.275042 0.275042)
							(end 0.3048 0.2032)
						)
					)
					(width 0)
					(fill yes)
				)
			)
		)
	)
	(footprint ""
		(layer "F.Cu")
		(at 44.2214 -159.7406)
		(property "Reference" "TP13"
			(at 0 0 0)
			(layer "F.SilkS")
			(hide yes)
			(effects
				(font
					(size 1.27 1.27)
				)
			)
		)
		(property "Value" "TPAD28-2-GP"
			(at -0.0127 -1.6637 0)
			(unlocked yes)
			(layer "F.Fab")
			(hide yes)
			(effects
				(font
					(size 1.016 1.016)
					(thickness 0.1524)
				)
			)
		)
		(property "Device Type" "TPAD28"
			(at -0.0127 -3.1877 0)
			(unlocked yes)
			(layer "F.Fab")
			(hide yes)
			(effects
				(font
					(size 1.016 1.016)
					(thickness 0.1524)
				)
			)
		)
		(duplicate_pad_numbers_are_jumpers no)
		(fp_poly
			(pts
				(arc
					(start 0.3556 0)
					(mid -0.3556 0)
					(end 0.3556 0)
				)
			)
			(stroke
				(width 0)
				(type default)
			)
			(fill no)
			(layer "F.CrtYd")
		)
		(fp_poly
			(pts
				(arc
					(start 0.6096 0)
					(mid -0.6096 0)
					(end 0.6096 0)
				)
			)
			(stroke
				(width 0)
				(type default)
			)
			(fill no)
			(layer "F.Fab")
		)
		(pad "1" smd circle
			(at 0 0)
			(size 0.7112 0.7112)
			(layers "F.Cu" "F.Mask" "F.Paste")
			(net "I2C_M2_1_SCL")
		)
	)
	(footprint ""
		(layer "F.Cu")
		(at 69.867018 -141.59992 -90)
		(property "Reference" "R601"
			(at 0 0 270)
			(layer "F.SilkS")
			(hide yes)
			(effects
				(font
					(size 1.27 1.27)
				)
			)
		)
		(property "Value" "4K7R2F-GP"
			(at 0.064008 -3.993896 270)
			(unlocked yes)
			(layer "F.Fab")
			(hide yes)
			(effects
				(font
					(size 1.016 1.016)
					(thickness 0.1524)
				)
			)
		)
		(property "Device Type" "R402H16"
			(at 0.064008 -5.517896 270)
			(unlocked yes)
			(layer "F.Fab")
			(hide yes)
			(effects
				(font
					(size 1.016 1.016)
					(thickness 0.1524)
				)
			)
		)
		(duplicate_pad_numbers_are_jumpers no)
		(fp_line
			(start -0.508 -0.9398)
			(end -0.508 0.9398)
			(stroke
				(width 0.1524)
				(type default)
			)
			(layer "F.SilkS")
		)
		(fp_line
			(start 0.508 -0.9398)
			(end -0.508 -0.9398)
			(stroke
				(width 0.1524)
				(type default)
			)
			(layer "F.SilkS")
		)
		(fp_rect
			(start -0.508 0.9398)
			(end 0.508 -0.9398)
			(stroke
				(width 0)
				(type default)
			)
			(fill no)
			(layer "F.CrtYd")
		)
		(fp_rect
			(start -0.508 0.9398)
			(end 0.508 -0.9398)
			(stroke
				(width 0)
				(type default)
			)
			(fill no)
			(layer "F.Fab")
		)
		(pad "1" smd custom
			(at 0 -0.4445 270)
			(size 0.1397 0.1397)
			(layers "F.Cu" "F.Mask" "F.Paste")
			(net "P3V3_STBY")
			(options
				(clearance outline)
				(anchor circle)
			)
			(primitives
				(gr_poly
					(pts
						(arc
							(start -0.1778 -0.2794)
							(mid -0.249642 -0.249642)
							(end -0.2794 -0.1778)
						)
						(arc
							(start -0.2794 0.1778)
							(mid -0.249642 0.249642)
							(end -0.1778 0.2794)
						)
						(arc
							(start 0.1778 0.2794)
							(mid 0.249642 0.249642)
							(end 0.2794 0.1778)
						)
						(arc
							(start 0.2794 -0.1778)
							(mid 0.249642 -0.249642)
							(end 0.1778 -0.2794)
						)
					)
					(width 0)
					(fill yes)
				)
			)
		)
		(pad "2" smd custom
			(at 0 0.4445 270)
			(size 0.1397 0.1397)
			(layers "F.Cu" "F.Mask" "F.Paste")
			(net "I2C_COMP_ALERT_N")
			(options
				(clearance outline)
				(anchor circle)
			)
			(primitives
				(gr_poly
					(pts
						(arc
							(start -0.1778 -0.2794)
							(mid -0.249642 -0.249642)
							(end -0.2794 -0.1778)
						)
						(arc
							(start -0.2794 0.1778)
							(mid -0.249642 0.249642)
							(end -0.1778 0.2794)
						)
						(arc
							(start 0.1778 0.2794)
							(mid 0.249642 0.249642)
							(end 0.2794 0.1778)
						)
						(arc
							(start 0.2794 -0.1778)
							(mid 0.249642 -0.249642)
							(end 0.1778 -0.2794)
						)
					)
					(width 0)
					(fill yes)
				)
			)
		)
	)
	(footprint ""
		(layer "F.Cu")
		(at 158.379668 -143.624808 180)
		(property "Reference" "R518"
			(at 0 0 180)
			(layer "F.SilkS")
			(hide yes)
			(effects
				(font
					(size 1.27 1.27)
				)
			)
		)
		(property "Value" "10KR2F-2-GP"
			(at 0.064008 -3.993896 180)
			(unlocked yes)
			(layer "F.Fab")
			(hide yes)
			(effects
				(font
					(size 1.016 1.016)
					(thickness 0.1524)
				)
			)
		)
		(property "Device Type" "R402H16"
			(at 0.064008 -5.517896 180)
			(unlocked yes)
			(layer "F.Fab")
			(hide yes)
			(effects
				(font
					(size 1.016 1.016)
					(thickness 0.1524)
				)
			)
		)
		(duplicate_pad_numbers_are_jumpers no)
		(fp_line
			(start 0.508 -0.9398)
			(end -0.508 -0.9398)
			(stroke
				(width 0.1524)
				(type default)
			)
			(layer "F.SilkS")
		)
		(fp_line
			(start -0.508 -0.9398)
			(end -0.508 0.9398)
			(stroke
				(width 0.1524)
				(type default)
			)
			(layer "F.SilkS")
		)
		(fp_rect
			(start -0.508 0.9398)
			(end 0.508 -0.9398)
			(stroke
				(width 0)
				(type default)
			)
			(fill no)
			(layer "F.CrtYd")
		)
		(fp_rect
			(start -0.508 0.9398)
			(end 0.508 -0.9398)
			(stroke
				(width 0)
				(type default)
			)
			(fill no)
			(layer "F.Fab")
		)
		(pad "1" smd custom
			(at 0 -0.4445 180)
			(size 0.1397 0.1397)
			(layers "F.Cu" "F.Mask" "F.Paste")
			(net "P1V8_STBY_VRG5")
			(options
				(clearance outline)
				(anchor circle)
			)
			(primitives
				(gr_poly
					(pts
						(arc
							(start -0.1778 -0.2794)
							(mid -0.249642 -0.249642)
							(end -0.2794 -0.1778)
						)
						(arc
							(start -0.2794 0.1778)
							(mid -0.249642 0.249642)
							(end -0.1778 0.2794)
						)
						(arc
							(start 0.1778 0.2794)
							(mid 0.249642 0.249642)
							(end 0.2794 0.1778)
						)
						(arc
							(start 0.2794 -0.1778)
							(mid 0.249642 -0.249642)
							(end 0.1778 -0.2794)
						)
					)
					(width 0)
					(fill yes)
				)
			)
		)
		(pad "2" smd custom
			(at 0 0.4445 180)
			(size 0.1397 0.1397)
			(layers "F.Cu" "F.Mask" "F.Paste")
			(net "PWRGD_P1V8_STBY")
			(options
				(clearance outline)
				(anchor circle)
			)
			(primitives
				(gr_poly
					(pts
						(arc
							(start -0.1778 -0.2794)
							(mid -0.249642 -0.249642)
							(end -0.2794 -0.1778)
						)
						(arc
							(start -0.2794 0.1778)
							(mid -0.249642 0.249642)
							(end -0.1778 0.2794)
						)
						(arc
							(start 0.1778 0.2794)
							(mid 0.249642 0.249642)
							(end 0.2794 0.1778)
						)
						(arc
							(start 0.2794 -0.1778)
							(mid 0.249642 -0.249642)
							(end 0.1778 -0.2794)
						)
					)
					(width 0)
					(fill yes)
				)
			)
		)
	)
	(footprint ""
		(layer "F.Cu")
		(at 33.5534 -165.0238 180)
		(property "Reference" "R705"
			(at 0 0 180)
			(layer "F.SilkS")
			(hide yes)
			(effects
				(font
					(size 1.27 1.27)
				)
			)
		)
		(property "Value" "4K7R2F-GP"
			(at 0.064008 -3.993896 180)
			(unlocked yes)
			(layer "F.Fab")
			(hide yes)
			(effects
				(font
					(size 1.016 1.016)
					(thickness 0.1524)
				)
			)
		)
		(property "Device Type" "R402H16"
			(at 0.064008 -5.517896 180)
			(unlocked yes)
			(layer "F.Fab")
			(hide yes)
			(effects
				(font
					(size 1.016 1.016)
					(thickness 0.1524)
				)
			)
		)
		(duplicate_pad_numbers_are_jumpers no)
		(fp_line
			(start 0.508 -0.9398)
			(end -0.508 -0.9398)
			(stroke
				(width 0.1524)
				(type default)
			)
			(layer "F.SilkS")
		)
		(fp_line
			(start -0.508 -0.9398)
			(end -0.508 0.9398)
			(stroke
				(width 0.1524)
				(type default)
			)
			(layer "F.SilkS")
		)
		(fp_rect
			(start -0.508 0.9398)
			(end 0.508 -0.9398)
			(stroke
				(width 0)
				(type default)
			)
			(fill no)
			(layer "F.CrtYd")
		)
		(fp_rect
			(start -0.508 0.9398)
			(end 0.508 -0.9398)
			(stroke
				(width 0)
				(type default)
			)
			(fill no)
			(layer "F.Fab")
		)
		(pad "1" smd custom
			(at 0 -0.4445 180)
			(size 0.1397 0.1397)
			(layers "F.Cu" "F.Mask" "F.Paste")
			(net "IOM_TYPE2")
			(options
				(clearance outline)
				(anchor circle)
			)
			(primitives
				(gr_poly
					(pts
						(arc
							(start -0.1778 -0.2794)
							(mid -0.249642 -0.249642)
							(end -0.2794 -0.1778)
						)
						(arc
							(start -0.2794 0.1778)
							(mid -0.249642 0.249642)
							(end -0.1778 0.2794)
						)
						(arc
							(start 0.1778 0.2794)
							(mid 0.249642 0.249642)
							(end 0.2794 0.1778)
						)
						(arc
							(start 0.2794 -0.1778)
							(mid 0.249642 -0.249642)
							(end 0.1778 -0.2794)
						)
					)
					(width 0)
					(fill yes)
				)
			)
		)
		(pad "2" smd custom
			(at 0 0.4445 180)
			(size 0.1397 0.1397)
			(layers "F.Cu" "F.Mask" "F.Paste")
			(net "P3V3_STBY")
			(options
				(clearance outline)
				(anchor circle)
			)
			(primitives
				(gr_poly
					(pts
						(arc
							(start -0.1778 -0.2794)
							(mid -0.249642 -0.249642)
							(end -0.2794 -0.1778)
						)
						(arc
							(start -0.2794 0.1778)
							(mid -0.249642 0.249642)
							(end -0.1778 0.2794)
						)
						(arc
							(start 0.1778 0.2794)
							(mid 0.249642 0.249642)
							(end 0.2794 0.1778)
						)
						(arc
							(start 0.2794 -0.1778)
							(mid 0.249642 -0.249642)
							(end 0.1778 -0.2794)
						)
					)
					(width 0)
					(fill yes)
				)
			)
		)
	)
	(footprint ""
		(layer "F.Cu")
		(at 47.498 -131.7498 180)
		(property "Reference" "R177"
			(at 0 0 180)
			(layer "F.SilkS")
			(hide yes)
			(effects
				(font
					(size 1.27 1.27)
				)
			)
		)
		(property "Value" "0R2J-2-GP"
			(at 0.064008 -3.993896 180)
			(unlocked yes)
			(layer "F.Fab")
			(hide yes)
			(effects
				(font
					(size 1.016 1.016)
					(thickness 0.1524)
				)
			)
		)
		(property "Device Type" "R402H16"
			(at 0.064008 -5.517896 180)
			(unlocked yes)
			(layer "F.Fab")
			(hide yes)
			(effects
				(font
					(size 1.016 1.016)
					(thickness 0.1524)
				)
			)
		)
		(duplicate_pad_numbers_are_jumpers no)
		(fp_line
			(start 0.508 -0.9398)
			(end -0.508 -0.9398)
			(stroke
				(width 0.1524)
				(type default)
			)
			(layer "F.SilkS")
		)
		(fp_line
			(start -0.508 -0.9398)
			(end -0.508 0.9398)
			(stroke
				(width 0.1524)
				(type default)
			)
			(layer "F.SilkS")
		)
		(fp_rect
			(start -0.508 0.9398)
			(end 0.508 -0.9398)
			(stroke
				(width 0)
				(type default)
			)
			(fill no)
			(layer "F.CrtYd")
		)
		(fp_rect
			(start -0.508 0.9398)
			(end 0.508 -0.9398)
			(stroke
				(width 0)
				(type default)
			)
			(fill no)
			(layer "F.Fab")
		)
		(pad "1" smd custom
			(at 0 -0.4445 180)
			(size 0.1397 0.1397)
			(layers "F.Cu" "F.Mask" "F.Paste")
			(net "I2C_TPM_SCL")
			(options
				(clearance outline)
				(anchor circle)
			)
			(primitives
				(gr_poly
					(pts
						(arc
							(start -0.1778 -0.2794)
							(mid -0.249642 -0.249642)
							(end -0.2794 -0.1778)
						)
						(arc
							(start -0.2794 0.1778)
							(mid -0.249642 0.249642)
							(end -0.1778 0.2794)
						)
						(arc
							(start 0.1778 0.2794)
							(mid 0.249642 0.249642)
							(end 0.2794 0.1778)
						)
						(arc
							(start 0.2794 -0.1778)
							(mid 0.249642 -0.249642)
							(end 0.1778 -0.2794)
						)
					)
					(width 0)
					(fill yes)
				)
			)
		)
		(pad "2" smd custom
			(at 0 0.4445 180)
			(size 0.1397 0.1397)
			(layers "F.Cu" "F.Mask" "F.Paste")
			(net "BMC_SMB14_CLK")
			(options
				(clearance outline)
				(anchor circle)
			)
			(primitives
				(gr_poly
					(pts
						(arc
							(start -0.1778 -0.2794)
							(mid -0.249642 -0.249642)
							(end -0.2794 -0.1778)
						)
						(arc
							(start -0.2794 0.1778)
							(mid -0.249642 0.249642)
							(end -0.1778 0.2794)
						)
						(arc
							(start 0.1778 0.2794)
							(mid 0.249642 0.249642)
							(end 0.2794 0.1778)
						)
						(arc
							(start 0.2794 -0.1778)
							(mid 0.249642 -0.249642)
							(end 0.1778 -0.2794)
						)
					)
					(width 0)
					(fill yes)
				)
			)
		)
	)
	(footprint ""
		(layer "F.Cu")
		(at 197.06209 -105.784142)
		(property "Reference" "C268"
			(at 0 0 0)
			(layer "F.SilkS")
			(hide yes)
			(effects
				(font
					(size 1.27 1.27)
				)
			)
		)
		(property "Value" "SC22U6D3V6KX-2-GP"
			(at -0.0762 -5.1308 0)
			(unlocked yes)
			(layer "F.Fab")
			(hide yes)
			(effects
				(font
					(size 1.016 1.016)
					(thickness 0.1524)
				)
			)
		)
		(property "Device Type" "C1206H71"
			(at -0.127 -6.6548 0)
			(unlocked yes)
			(layer "F.Fab")
			(hide yes)
			(effects
				(font
					(size 1.016 1.016)
					(thickness 0.1524)
				)
			)
		)
		(duplicate_pad_numbers_are_jumpers no)
		(fp_line
			(start -1.016 -2.2352)
			(end 1.016 -2.2352)
			(stroke
				(width 0.1524)
				(type default)
			)
			(layer "F.SilkS")
		)
		(fp_line
			(start -1.016 -0.8382)
			(end -1.016 -2.2352)
			(stroke
				(width 0.1524)
				(type default)
			)
			(layer "F.SilkS")
		)
		(fp_line
			(start -1.016 2.2352)
			(end -1.016 0.8382)
			(stroke
				(width 0.1524)
				(type default)
			)
			(layer "F.SilkS")
		)
		(fp_line
			(start 1.016 -2.2352)
			(end 1.016 -0.8382)
			(stroke
				(width 0.1524)
				(type default)
			)
			(layer "F.SilkS")
		)
		(fp_line
			(start 1.016 0.8382)
			(end 1.016 2.2352)
			(stroke
				(width 0.1524)
				(type default)
			)
			(layer "F.SilkS")
		)
		(fp_line
			(start 1.016 2.2352)
			(end -1.016 2.2352)
			(stroke
				(width 0.1524)
				(type default)
			)
			(layer "F.SilkS")
		)
		(fp_rect
			(start -1.0922 2.3114)
			(end 1.0922 -2.3114)
			(stroke
				(width 0)
				(type default)
			)
			(fill no)
			(layer "F.CrtYd")
		)
		(fp_poly
			(pts
				(xy 1.0922 -2.3114) (xy 1.0922 2.3114) (xy -1.0922 2.3114) (xy -1.0922 -2.3114)
			)
			(stroke
				(width 0)
				(type default)
			)
			(fill no)
			(layer "F.Fab")
		)
		(pad "1" smd rect
			(at 0 -1.397)
			(size 1.651 1.27)
			(layers "F.Cu" "F.Mask" "F.Paste")
			(net "P0V975")
		)
		(pad "2" smd rect
			(at 0 1.397)
			(size 1.651 1.27)
			(layers "F.Cu" "F.Mask" "F.Paste")
			(net "GND")
		)
	)
	(footprint ""
		(layer "F.Cu")
		(at 179.028852 -140.614908 90)
		(property "Reference" "R476"
			(at 0 0 90)
			(layer "F.SilkS")
			(hide yes)
			(effects
				(font
					(size 1.27 1.27)
				)
			)
		)
		(property "Value" "866KR2F-GP"
			(at 0.064008 -3.993896 90)
			(unlocked yes)
			(layer "F.Fab")
			(hide yes)
			(effects
				(font
					(size 1.016 1.016)
					(thickness 0.1524)
				)
			)
		)
		(property "Device Type" "R402H16"
			(at 0.064008 -5.517896 90)
			(unlocked yes)
			(layer "F.Fab")
			(hide yes)
			(effects
				(font
					(size 1.016 1.016)
					(thickness 0.1524)
				)
			)
		)
		(duplicate_pad_numbers_are_jumpers no)
		(fp_line
			(start 0.508 -0.9398)
			(end -0.508 -0.9398)
			(stroke
				(width 0.1524)
				(type default)
			)
			(layer "F.SilkS")
		)
		(fp_line
			(start -0.508 -0.9398)
			(end -0.508 0.9398)
			(stroke
				(width 0.1524)
				(type default)
			)
			(layer "F.SilkS")
		)
		(fp_rect
			(start -0.508 0.9398)
			(end 0.508 -0.9398)
			(stroke
				(width 0)
				(type default)
			)
			(fill no)
			(layer "F.CrtYd")
		)
		(fp_rect
			(start -0.508 0.9398)
			(end 0.508 -0.9398)
			(stroke
				(width 0)
				(type default)
			)
			(fill no)
			(layer "F.Fab")
		)
		(pad "1" smd custom
			(at 0 -0.4445 90)
			(size 0.1397 0.1397)
			(layers "F.Cu" "F.Mask" "F.Paste")
			(net "P5V_STBY_VREG")
			(options
				(clearance outline)
				(anchor circle)
			)
			(primitives
				(gr_poly
					(pts
						(arc
							(start -0.1778 -0.2794)
							(mid -0.249642 -0.249642)
							(end -0.2794 -0.1778)
						)
						(arc
							(start -0.2794 0.1778)
							(mid -0.249642 0.249642)
							(end -0.1778 0.2794)
						)
						(arc
							(start 0.1778 0.2794)
							(mid 0.249642 0.249642)
							(end 0.2794 0.1778)
						)
						(arc
							(start 0.2794 -0.1778)
							(mid 0.249642 -0.249642)
							(end 0.1778 -0.2794)
						)
					)
					(width 0)
					(fill yes)
				)
			)
		)
		(pad "2" smd custom
			(at 0 0.4445 90)
			(size 0.1397 0.1397)
			(layers "F.Cu" "F.Mask" "F.Paste")
			(net "P5V_RF")
			(options
				(clearance outline)
				(anchor circle)
			)
			(primitives
				(gr_poly
					(pts
						(arc
							(start -0.1778 -0.2794)
							(mid -0.249642 -0.249642)
							(end -0.2794 -0.1778)
						)
						(arc
							(start -0.2794 0.1778)
							(mid -0.249642 0.249642)
							(end -0.1778 0.2794)
						)
						(arc
							(start 0.1778 0.2794)
							(mid 0.249642 0.249642)
							(end 0.2794 0.1778)
						)
						(arc
							(start 0.2794 -0.1778)
							(mid 0.249642 -0.249642)
							(end 0.1778 -0.2794)
						)
					)
					(width 0)
					(fill yes)
				)
			)
		)
	)
	(footprint ""
		(layer "F.Cu")
		(at 63.119 -165.735 90)
		(property "Reference" "Q3"
			(at 0 0 90)
			(layer "F.SilkS")
			(hide yes)
			(effects
				(font
					(size 1.27 1.27)
				)
			)
		)
		(property "Value" "MMBT3904-3-GP"
			(at 0.10287 -10.29843 90)
			(unlocked yes)
			(layer "F.Fab")
			(hide yes)
			(effects
				(font
					(size 1.016 1.016)
					(thickness 0.1524)
				)
			)
		)
		(property "Device Type" "SOT23CBE2D4H44"
			(at 0.10287 -12.20343 90)
			(unlocked yes)
			(layer "F.Fab")
			(hide yes)
			(effects
				(font
					(size 1.016 1.016)
					(thickness 0.1524)
				)
			)
		)
		(duplicate_pad_numbers_are_jumpers no)
		(fp_line
			(start 1.651 -1.778)
			(end -1.651 -1.778)
			(stroke
				(width 0.1524)
				(type default)
			)
			(layer "F.SilkS")
		)
		(fp_line
			(start -1.651 -1.778)
			(end -1.651 1.778)
			(stroke
				(width 0.1524)
				(type default)
			)
			(layer "F.SilkS")
		)
		(fp_line
			(start 1.651 1.778)
			(end 1.651 -1.778)
			(stroke
				(width 0.1524)
				(type default)
			)
			(layer "F.SilkS")
		)
		(fp_line
			(start -1.651 1.778)
			(end 1.651 1.778)
			(stroke
				(width 0.1524)
				(type default)
			)
			(layer "F.SilkS")
		)
		(fp_poly
			(pts
				(xy -1.778 1.8796) (xy -1.778 -1.8796) (xy 1.778 -1.8796) (xy 1.778 1.8796)
			)
			(stroke
				(width 0)
				(type default)
			)
			(fill no)
			(layer "F.CrtYd")
		)
		(fp_poly
			(pts
				(xy -1.778 1.8796) (xy -1.778 -1.8796) (xy 1.778 -1.8796) (xy 1.778 1.8796)
			)
			(stroke
				(width 0)
				(type default)
			)
			(fill no)
			(layer "F.Fab")
		)
		(pad "B" smd custom
			(at -0.98425 0.9525 90)
			(size 0.1905 0.1905)
			(layers "F.Cu" "F.Mask" "F.Paste")
			(net "FM_TPM_PRSNT_RST_N_R")
			(options
				(clearance outline)
				(anchor circle)
			)
			(primitives
				(gr_poly
					(pts
						(arc
							(start -0.1778 0.5715)
							(mid -0.321484 0.511984)
							(end -0.381 0.3683)
						)
						(arc
							(start -0.381 -0.3683)
							(mid -0.321484 -0.511984)
							(end -0.1778 -0.5715)
						)
						(arc
							(start 0.1778 -0.5715)
							(mid 0.321484 -0.511984)
							(end 0.381 -0.3683)
						)
						(arc
							(start 0.381 0.3683)
							(mid 0.321484 0.511984)
							(end 0.1778 0.5715)
						)
					)
					(width 0)
					(fill yes)
				)
			)
		)
		(pad "C" smd custom
			(at 0 -0.9525 90)
			(size 0.1905 0.1905)
			(layers "F.Cu" "F.Mask" "F.Paste")
			(net "FM_TPM_PRSNT_RST")
			(options
				(clearance outline)
				(anchor circle)
			)
			(primitives
				(gr_poly
					(pts
						(arc
							(start -0.1778 0.5715)
							(mid -0.321484 0.511984)
							(end -0.381 0.3683)
						)
						(arc
							(start -0.381 -0.3683)
							(mid -0.321484 -0.511984)
							(end -0.1778 -0.5715)
						)
						(arc
							(start 0.1778 -0.5715)
							(mid 0.321484 -0.511984)
							(end 0.381 -0.3683)
						)
						(arc
							(start 0.381 0.3683)
							(mid 0.321484 0.511984)
							(end 0.1778 0.5715)
						)
					)
					(width 0)
					(fill yes)
				)
			)
		)
		(pad "E" smd custom
			(at 0.98425 0.9525 90)
			(size 0.1905 0.1905)
			(layers "F.Cu" "F.Mask" "F.Paste")
			(net "GND")
			(options
				(clearance outline)
				(anchor circle)
			)
			(primitives
				(gr_poly
					(pts
						(arc
							(start -0.1778 0.5715)
							(mid -0.321484 0.511984)
							(end -0.381 0.3683)
						)
						(arc
							(start -0.381 -0.3683)
							(mid -0.321484 -0.511984)
							(end -0.1778 -0.5715)
						)
						(arc
							(start 0.1778 -0.5715)
							(mid 0.321484 -0.511984)
							(end 0.381 -0.3683)
						)
						(arc
							(start 0.381 0.3683)
							(mid 0.321484 0.511984)
							(end 0.1778 0.5715)
						)
					)
					(width 0)
					(fill yes)
				)
			)
		)
	)
	(footprint ""
		(layer "F.Cu")
		(at 167.5384 -133.858)
		(property "Reference" "C205"
			(at 0 0 0)
			(layer "F.SilkS")
			(hide yes)
			(effects
				(font
					(size 1.27 1.27)
				)
			)
		)
		(property "Value" "SC10U16V5KX-7-GP-U"
			(at -0.0762 -6.1214 0)
			(unlocked yes)
			(layer "F.Fab")
			(hide yes)
			(effects
				(font
					(size 1.016 1.016)
					(thickness 0.1524)
				)
			)
		)
		(property "Device Type" "C805H58"
			(at -0.0762 -8.1534 0)
			(unlocked yes)
			(layer "F.Fab")
			(hide yes)
			(effects
				(font
					(size 1.016 1.016)
					(thickness 0.1524)
				)
			)
		)
		(duplicate_pad_numbers_are_jumpers no)
		(fp_line
			(start 0.635 0)
			(end -0.635 0)
			(stroke
				(width 0.508)
				(type default)
			)
			(layer "F.SilkS")
		)
		(fp_rect
			(start -0.9652 1.778)
			(end 0.9652 -1.778)
			(stroke
				(width 0)
				(type default)
			)
			(fill no)
			(layer "F.CrtYd")
		)
		(fp_poly
			(pts
				(xy -0.9652 -1.778) (xy 0.9652 -1.778) (xy 0.9652 1.778) (xy -0.9652 1.778)
			)
			(stroke
				(width 0)
				(type default)
			)
			(fill no)
			(layer "F.Fab")
		)
		(pad "1" smd rect
			(at 0 -0.9652)
			(size 1.397 1.143)
			(layers "F.Cu" "F.Mask" "F.Paste")
			(net "P12V_STBY_VIN_PU4")
		)
		(pad "2" smd rect
			(at 0 0.9652)
			(size 1.397 1.143)
			(layers "F.Cu" "F.Mask" "F.Paste")
			(net "GND")
		)
	)
	(footprint ""
		(layer "F.Cu")
		(at 160.533588 -95.32747 90)
		(property "Reference" "R833"
			(at 0 0 90)
			(layer "F.SilkS")
			(hide yes)
			(effects
				(font
					(size 1.27 1.27)
				)
			)
		)
		(property "Value" "200KR2F-L-GP"
			(at 0.064008 -3.993896 90)
			(unlocked yes)
			(layer "F.Fab")
			(hide yes)
			(effects
				(font
					(size 1.016 1.016)
					(thickness 0.1524)
				)
			)
		)
		(property "Device Type" "R402H16"
			(at 0.064008 -5.517896 90)
			(unlocked yes)
			(layer "F.Fab")
			(hide yes)
			(effects
				(font
					(size 1.016 1.016)
					(thickness 0.1524)
				)
			)
		)
		(duplicate_pad_numbers_are_jumpers no)
		(fp_line
			(start 0.508 -0.9398)
			(end -0.508 -0.9398)
			(stroke
				(width 0.1524)
				(type default)
			)
			(layer "F.SilkS")
		)
		(fp_line
			(start -0.508 -0.9398)
			(end -0.508 0.9398)
			(stroke
				(width 0.1524)
				(type default)
			)
			(layer "F.SilkS")
		)
		(fp_rect
			(start -0.508 0.9398)
			(end 0.508 -0.9398)
			(stroke
				(width 0)
				(type default)
			)
			(fill no)
			(layer "F.CrtYd")
		)
		(fp_rect
			(start -0.508 0.9398)
			(end 0.508 -0.9398)
			(stroke
				(width 0)
				(type default)
			)
			(fill no)
			(layer "F.Fab")
		)
		(pad "1" smd custom
			(at 0 -0.4445 90)
			(size 0.1397 0.1397)
			(layers "F.Cu" "F.Mask" "F.Paste")
			(net "U43_VREF2")
			(options
				(clearance outline)
				(anchor circle)
			)
			(primitives
				(gr_poly
					(pts
						(arc
							(start -0.1778 -0.2794)
							(mid -0.249642 -0.249642)
							(end -0.2794 -0.1778)
						)
						(arc
							(start -0.2794 0.1778)
							(mid -0.249642 0.249642)
							(end -0.1778 0.2794)
						)
						(arc
							(start 0.1778 0.2794)
							(mid 0.249642 0.249642)
							(end 0.2794 0.1778)
						)
						(arc
							(start 0.2794 -0.1778)
							(mid 0.249642 -0.249642)
							(end 0.1778 -0.2794)
						)
					)
					(width 0)
					(fill yes)
				)
			)
		)
		(pad "2" smd custom
			(at 0 0.4445 90)
			(size 0.1397 0.1397)
			(layers "F.Cu" "F.Mask" "F.Paste")
			(net "P3V3_STBY")
			(options
				(clearance outline)
				(anchor circle)
			)
			(primitives
				(gr_poly
					(pts
						(arc
							(start -0.1778 -0.2794)
							(mid -0.249642 -0.249642)
							(end -0.2794 -0.1778)
						)
						(arc
							(start -0.2794 0.1778)
							(mid -0.249642 0.249642)
							(end -0.1778 0.2794)
						)
						(arc
							(start 0.1778 0.2794)
							(mid 0.249642 0.249642)
							(end 0.2794 0.1778)
						)
						(arc
							(start 0.2794 -0.1778)
							(mid 0.249642 -0.249642)
							(end 0.1778 -0.2794)
						)
					)
					(width 0)
					(fill yes)
				)
			)
		)
	)
	(footprint ""
		(layer "F.Cu")
		(at 99.453446 -142.7226 180)
		(property "Reference" "R423"
			(at 0 0 180)
			(layer "F.SilkS")
			(hide yes)
			(effects
				(font
					(size 1.27 1.27)
				)
			)
		)
		(property "Value" "4K7R2F-GP"
			(at 0.064008 -3.993896 180)
			(unlocked yes)
			(layer "F.Fab")
			(hide yes)
			(effects
				(font
					(size 1.016 1.016)
					(thickness 0.1524)
				)
			)
		)
		(property "Device Type" "R402H16"
			(at 0.064008 -5.517896 180)
			(unlocked yes)
			(layer "F.Fab")
			(hide yes)
			(effects
				(font
					(size 1.016 1.016)
					(thickness 0.1524)
				)
			)
		)
		(duplicate_pad_numbers_are_jumpers no)
		(fp_line
			(start 0.508 -0.9398)
			(end -0.508 -0.9398)
			(stroke
				(width 0.1524)
				(type default)
			)
			(layer "F.SilkS")
		)
		(fp_line
			(start -0.508 -0.9398)
			(end -0.508 0.9398)
			(stroke
				(width 0.1524)
				(type default)
			)
			(layer "F.SilkS")
		)
		(fp_rect
			(start -0.508 0.9398)
			(end 0.508 -0.9398)
			(stroke
				(width 0)
				(type default)
			)
			(fill no)
			(layer "F.CrtYd")
		)
		(fp_rect
			(start -0.508 0.9398)
			(end 0.508 -0.9398)
			(stroke
				(width 0)
				(type default)
			)
			(fill no)
			(layer "F.Fab")
		)
		(pad "1" smd custom
			(at 0 -0.4445 180)
			(size 0.1397 0.1397)
			(layers "F.Cu" "F.Mask" "F.Paste")
			(net "P3V3_STBY")
			(options
				(clearance outline)
				(anchor circle)
			)
			(primitives
				(gr_poly
					(pts
						(arc
							(start -0.1778 -0.2794)
							(mid -0.249642 -0.249642)
							(end -0.2794 -0.1778)
						)
						(arc
							(start -0.2794 0.1778)
							(mid -0.249642 0.249642)
							(end -0.1778 0.2794)
						)
						(arc
							(start 0.1778 0.2794)
							(mid 0.249642 0.249642)
							(end 0.2794 0.1778)
						)
						(arc
							(start 0.2794 -0.1778)
							(mid 0.249642 -0.249642)
							(end 0.1778 -0.2794)
						)
					)
					(width 0)
					(fill yes)
				)
			)
		)
		(pad "2" smd custom
			(at 0 0.4445 180)
			(size 0.1397 0.1397)
			(layers "F.Cu" "F.Mask" "F.Paste")
			(net "TCA9555_A0")
			(options
				(clearance outline)
				(anchor circle)
			)
			(primitives
				(gr_poly
					(pts
						(arc
							(start -0.1778 -0.2794)
							(mid -0.249642 -0.249642)
							(end -0.2794 -0.1778)
						)
						(arc
							(start -0.2794 0.1778)
							(mid -0.249642 0.249642)
							(end -0.1778 0.2794)
						)
						(arc
							(start 0.1778 0.2794)
							(mid 0.249642 0.249642)
							(end 0.2794 0.1778)
						)
						(arc
							(start 0.2794 -0.1778)
							(mid 0.249642 -0.249642)
							(end 0.1778 -0.2794)
						)
					)
					(width 0)
					(fill yes)
				)
			)
		)
	)
	(footprint ""
		(layer "F.Cu")
		(at 177.938684 -146.710146)
		(property "Reference" "PU1"
			(at 0 0 0)
			(layer "F.SilkS")
			(hide yes)
			(effects
				(font
					(size 1.27 1.27)
				)
			)
		)
		(property "Value" "TPS53318DQPR-GP"
			(at -5.022088 -6.851904 0)
			(unlocked yes)
			(layer "F.Fab")
			(hide yes)
			(effects
				(font
					(size 1.016 1.016)
					(thickness 0.1524)
				)
			)
		)
		(property "Device Type" "DFN22G6050-G6133H60"
			(at -5.022088 -8.375904 0)
			(unlocked yes)
			(layer "F.Fab")
			(hide yes)
			(effects
				(font
					(size 1.016 1.016)
					(thickness 0.1524)
				)
			)
		)
		(duplicate_pad_numbers_are_jumpers no)
		(fp_line
			(start -3.5052 -3.5179)
			(end -3.5052 -2.2479)
			(stroke
				(width 0.1524)
				(type default)
			)
			(layer "F.SilkS")
		)
		(fp_line
			(start -3.5052 2.2479)
			(end -3.5052 3.5179)
			(stroke
				(width 0.1524)
				(type default)
			)
			(layer "F.SilkS")
		)
		(fp_line
			(start -3.5052 3.5179)
			(end -2.2352 3.5179)
			(stroke
				(width 0.1524)
				(type default)
			)
			(layer "F.SilkS")
		)
		(fp_line
			(start -2.2352 -3.5179)
			(end -3.5052 -3.5179)
			(stroke
				(width 0.1524)
				(type default)
			)
			(layer "F.SilkS")
		)
		(fp_line
			(start -1.999996 -3.262122)
			(end -1.999996 -4.024122)
			(stroke
				(width 0.1524)
				(type default)
			)
			(layer "F.SilkS")
		)
		(fp_line
			(start -0.999998 3.262122)
			(end -0.999998 3.770122)
			(stroke
				(width 0.1524)
				(type default)
			)
			(layer "F.SilkS")
		)
		(fp_line
			(start 0.500126 -3.262122)
			(end 0.500126 -3.770122)
			(stroke
				(width 0.1524)
				(type default)
			)
			(layer "F.SilkS")
		)
		(fp_line
			(start 1.500124 3.262122)
			(end 1.500124 4.024122)
			(stroke
				(width 0.1524)
				(type default)
			)
			(layer "F.SilkS")
		)
		(fp_line
			(start 2.2352 3.5179)
			(end 3.5052 3.5179)
			(stroke
				(width 0.1524)
				(type default)
			)
			(layer "F.SilkS")
		)
		(fp_line
			(start 3.5052 3.5179)
			(end 3.5052 2.2479)
			(stroke
				(width 0.1524)
				(type default)
			)
			(layer "F.SilkS")
		)
		(fp_poly
			(pts
				(xy 3.5052 -3.5179) (xy 2.4765 -3.5179) (xy 3.5052 -2.4892)
			)
			(stroke
				(width 0)
				(type default)
			)
			(fill yes)
			(layer "F.SilkS")
		)
		(fp_rect
			(start -2.9972 2.5019)
			(end 2.9972 -2.5019)
			(stroke
				(width 0)
				(type default)
			)
			(fill no)
			(layer "F.CrtYd")
		)
		(fp_poly
			(pts
				(xy 3.556 -2.5019) (xy -2.9972 -2.5019) (xy -2.9972 2.5019) (xy 2.9972 2.5019) (xy 2.9972 -2.4892)
				(xy 3.556 -2.4892) (xy 3.556 3.5179) (xy -3.556 3.5179) (xy -3.556 -3.5179) (xy 3.556 -3.5179)
			)
			(stroke
				(width 0)
				(type default)
			)
			(fill no)
			(layer "F.CrtYd")
		)
		(fp_rect
			(start -3.556 3.5179)
			(end 3.556 -3.5179)
			(stroke
				(width 0)
				(type default)
			)
			(fill no)
			(layer "F.Fab")
		)
		(pad "1" smd rect
			(at 2.500122 -2.449322)
			(size 0.3048 1.1176)
			(layers "F.Cu" "F.Mask" "F.Paste")
			(net "P5V_VFB")
		)
		(pad "2" smd rect
			(at 1.999996 -2.449322)
			(size 0.3048 1.1176)
			(layers "F.Cu" "F.Mask" "F.Paste")
			(net "P5V_EN_R")
		)
		(pad "3" smd rect
			(at 1.500124 -2.449322)
			(size 0.3048 1.1176)
			(layers "F.Cu" "F.Mask" "F.Paste")
			(net "PWRGD_P5V_STBY")
		)
		(pad "4" smd rect
			(at 0.999998 -2.449322)
			(size 0.3048 1.1176)
			(layers "F.Cu" "F.Mask" "F.Paste")
			(net "P5V_VBST")
		)
		(pad "5" smd rect
			(at 0.500126 -2.449322)
			(size 0.3048 1.1176)
			(layers "F.Cu" "F.Mask" "F.Paste")
			(net "AGND_P5V")
		)
		(pad "6" smd rect
			(at 0 -2.449322)
			(size 0.3048 1.1176)
			(layers "F.Cu" "F.Mask" "F.Paste")
			(net "P5V_LL")
		)
		(pad "7" smd rect
			(at -0.500126 -2.449322)
			(size 0.3048 1.1176)
			(layers "F.Cu" "F.Mask" "F.Paste")
			(net "P5V_LL")
		)
		(pad "8" smd rect
			(at -0.999998 -2.449322)
			(size 0.3048 1.1176)
			(layers "F.Cu" "F.Mask" "F.Paste")
			(net "P5V_LL")
		)
		(pad "9" smd rect
			(at -1.500124 -2.449322)
			(size 0.3048 1.1176)
			(layers "F.Cu" "F.Mask" "F.Paste")
			(net "P5V_LL")
		)
		(pad "10" smd rect
			(at -1.999996 -2.449322)
			(size 0.3048 1.1176)
			(layers "F.Cu" "F.Mask" "F.Paste")
			(net "P5V_LL")
		)
		(pad "11" smd rect
			(at -2.500122 -2.449322)
			(size 0.3048 1.1176)
			(layers "F.Cu" "F.Mask" "F.Paste")
			(net "P5V_LL")
		)
		(pad "12" smd rect
			(at -2.500122 2.449322)
			(size 0.3048 1.1176)
			(layers "F.Cu" "F.Mask" "F.Paste")
			(net "P12V_STBY_VIN_PU1")
		)
		(pad "13" smd rect
			(at -1.999996 2.449322)
			(size 0.3048 1.1176)
			(layers "F.Cu" "F.Mask" "F.Paste")
			(net "P12V_STBY_VIN_PU1")
		)
		(pad "14" smd rect
			(at -1.500124 2.449322)
			(size 0.3048 1.1176)
			(layers "F.Cu" "F.Mask" "F.Paste")
			(net "P12V_STBY_VIN_PU1")
		)
		(pad "15" smd rect
			(at -0.999998 2.449322)
			(size 0.3048 1.1176)
			(layers "F.Cu" "F.Mask" "F.Paste")
			(net "P12V_STBY_VIN_PU1")
		)
		(pad "16" smd rect
			(at -0.500126 2.449322)
			(size 0.3048 1.1176)
			(layers "F.Cu" "F.Mask" "F.Paste")
			(net "P12V_STBY_VIN_PU1")
		)
		(pad "17" smd rect
			(at 0 2.449322)
			(size 0.3048 1.1176)
			(layers "F.Cu" "F.Mask" "F.Paste")
			(net "P12V_STBY_VIN_PU1")
		)
		(pad "18" smd rect
			(at 0.500126 2.449322)
			(size 0.3048 1.1176)
			(layers "F.Cu" "F.Mask" "F.Paste")
			(net "P5V_STBY_VREG")
		)
		(pad "19" smd rect
			(at 0.999998 2.449322)
			(size 0.3048 1.1176)
			(layers "F.Cu" "F.Mask" "F.Paste")
			(net "P12V_STBY_VDD_PU1")
		)
		(pad "20" smd rect
			(at 1.500124 2.449322)
			(size 0.3048 1.1176)
			(layers "F.Cu" "F.Mask" "F.Paste")
			(net "P5V_MODE")
		)
		(pad "21" smd rect
			(at 1.999996 2.449322)
			(size 0.3048 1.1176)
			(layers "F.Cu" "F.Mask" "F.Paste")
			(net "P5V_TRIP")
		)
		(pad "22" smd rect
			(at 2.500122 2.449322)
			(size 0.3048 1.1176)
			(layers "F.Cu" "F.Mask" "F.Paste")
			(net "P5V_RF")
		)
		(pad "23" smd custom
			(at 0 0)
			(size 0.83185 0.83185)
			(layers "F.Cu" "F.Mask" "F.Paste")
			(net "GND")
			(options
				(clearance outline)
				(anchor circle)
			)
			(primitives
				(gr_poly
					(pts
						(xy -2.7813 1.6637) (xy -2.7813 1.2954) (xy -3.048 1.2954) (xy -3.048 0.9525) (xy -2.7813 0.9525)
						(xy -2.7813 -0.9525) (xy -3.048 -0.9525) (xy -3.048 -1.2954) (xy -2.7813 -1.2954) (xy -2.7813 -1.6637)
						(xy 2.7813 -1.6637) (xy 2.7813 -1.2954) (xy 3.048 -1.2954) (xy 3.048 -0.9525) (xy 2.7813 -0.9525)
						(xy 2.7813 0.9525) (xy 3.048 0.9525) (xy 3.048 1.2954) (xy 2.7813 1.2954) (xy 2.7813 1.6637)
					)
					(width 0)
					(fill yes)
				)
			)
		)
	)
	(footprint ""
		(layer "F.Cu")
		(at 46.552358 -123.794012)
		(property "Reference" "R787"
			(at 0 0 0)
			(layer "F.SilkS")
			(hide yes)
			(effects
				(font
					(size 1.27 1.27)
				)
			)
		)
		(property "Value" "0R2J-2-GP"
			(at 0.064008 -3.993896 0)
			(unlocked yes)
			(layer "F.Fab")
			(hide yes)
			(effects
				(font
					(size 1.016 1.016)
					(thickness 0.1524)
				)
			)
		)
		(property "Device Type" "R402H16"
			(at 0.064008 -5.517896 0)
			(unlocked yes)
			(layer "F.Fab")
			(hide yes)
			(effects
				(font
					(size 1.016 1.016)
					(thickness 0.1524)
				)
			)
		)
		(duplicate_pad_numbers_are_jumpers no)
		(fp_line
			(start -0.508 -0.9398)
			(end -0.508 0.9398)
			(stroke
				(width 0.1524)
				(type default)
			)
			(layer "F.SilkS")
		)
		(fp_line
			(start 0.508 -0.9398)
			(end -0.508 -0.9398)
			(stroke
				(width 0.1524)
				(type default)
			)
			(layer "F.SilkS")
		)
		(fp_rect
			(start -0.508 0.9398)
			(end 0.508 -0.9398)
			(stroke
				(width 0)
				(type default)
			)
			(fill no)
			(layer "F.CrtYd")
		)
		(fp_rect
			(start -0.508 0.9398)
			(end 0.508 -0.9398)
			(stroke
				(width 0)
				(type default)
			)
			(fill no)
			(layer "F.Fab")
		)
		(pad "1" smd custom
			(at 0 -0.4445)
			(size 0.1397 0.1397)
			(layers "F.Cu" "F.Mask" "F.Paste")
			(net "FLA_CS_0_R")
			(options
				(clearance outline)
				(anchor circle)
			)
			(primitives
				(gr_poly
					(pts
						(arc
							(start -0.1778 -0.2794)
							(mid -0.249642 -0.249642)
							(end -0.2794 -0.1778)
						)
						(arc
							(start -0.2794 0.1778)
							(mid -0.249642 0.249642)
							(end -0.1778 0.2794)
						)
						(arc
							(start 0.1778 0.2794)
							(mid 0.249642 0.249642)
							(end 0.2794 0.1778)
						)
						(arc
							(start 0.2794 -0.1778)
							(mid 0.249642 -0.249642)
							(end 0.1778 -0.2794)
						)
					)
					(width 0)
					(fill yes)
				)
			)
		)
		(pad "2" smd custom
			(at 0 0.4445)
			(size 0.1397 0.1397)
			(layers "F.Cu" "F.Mask" "F.Paste")
			(net "BMC_CPU_EN")
			(options
				(clearance outline)
				(anchor circle)
			)
			(primitives
				(gr_poly
					(pts
						(arc
							(start -0.1778 -0.2794)
							(mid -0.249642 -0.249642)
							(end -0.2794 -0.1778)
						)
						(arc
							(start -0.2794 0.1778)
							(mid -0.249642 0.249642)
							(end -0.1778 0.2794)
						)
						(arc
							(start 0.1778 0.2794)
							(mid 0.249642 0.249642)
							(end 0.2794 0.1778)
						)
						(arc
							(start 0.2794 -0.1778)
							(mid 0.249642 -0.249642)
							(end 0.1778 -0.2794)
						)
					)
					(width 0)
					(fill yes)
				)
			)
		)
	)
	(footprint ""
		(layer "F.Cu")
		(at 63.3476 -148.7678 90)
		(property "Reference" "R189"
			(at 0 0 90)
			(layer "F.SilkS")
			(hide yes)
			(effects
				(font
					(size 1.27 1.27)
				)
			)
		)
		(property "Value" "499R2F-2-GP"
			(at 0.064008 -3.993896 90)
			(unlocked yes)
			(layer "F.Fab")
			(hide yes)
			(effects
				(font
					(size 1.016 1.016)
					(thickness 0.1524)
				)
			)
		)
		(property "Device Type" "R402H16"
			(at 0.064008 -5.517896 90)
			(unlocked yes)
			(layer "F.Fab")
			(hide yes)
			(effects
				(font
					(size 1.016 1.016)
					(thickness 0.1524)
				)
			)
		)
		(duplicate_pad_numbers_are_jumpers no)
		(fp_line
			(start 0.508 -0.9398)
			(end -0.508 -0.9398)
			(stroke
				(width 0.1524)
				(type default)
			)
			(layer "F.SilkS")
		)
		(fp_line
			(start -0.508 -0.9398)
			(end -0.508 0.9398)
			(stroke
				(width 0.1524)
				(type default)
			)
			(layer "F.SilkS")
		)
		(fp_rect
			(start -0.508 0.9398)
			(end 0.508 -0.9398)
			(stroke
				(width 0)
				(type default)
			)
			(fill no)
			(layer "F.CrtYd")
		)
		(fp_rect
			(start -0.508 0.9398)
			(end 0.508 -0.9398)
			(stroke
				(width 0)
				(type default)
			)
			(fill no)
			(layer "F.Fab")
		)
		(pad "1" smd custom
			(at 0 -0.4445 90)
			(size 0.1397 0.1397)
			(layers "F.Cu" "F.Mask" "F.Paste")
			(net "I2C_BMC_COMP_SCL_OUT")
			(options
				(clearance outline)
				(anchor circle)
			)
			(primitives
				(gr_poly
					(pts
						(arc
							(start -0.1778 -0.2794)
							(mid -0.249642 -0.249642)
							(end -0.2794 -0.1778)
						)
						(arc
							(start -0.2794 0.1778)
							(mid -0.249642 0.249642)
							(end -0.1778 0.2794)
						)
						(arc
							(start 0.1778 0.2794)
							(mid 0.249642 0.249642)
							(end 0.2794 0.1778)
						)
						(arc
							(start 0.2794 -0.1778)
							(mid 0.249642 -0.249642)
							(end 0.1778 -0.2794)
						)
					)
					(width 0)
					(fill yes)
				)
			)
		)
		(pad "2" smd custom
			(at 0 0.4445 90)
			(size 0.1397 0.1397)
			(layers "F.Cu" "F.Mask" "F.Paste")
			(net "P3V3_STBY")
			(options
				(clearance outline)
				(anchor circle)
			)
			(primitives
				(gr_poly
					(pts
						(arc
							(start -0.1778 -0.2794)
							(mid -0.249642 -0.249642)
							(end -0.2794 -0.1778)
						)
						(arc
							(start -0.2794 0.1778)
							(mid -0.249642 0.249642)
							(end -0.1778 0.2794)
						)
						(arc
							(start 0.1778 0.2794)
							(mid 0.249642 0.249642)
							(end 0.2794 0.1778)
						)
						(arc
							(start 0.2794 -0.1778)
							(mid 0.249642 -0.249642)
							(end 0.1778 -0.2794)
						)
					)
					(width 0)
					(fill yes)
				)
			)
		)
	)
	(footprint ""
		(layer "F.Cu")
		(at 84.983828 -91.750896 90)
		(property "Reference" "VIA15"
			(at 0 0 90)
			(layer "F.SilkS")
			(hide yes)
			(effects
				(font
					(size 1.27 1.27)
				)
			)
		)
		(property "Value" "85OHM-8L-1D6MM-L16L18-GP"
			(at 4.064 0.6096 90)
			(unlocked yes)
			(layer "F.Fab")
			(hide yes)
			(effects
				(font
					(size 1.016 1.016)
					(thickness 0.1524)
				)
			)
		)
		(property "Device Type" "VIA-PCIE-4P-368076"
			(at 4.064 -0.9144 90)
			(unlocked yes)
			(layer "F.Fab")
			(hide yes)
			(effects
				(font
					(size 1.016 1.016)
					(thickness 0.1524)
				)
			)
		)
		(duplicate_pad_numbers_are_jumpers no)
		(fp_rect
			(start -1.8415 0.381)
			(end 1.8415 -0.381)
			(stroke
				(width 0)
				(type default)
			)
			(fill no)
			(layer "F.CrtYd")
		)
		(fp_rect
			(start -1.8415 0.381)
			(end 1.8415 -0.381)
			(stroke
				(width 0)
				(type default)
			)
			(fill no)
			(layer "F.Fab")
		)
		(pad "1" thru_hole circle
			(at -1.4605 0 90)
			(size 0.508 0.508)
			(drill 0.254)
			(layers "*.Cu" "*.Mask")
			(remove_unused_layers no)
			(net "GND")
			(clearance 0.127)
			(thermal_gap 0.127)
		)
		(pad "2" thru_hole circle
			(at -0.4445 0 90)
			(size 0.508 0.508)
			(drill 0.254)
			(layers "*.Cu" "*.Mask")
			(remove_unused_layers no)
			(net "PCIE_IOM_TO_COMP_22_DP")
			(clearance 0.127)
			(thermal_gap 0.127)
		)
		(pad "3" thru_hole circle
			(at 0.4445 0 90)
			(size 0.508 0.508)
			(drill 0.254)
			(layers "*.Cu" "*.Mask")
			(remove_unused_layers no)
			(net "PCIE_IOM_TO_COMP_22_DN")
			(clearance 0.127)
			(thermal_gap 0.127)
		)
		(pad "4" thru_hole circle
			(at 1.4605 0 90)
			(size 0.508 0.508)
			(drill 0.254)
			(layers "*.Cu" "*.Mask")
			(remove_unused_layers no)
			(net "GND")
			(clearance 0.127)
			(thermal_gap 0.127)
		)
	)
	(footprint ""
		(layer "F.Cu")
		(at 83.316064 -138.129264 -90)
		(property "Reference" "R99"
			(at 0 0 270)
			(layer "F.SilkS")
			(hide yes)
			(effects
				(font
					(size 1.27 1.27)
				)
			)
		)
		(property "Value" "0R2J-2-GP"
			(at 0.064008 -3.993896 270)
			(unlocked yes)
			(layer "F.Fab")
			(hide yes)
			(effects
				(font
					(size 1.016 1.016)
					(thickness 0.1524)
				)
			)
		)
		(property "Device Type" "R402H16"
			(at 0.064008 -5.517896 270)
			(unlocked yes)
			(layer "F.Fab")
			(hide yes)
			(effects
				(font
					(size 1.016 1.016)
					(thickness 0.1524)
				)
			)
		)
		(duplicate_pad_numbers_are_jumpers no)
		(fp_line
			(start -0.508 -0.9398)
			(end -0.508 0.9398)
			(stroke
				(width 0.1524)
				(type default)
			)
			(layer "F.SilkS")
		)
		(fp_line
			(start 0.508 -0.9398)
			(end -0.508 -0.9398)
			(stroke
				(width 0.1524)
				(type default)
			)
			(layer "F.SilkS")
		)
		(fp_rect
			(start -0.508 0.9398)
			(end 0.508 -0.9398)
			(stroke
				(width 0)
				(type default)
			)
			(fill no)
			(layer "F.CrtYd")
		)
		(fp_rect
			(start -0.508 0.9398)
			(end 0.508 -0.9398)
			(stroke
				(width 0)
				(type default)
			)
			(fill no)
			(layer "F.Fab")
		)
		(pad "1" smd custom
			(at 0 -0.4445 270)
			(size 0.1397 0.1397)
			(layers "F.Cu" "F.Mask" "F.Paste")
			(net "P3V3_STBY")
			(options
				(clearance outline)
				(anchor circle)
			)
			(primitives
				(gr_poly
					(pts
						(arc
							(start -0.1778 -0.2794)
							(mid -0.249642 -0.249642)
							(end -0.2794 -0.1778)
						)
						(arc
							(start -0.2794 0.1778)
							(mid -0.249642 0.249642)
							(end -0.1778 0.2794)
						)
						(arc
							(start 0.1778 0.2794)
							(mid 0.249642 0.249642)
							(end 0.2794 0.1778)
						)
						(arc
							(start 0.2794 -0.1778)
							(mid 0.249642 -0.249642)
							(end 0.1778 -0.2794)
						)
					)
					(width 0)
					(fill yes)
				)
			)
		)
		(pad "2" smd custom
			(at 0 0.4445 270)
			(size 0.1397 0.1397)
			(layers "F.Cu" "F.Mask" "F.Paste")
			(net "D_FLIP_PRE#")
			(options
				(clearance outline)
				(anchor circle)
			)
			(primitives
				(gr_poly
					(pts
						(arc
							(start -0.1778 -0.2794)
							(mid -0.249642 -0.249642)
							(end -0.2794 -0.1778)
						)
						(arc
							(start -0.2794 0.1778)
							(mid -0.249642 0.249642)
							(end -0.1778 0.2794)
						)
						(arc
							(start 0.1778 0.2794)
							(mid 0.249642 0.249642)
							(end 0.2794 0.1778)
						)
						(arc
							(start 0.2794 -0.1778)
							(mid 0.249642 -0.249642)
							(end 0.1778 -0.2794)
						)
					)
					(width 0)
					(fill yes)
				)
			)
		)
	)
	(footprint ""
		(layer "F.Cu")
		(at 87.357966 -49.194212 90)
		(property "Reference" "R503"
			(at 0 0 90)
			(layer "F.SilkS")
			(hide yes)
			(effects
				(font
					(size 1.27 1.27)
				)
			)
		)
		(property "Value" "1KR2F-3-GP"
			(at 0.064008 -3.993896 90)
			(unlocked yes)
			(layer "F.Fab")
			(hide yes)
			(effects
				(font
					(size 1.016 1.016)
					(thickness 0.1524)
				)
			)
		)
		(property "Device Type" "R402H16"
			(at 0.064008 -5.517896 90)
			(unlocked yes)
			(layer "F.Fab")
			(hide yes)
			(effects
				(font
					(size 1.016 1.016)
					(thickness 0.1524)
				)
			)
		)
		(duplicate_pad_numbers_are_jumpers no)
		(fp_line
			(start 0.508 -0.9398)
			(end -0.508 -0.9398)
			(stroke
				(width 0.1524)
				(type default)
			)
			(layer "F.SilkS")
		)
		(fp_line
			(start -0.508 -0.9398)
			(end -0.508 0.9398)
			(stroke
				(width 0.1524)
				(type default)
			)
			(layer "F.SilkS")
		)
		(fp_rect
			(start -0.508 0.9398)
			(end 0.508 -0.9398)
			(stroke
				(width 0)
				(type default)
			)
			(fill no)
			(layer "F.CrtYd")
		)
		(fp_rect
			(start -0.508 0.9398)
			(end 0.508 -0.9398)
			(stroke
				(width 0)
				(type default)
			)
			(fill no)
			(layer "F.Fab")
		)
		(pad "1" smd custom
			(at 0 -0.4445 90)
			(size 0.1397 0.1397)
			(layers "F.Cu" "F.Mask" "F.Paste")
			(net "P3V3")
			(options
				(clearance outline)
				(anchor circle)
			)
			(primitives
				(gr_poly
					(pts
						(arc
							(start -0.1778 -0.2794)
							(mid -0.249642 -0.249642)
							(end -0.2794 -0.1778)
						)
						(arc
							(start -0.2794 0.1778)
							(mid -0.249642 0.249642)
							(end -0.1778 0.2794)
						)
						(arc
							(start 0.1778 0.2794)
							(mid 0.249642 0.249642)
							(end 0.2794 0.1778)
						)
						(arc
							(start 0.2794 -0.1778)
							(mid 0.249642 -0.249642)
							(end 0.1778 -0.2794)
						)
					)
					(width 0)
					(fill yes)
				)
			)
		)
		(pad "2" smd custom
			(at 0 0.4445 90)
			(size 0.1397 0.1397)
			(layers "F.Cu" "F.Mask" "F.Paste")
			(net "GND")
			(options
				(clearance outline)
				(anchor circle)
			)
			(primitives
				(gr_poly
					(pts
						(arc
							(start -0.1778 -0.2794)
							(mid -0.249642 -0.249642)
							(end -0.2794 -0.1778)
						)
						(arc
							(start -0.2794 0.1778)
							(mid -0.249642 0.249642)
							(end -0.1778 0.2794)
						)
						(arc
							(start 0.1778 0.2794)
							(mid 0.249642 0.249642)
							(end 0.2794 0.1778)
						)
						(arc
							(start 0.2794 -0.1778)
							(mid 0.249642 -0.249642)
							(end 0.1778 -0.2794)
						)
					)
					(width 0)
					(fill yes)
				)
			)
		)
	)
	(footprint ""
		(layer "F.Cu")
		(at 224.259902 -58.546492 180)
		(property "Reference" "R571"
			(at 0 0 180)
			(layer "F.SilkS")
			(hide yes)
			(effects
				(font
					(size 1.27 1.27)
				)
			)
		)
		(property "Value" "0R2J-2-GP"
			(at 0.064008 -3.993896 180)
			(unlocked yes)
			(layer "F.Fab")
			(hide yes)
			(effects
				(font
					(size 1.016 1.016)
					(thickness 0.1524)
				)
			)
		)
		(property "Device Type" "R402H16"
			(at 0.064008 -5.517896 180)
			(unlocked yes)
			(layer "F.Fab")
			(hide yes)
			(effects
				(font
					(size 1.016 1.016)
					(thickness 0.1524)
				)
			)
		)
		(duplicate_pad_numbers_are_jumpers no)
		(fp_line
			(start 0.508 -0.9398)
			(end -0.508 -0.9398)
			(stroke
				(width 0.1524)
				(type default)
			)
			(layer "F.SilkS")
		)
		(fp_line
			(start -0.508 -0.9398)
			(end -0.508 0.9398)
			(stroke
				(width 0.1524)
				(type default)
			)
			(layer "F.SilkS")
		)
		(fp_rect
			(start -0.508 0.9398)
			(end 0.508 -0.9398)
			(stroke
				(width 0)
				(type default)
			)
			(fill no)
			(layer "F.CrtYd")
		)
		(fp_rect
			(start -0.508 0.9398)
			(end 0.508 -0.9398)
			(stroke
				(width 0)
				(type default)
			)
			(fill no)
			(layer "F.Fab")
		)
		(pad "1" smd custom
			(at 0 -0.4445 180)
			(size 0.1397 0.1397)
			(layers "F.Cu" "F.Mask" "F.Paste")
			(net "REF_CLK")
			(options
				(clearance outline)
				(anchor circle)
			)
			(primitives
				(gr_poly
					(pts
						(arc
							(start -0.1778 -0.2794)
							(mid -0.249642 -0.249642)
							(end -0.2794 -0.1778)
						)
						(arc
							(start -0.2794 0.1778)
							(mid -0.249642 0.249642)
							(end -0.1778 0.2794)
						)
						(arc
							(start 0.1778 0.2794)
							(mid 0.249642 0.249642)
							(end 0.2794 0.1778)
						)
						(arc
							(start 0.2794 -0.1778)
							(mid 0.249642 -0.249642)
							(end 0.1778 -0.2794)
						)
					)
					(width 0)
					(fill yes)
				)
			)
		)
		(pad "2" smd custom
			(at 0 0.4445 180)
			(size 0.1397 0.1397)
			(layers "F.Cu" "F.Mask" "F.Paste")
			(net "IOC_REF_CLK_N")
			(options
				(clearance outline)
				(anchor circle)
			)
			(primitives
				(gr_poly
					(pts
						(arc
							(start -0.1778 -0.2794)
							(mid -0.249642 -0.249642)
							(end -0.2794 -0.1778)
						)
						(arc
							(start -0.2794 0.1778)
							(mid -0.249642 0.249642)
							(end -0.1778 0.2794)
						)
						(arc
							(start 0.1778 0.2794)
							(mid 0.249642 0.249642)
							(end 0.2794 0.1778)
						)
						(arc
							(start 0.2794 -0.1778)
							(mid 0.249642 -0.249642)
							(end 0.1778 -0.2794)
						)
					)
					(width 0)
					(fill yes)
				)
			)
		)
	)
	(footprint ""
		(layer "F.Cu")
		(at 62.6872 -137.6426)
		(property "Reference" "TP55"
			(at 0 0 0)
			(layer "F.SilkS")
			(hide yes)
			(effects
				(font
					(size 1.27 1.27)
				)
			)
		)
		(property "Value" "TPAD28-2-GP"
			(at -0.0127 -1.6637 0)
			(unlocked yes)
			(layer "F.Fab")
			(hide yes)
			(effects
				(font
					(size 1.016 1.016)
					(thickness 0.1524)
				)
			)
		)
		(property "Device Type" "TPAD28"
			(at -0.0127 -3.1877 0)
			(unlocked yes)
			(layer "F.Fab")
			(hide yes)
			(effects
				(font
					(size 1.016 1.016)
					(thickness 0.1524)
				)
			)
		)
		(duplicate_pad_numbers_are_jumpers no)
		(fp_poly
			(pts
				(arc
					(start 0.3556 0)
					(mid -0.3556 0)
					(end 0.3556 0)
				)
			)
			(stroke
				(width 0)
				(type default)
			)
			(fill no)
			(layer "F.CrtYd")
		)
		(fp_poly
			(pts
				(arc
					(start 0.6096 0)
					(mid -0.6096 0)
					(end 0.6096 0)
				)
			)
			(stroke
				(width 0)
				(type default)
			)
			(fill no)
			(layer "F.Fab")
		)
		(pad "1" smd circle
			(at 0 0)
			(size 0.7112 0.7112)
			(layers "F.Cu" "F.Mask" "F.Paste")
			(net "TP_BMC_GPIOA7")
		)
	)
	(footprint ""
		(layer "F.Cu")
		(at 140.9954 -14.44752)
		(property "Reference" "U50"
			(at 0 0 0)
			(layer "F.SilkS")
			(hide yes)
			(effects
				(font
					(size 1.27 1.27)
				)
			)
		)
		(property "Value" "74LVC1G86DCKR-GP"
			(at -2.3368 -8.6868 0)
			(unlocked yes)
			(layer "F.Fab")
			(hide yes)
			(effects
				(font
					(size 1.016 1.016)
					(thickness 0.1524)
				)
			)
		)
		(property "Device Type" "SC70-5H44"
			(at -2.3114 -10.414 0)
			(unlocked yes)
			(layer "F.Fab")
			(hide yes)
			(effects
				(font
					(size 1.016 1.016)
					(thickness 0.1524)
				)
			)
		)
		(duplicate_pad_numbers_are_jumpers no)
		(fp_line
			(start -1.27 -1.7018)
			(end 1.27 -1.7018)
			(stroke
				(width 0.1524)
				(type default)
			)
			(layer "F.SilkS")
		)
		(fp_line
			(start -1.27 1.7018)
			(end -1.27 -1.7018)
			(stroke
				(width 0.1524)
				(type default)
			)
			(layer "F.SilkS")
		)
		(fp_line
			(start 0.6604 -1.8034)
			(end 1.3843 -1.8034)
			(stroke
				(width 0.3302)
				(type default)
			)
			(layer "F.SilkS")
		)
		(fp_line
			(start 1.27 -1.7018)
			(end 1.27 1.7018)
			(stroke
				(width 0.1524)
				(type default)
			)
			(layer "F.SilkS")
		)
		(fp_line
			(start 1.27 1.7018)
			(end -1.27 1.7018)
			(stroke
				(width 0.1524)
				(type default)
			)
			(layer "F.SilkS")
		)
		(fp_line
			(start 1.3843 -1.8034)
			(end 1.3843 -1.1176)
			(stroke
				(width 0.3302)
				(type default)
			)
			(layer "F.SilkS")
		)
		(fp_rect
			(start -1.524 1.9558)
			(end 1.524 -1.9558)
			(stroke
				(width 0)
				(type default)
			)
			(fill no)
			(layer "F.CrtYd")
		)
		(fp_poly
			(pts
				(xy -1.524 -1.9558) (xy 1.524 -1.9558) (xy 1.524 1.9558) (xy -1.524 1.9558)
			)
			(stroke
				(width 0)
				(type default)
			)
			(fill no)
			(layer "F.Fab")
		)
		(pad "1" smd rect
			(at 0.65024 -0.8255)
			(size 0.4064 1.2192)
			(layers "F.Cu" "F.Mask" "F.Paste")
			(net "IOC_EXT2_LED_B")
		)
		(pad "2" smd rect
			(at 0 -0.8255)
			(size 0.4064 1.2192)
			(layers "F.Cu" "F.Mask" "F.Paste")
			(net "IOC_EXT2_LED_Y")
		)
		(pad "3" smd rect
			(at -0.65024 -0.8255)
			(size 0.4064 1.2192)
			(layers "F.Cu" "F.Mask" "F.Paste")
			(net "GND")
		)
		(pad "4" smd rect
			(at -0.65024 0.8255)
			(size 0.4064 1.2192)
			(layers "F.Cu" "F.Mask" "F.Paste")
			(net "IOC_EXT2_LED_Y_XOR")
		)
		(pad "5" smd rect
			(at 0.65024 0.8255)
			(size 0.4064 1.2192)
			(layers "F.Cu" "F.Mask" "F.Paste")
			(net "P1V8")
		)
	)
	(footprint ""
		(layer "F.Cu")
		(at 91.6432 -125.349 180)
		(property "Reference" "C522"
			(at 0 0 180)
			(layer "F.SilkS")
			(hide yes)
			(effects
				(font
					(size 1.27 1.27)
				)
			)
		)
		(property "Value" "SCD1U25V2KX-2-GP"
			(at 1.1811 -2.7051 180)
			(unlocked yes)
			(layer "F.Fab")
			(hide yes)
			(effects
				(font
					(size 1.016 1.016)
					(thickness 0.1524)
				)
			)
		)
		(property "Device Type" "C402H22"
			(at 1.1811 -4.2291 180)
			(unlocked yes)
			(layer "F.Fab")
			(hide yes)
			(effects
				(font
					(size 1.016 1.016)
					(thickness 0.1524)
				)
			)
		)
		(duplicate_pad_numbers_are_jumpers no)
		(fp_rect
			(start -0.4318 0.9525)
			(end 0.4318 -0.9525)
			(stroke
				(width 0)
				(type default)
			)
			(fill no)
			(layer "F.CrtYd")
		)
		(fp_rect
			(start -0.4318 0.9525)
			(end 0.4318 -0.9525)
			(stroke
				(width 0)
				(type default)
			)
			(fill no)
			(layer "F.Fab")
		)
		(pad "1" smd custom
			(at 0 -0.4445 180)
			(size 0.1524 0.1524)
			(layers "F.Cu" "F.Mask" "F.Paste")
			(net "P3V3_STBY")
			(options
				(clearance outline)
				(anchor circle)
			)
			(primitives
				(gr_poly
					(pts
						(arc
							(start 0.3048 -0.2032)
							(mid 0.275042 -0.275042)
							(end 0.2032 -0.3048)
						)
						(arc
							(start -0.2032 -0.3048)
							(mid -0.275042 -0.275042)
							(end -0.3048 -0.2032)
						)
						(arc
							(start -0.3048 0.2032)
							(mid -0.275042 0.275042)
							(end -0.2032 0.3048)
						)
						(arc
							(start 0.2032 0.3048)
							(mid 0.275042 0.275042)
							(end 0.3048 0.2032)
						)
					)
					(width 0)
					(fill yes)
				)
			)
		)
		(pad "2" smd custom
			(at 0 0.4445 180)
			(size 0.1524 0.1524)
			(layers "F.Cu" "F.Mask" "F.Paste")
			(net "GND")
			(options
				(clearance outline)
				(anchor circle)
			)
			(primitives
				(gr_poly
					(pts
						(arc
							(start 0.3048 -0.2032)
							(mid 0.275042 -0.275042)
							(end 0.2032 -0.3048)
						)
						(arc
							(start -0.2032 -0.3048)
							(mid -0.275042 -0.275042)
							(end -0.3048 -0.2032)
						)
						(arc
							(start -0.3048 0.2032)
							(mid -0.275042 0.275042)
							(end -0.2032 0.3048)
						)
						(arc
							(start 0.2032 0.3048)
							(mid 0.275042 0.275042)
							(end 0.3048 0.2032)
						)
					)
					(width 0)
					(fill yes)
				)
			)
		)
	)
	(footprint ""
		(layer "F.Cu")
		(at 165.0238 -126.8984 90)
		(property "Reference" "C211"
			(at 0 0 90)
			(layer "F.SilkS")
			(hide yes)
			(effects
				(font
					(size 1.27 1.27)
				)
			)
		)
		(property "Value" "SCD1U50V3KX-GP"
			(at 0 -2.8194 90)
			(unlocked yes)
			(layer "F.Fab")
			(hide yes)
			(effects
				(font
					(size 1.016 1.016)
					(thickness 0.1524)
				)
			)
		)
		(property "Device Type" "C603H36"
			(at 0 -4.3434 90)
			(unlocked yes)
			(layer "F.Fab")
			(hide yes)
			(effects
				(font
					(size 1.016 1.016)
					(thickness 0.1524)
				)
			)
		)
		(duplicate_pad_numbers_are_jumpers no)
		(fp_line
			(start 0.508 0)
			(end -0.508 0)
			(stroke
				(width 0.2032)
				(type default)
			)
			(layer "F.SilkS")
		)
		(fp_rect
			(start -0.5842 1.3335)
			(end 0.5842 -1.3335)
			(stroke
				(width 0)
				(type default)
			)
			(fill no)
			(layer "F.CrtYd")
		)
		(fp_rect
			(start -0.5842 1.3335)
			(end 0.5842 -1.3335)
			(stroke
				(width 0)
				(type default)
			)
			(fill no)
			(layer "F.Fab")
		)
		(pad "1" smd custom
			(at 0 -0.762 90)
			(size 0.2159 0.2159)
			(layers "F.Cu" "F.Mask" "F.Paste")
			(net "P1V8_STBY")
			(options
				(clearance outline)
				(anchor circle)
			)
			(primitives
				(gr_poly
					(pts
						(arc
							(start -0.3302 -0.4318)
							(mid -0.402042 -0.402042)
							(end -0.4318 -0.3302)
						)
						(arc
							(start -0.4318 0.3302)
							(mid -0.402042 0.402042)
							(end -0.3302 0.4318)
						)
						(arc
							(start 0.3302 0.4318)
							(mid 0.402042 0.402042)
							(end 0.4318 0.3302)
						)
						(arc
							(start 0.4318 -0.3302)
							(mid 0.402042 -0.402042)
							(end 0.3302 -0.4318)
						)
					)
					(width 0)
					(fill yes)
				)
			)
		)
		(pad "2" smd custom
			(at 0 0.762 90)
			(size 0.2159 0.2159)
			(layers "F.Cu" "F.Mask" "F.Paste")
			(net "P1V8_STBY_VFB_R")
			(options
				(clearance outline)
				(anchor circle)
			)
			(primitives
				(gr_poly
					(pts
						(arc
							(start -0.3302 -0.4318)
							(mid -0.402042 -0.402042)
							(end -0.4318 -0.3302)
						)
						(arc
							(start -0.4318 0.3302)
							(mid -0.402042 0.402042)
							(end -0.3302 0.4318)
						)
						(arc
							(start 0.3302 0.4318)
							(mid 0.402042 0.402042)
							(end 0.4318 0.3302)
						)
						(arc
							(start 0.4318 -0.3302)
							(mid 0.402042 -0.402042)
							(end 0.3302 -0.4318)
						)
					)
					(width 0)
					(fill yes)
				)
			)
		)
	)
	(footprint ""
		(layer "F.Cu")
		(at 178.7652 -153.2128)
		(property "Reference" "R467"
			(at 0 0 0)
			(layer "F.SilkS")
			(hide yes)
			(effects
				(font
					(size 1.27 1.27)
				)
			)
		)
		(property "Value" "10KR2F-2-GP"
			(at 0.064008 -3.993896 0)
			(unlocked yes)
			(layer "F.Fab")
			(hide yes)
			(effects
				(font
					(size 1.016 1.016)
					(thickness 0.1524)
				)
			)
		)
		(property "Device Type" "R402H16"
			(at 0.064008 -5.517896 0)
			(unlocked yes)
			(layer "F.Fab")
			(hide yes)
			(effects
				(font
					(size 1.016 1.016)
					(thickness 0.1524)
				)
			)
		)
		(duplicate_pad_numbers_are_jumpers no)
		(fp_line
			(start -0.508 -0.9398)
			(end -0.508 0.9398)
			(stroke
				(width 0.1524)
				(type default)
			)
			(layer "F.SilkS")
		)
		(fp_line
			(start 0.508 -0.9398)
			(end -0.508 -0.9398)
			(stroke
				(width 0.1524)
				(type default)
			)
			(layer "F.SilkS")
		)
		(fp_rect
			(start -0.508 0.9398)
			(end 0.508 -0.9398)
			(stroke
				(width 0)
				(type default)
			)
			(fill no)
			(layer "F.CrtYd")
		)
		(fp_rect
			(start -0.508 0.9398)
			(end 0.508 -0.9398)
			(stroke
				(width 0)
				(type default)
			)
			(fill no)
			(layer "F.Fab")
		)
		(pad "1" smd custom
			(at 0 -0.4445)
			(size 0.1397 0.1397)
			(layers "F.Cu" "F.Mask" "F.Paste")
			(net "P5V_STBY_VREG")
			(options
				(clearance outline)
				(anchor circle)
			)
			(primitives
				(gr_poly
					(pts
						(arc
							(start -0.1778 -0.2794)
							(mid -0.249642 -0.249642)
							(end -0.2794 -0.1778)
						)
						(arc
							(start -0.2794 0.1778)
							(mid -0.249642 0.249642)
							(end -0.1778 0.2794)
						)
						(arc
							(start 0.1778 0.2794)
							(mid 0.249642 0.249642)
							(end 0.2794 0.1778)
						)
						(arc
							(start 0.2794 -0.1778)
							(mid 0.249642 -0.249642)
							(end 0.1778 -0.2794)
						)
					)
					(width 0)
					(fill yes)
				)
			)
		)
		(pad "2" smd custom
			(at 0 0.4445)
			(size 0.1397 0.1397)
			(layers "F.Cu" "F.Mask" "F.Paste")
			(net "PWRGD_P5V_STBY")
			(options
				(clearance outline)
				(anchor circle)
			)
			(primitives
				(gr_poly
					(pts
						(arc
							(start -0.1778 -0.2794)
							(mid -0.249642 -0.249642)
							(end -0.2794 -0.1778)
						)
						(arc
							(start -0.2794 0.1778)
							(mid -0.249642 0.249642)
							(end -0.1778 0.2794)
						)
						(arc
							(start 0.1778 0.2794)
							(mid 0.249642 0.249642)
							(end 0.2794 0.1778)
						)
						(arc
							(start 0.2794 -0.1778)
							(mid 0.249642 -0.249642)
							(end 0.1778 -0.2794)
						)
					)
					(width 0)
					(fill yes)
				)
			)
		)
	)
	(footprint ""
		(layer "F.Cu")
		(at 87.3506 -48.227996 90)
		(property "Reference" "C189"
			(at 0 0 90)
			(layer "F.SilkS")
			(hide yes)
			(effects
				(font
					(size 1.27 1.27)
				)
			)
		)
		(property "Value" "SCD1U25V2KX-2-GP"
			(at 1.1811 -2.7051 90)
			(unlocked yes)
			(layer "F.Fab")
			(hide yes)
			(effects
				(font
					(size 1.016 1.016)
					(thickness 0.1524)
				)
			)
		)
		(property "Device Type" "C402H22"
			(at 1.1811 -4.2291 90)
			(unlocked yes)
			(layer "F.Fab")
			(hide yes)
			(effects
				(font
					(size 1.016 1.016)
					(thickness 0.1524)
				)
			)
		)
		(duplicate_pad_numbers_are_jumpers no)
		(fp_rect
			(start -0.4318 0.9525)
			(end 0.4318 -0.9525)
			(stroke
				(width 0)
				(type default)
			)
			(fill no)
			(layer "F.CrtYd")
		)
		(fp_rect
			(start -0.4318 0.9525)
			(end 0.4318 -0.9525)
			(stroke
				(width 0)
				(type default)
			)
			(fill no)
			(layer "F.Fab")
		)
		(pad "1" smd custom
			(at 0 -0.4445 90)
			(size 0.1524 0.1524)
			(layers "F.Cu" "F.Mask" "F.Paste")
			(net "P3V3")
			(options
				(clearance outline)
				(anchor circle)
			)
			(primitives
				(gr_poly
					(pts
						(arc
							(start 0.3048 -0.2032)
							(mid 0.275042 -0.275042)
							(end 0.2032 -0.3048)
						)
						(arc
							(start -0.2032 -0.3048)
							(mid -0.275042 -0.275042)
							(end -0.3048 -0.2032)
						)
						(arc
							(start -0.3048 0.2032)
							(mid -0.275042 0.275042)
							(end -0.2032 0.3048)
						)
						(arc
							(start 0.2032 0.3048)
							(mid 0.275042 0.275042)
							(end 0.3048 0.2032)
						)
					)
					(width 0)
					(fill yes)
				)
			)
		)
		(pad "2" smd custom
			(at 0 0.4445 90)
			(size 0.1524 0.1524)
			(layers "F.Cu" "F.Mask" "F.Paste")
			(net "GND")
			(options
				(clearance outline)
				(anchor circle)
			)
			(primitives
				(gr_poly
					(pts
						(arc
							(start 0.3048 -0.2032)
							(mid 0.275042 -0.275042)
							(end 0.2032 -0.3048)
						)
						(arc
							(start -0.2032 -0.3048)
							(mid -0.275042 -0.275042)
							(end -0.3048 -0.2032)
						)
						(arc
							(start -0.3048 0.2032)
							(mid -0.275042 0.275042)
							(end -0.2032 0.3048)
						)
						(arc
							(start 0.2032 0.3048)
							(mid 0.275042 0.275042)
							(end 0.3048 0.2032)
						)
					)
					(width 0)
					(fill yes)
				)
			)
		)
	)
	(footprint ""
		(layer "F.Cu")
		(at 63.119 -169.291 90)
		(property "Reference" "Q4"
			(at 0 0 90)
			(layer "F.SilkS")
			(hide yes)
			(effects
				(font
					(size 1.27 1.27)
				)
			)
		)
		(property "Value" "2N7002K-1-GP"
			(at 0.127 -8.9662 90)
			(unlocked yes)
			(layer "F.Fab")
			(hide yes)
			(effects
				(font
					(size 1.016 1.016)
					(thickness 0.1524)
				)
			)
		)
		(property "Device Type" "SOT23DGS2D4H44"
			(at 0.127 -10.4902 90)
			(unlocked yes)
			(layer "F.Fab")
			(hide yes)
			(effects
				(font
					(size 1.016 1.016)
					(thickness 0.1524)
				)
			)
		)
		(duplicate_pad_numbers_are_jumpers no)
		(fp_line
			(start 1.651 -1.778)
			(end -1.651 -1.778)
			(stroke
				(width 0.1524)
				(type default)
			)
			(layer "F.SilkS")
		)
		(fp_line
			(start -1.651 -1.778)
			(end -1.651 1.778)
			(stroke
				(width 0.1524)
				(type default)
			)
			(layer "F.SilkS")
		)
		(fp_line
			(start 1.651 1.778)
			(end 1.651 -1.778)
			(stroke
				(width 0.1524)
				(type default)
			)
			(layer "F.SilkS")
		)
		(fp_line
			(start -1.651 1.778)
			(end 1.651 1.778)
			(stroke
				(width 0.1524)
				(type default)
			)
			(layer "F.SilkS")
		)
		(fp_poly
			(pts
				(xy -1.778 1.8796) (xy -1.778 -1.8796) (xy 1.778 -1.8796) (xy 1.778 1.8796)
			)
			(stroke
				(width 0)
				(type default)
			)
			(fill no)
			(layer "F.CrtYd")
		)
		(fp_poly
			(pts
				(xy -1.778 1.8796) (xy -1.778 -1.8796) (xy 1.778 -1.8796) (xy 1.778 1.8796)
			)
			(stroke
				(width 0)
				(type default)
			)
			(fill no)
			(layer "F.Fab")
		)
		(pad "D" smd custom
			(at 0 -0.9525 90)
			(size 0.1905 0.1905)
			(layers "F.Cu" "F.Mask" "F.Paste")
			(net "FM_TPM_PRSNT_RST_N")
			(options
				(clearance outline)
				(anchor circle)
			)
			(primitives
				(gr_poly
					(pts
						(arc
							(start -0.1778 0.5715)
							(mid -0.321484 0.511984)
							(end -0.381 0.3683)
						)
						(arc
							(start -0.381 -0.3683)
							(mid -0.321484 -0.511984)
							(end -0.1778 -0.5715)
						)
						(arc
							(start 0.1778 -0.5715)
							(mid 0.321484 -0.511984)
							(end 0.381 -0.3683)
						)
						(arc
							(start 0.381 0.3683)
							(mid 0.321484 0.511984)
							(end 0.1778 0.5715)
						)
					)
					(width 0)
					(fill yes)
				)
			)
		)
		(pad "G" smd custom
			(at -0.98425 0.9525 90)
			(size 0.1905 0.1905)
			(layers "F.Cu" "F.Mask" "F.Paste")
			(net "Q4_G")
			(options
				(clearance outline)
				(anchor circle)
			)
			(primitives
				(gr_poly
					(pts
						(arc
							(start -0.1778 0.5715)
							(mid -0.321484 0.511984)
							(end -0.381 0.3683)
						)
						(arc
							(start -0.381 -0.3683)
							(mid -0.321484 -0.511984)
							(end -0.1778 -0.5715)
						)
						(arc
							(start 0.1778 -0.5715)
							(mid 0.321484 -0.511984)
							(end 0.381 -0.3683)
						)
						(arc
							(start 0.381 0.3683)
							(mid 0.321484 0.511984)
							(end 0.1778 0.5715)
						)
					)
					(width 0)
					(fill yes)
				)
			)
		)
		(pad "S" smd custom
			(at 0.98425 0.9525 90)
			(size 0.1905 0.1905)
			(layers "F.Cu" "F.Mask" "F.Paste")
			(net "GND")
			(options
				(clearance outline)
				(anchor circle)
			)
			(primitives
				(gr_poly
					(pts
						(arc
							(start -0.1778 0.5715)
							(mid -0.321484 0.511984)
							(end -0.381 0.3683)
						)
						(arc
							(start -0.381 -0.3683)
							(mid -0.321484 -0.511984)
							(end -0.1778 -0.5715)
						)
						(arc
							(start 0.1778 -0.5715)
							(mid 0.321484 -0.511984)
							(end 0.381 -0.3683)
						)
						(arc
							(start 0.381 0.3683)
							(mid 0.321484 0.511984)
							(end 0.1778 0.5715)
						)
					)
					(width 0)
					(fill yes)
				)
			)
		)
	)
	(footprint ""
		(layer "F.Cu")
		(at 205.794356 -126.9619 -90)
		(property "Reference" "PU7"
			(at 0 0 270)
			(layer "F.SilkS")
			(hide yes)
			(effects
				(font
					(size 1.27 1.27)
				)
			)
		)
		(property "Value" "TPS74801RGW-GP"
			(at -4.7244 -6.223 270)
			(unlocked yes)
			(layer "F.Fab")
			(hide yes)
			(effects
				(font
					(size 1.016 1.016)
					(thickness 0.1524)
				)
			)
		)
		(property "Device Type" "QFN20-1G3D15H40"
			(at -4.7244 -7.747 270)
			(unlocked yes)
			(layer "F.Fab")
			(hide yes)
			(effects
				(font
					(size 1.016 1.016)
					(thickness 0.1524)
				)
			)
		)
		(duplicate_pad_numbers_are_jumpers no)
		(fp_line
			(start -3.5179 3.5179)
			(end -2.2479 3.5179)
			(stroke
				(width 0.1524)
				(type default)
			)
			(layer "F.SilkS")
		)
		(fp_line
			(start 2.2479 3.5179)
			(end 3.5179 3.5179)
			(stroke
				(width 0.1524)
				(type default)
			)
			(layer "F.SilkS")
		)
		(fp_line
			(start 3.5179 3.5179)
			(end 3.5179 2.2479)
			(stroke
				(width 0.1524)
				(type default)
			)
			(layer "F.SilkS")
		)
		(fp_line
			(start 1.299972 3.160522)
			(end 1.299972 3.668522)
			(stroke
				(width 0.1524)
				(type default)
			)
			(layer "F.SilkS")
		)
		(fp_line
			(start -3.5179 2.2479)
			(end -3.5179 3.5179)
			(stroke
				(width 0.1524)
				(type default)
			)
			(layer "F.SilkS")
		)
		(fp_line
			(start -3.160522 1.299972)
			(end -3.922522 1.299972)
			(stroke
				(width 0.1524)
				(type default)
			)
			(layer "F.SilkS")
		)
		(fp_line
			(start 3.160522 -1.299972)
			(end 3.922522 -1.299972)
			(stroke
				(width 0.1524)
				(type default)
			)
			(layer "F.SilkS")
		)
		(fp_line
			(start -1.299972 -3.160522)
			(end -1.299972 -3.668522)
			(stroke
				(width 0.1524)
				(type default)
			)
			(layer "F.SilkS")
		)
		(fp_line
			(start -3.5179 -3.5179)
			(end -3.5179 -2.2479)
			(stroke
				(width 0.1524)
				(type default)
			)
			(layer "F.SilkS")
		)
		(fp_line
			(start -2.2479 -3.5179)
			(end -3.5179 -3.5179)
			(stroke
				(width 0.1524)
				(type default)
			)
			(layer "F.SilkS")
		)
		(fp_poly
			(pts
				(xy 3.5179 -3.5179) (xy 2.2479 -3.5179) (xy 3.5179 -2.2479)
			)
			(stroke
				(width 0)
				(type default)
			)
			(fill yes)
			(layer "F.SilkS")
		)
		(fp_rect
			(start -2.5019 2.5019)
			(end 2.5019 -2.5019)
			(stroke
				(width 0)
				(type default)
			)
			(fill no)
			(layer "F.CrtYd")
		)
		(fp_poly
			(pts
				(xy -3.5179 3.5179) (xy -3.5179 -3.5179) (xy 3.5179 -3.5179) (xy 3.5179 -2.5019) (xy -2.5019 -2.5019)
				(xy -2.5019 2.5019) (xy 2.5019 2.5019) (xy 2.5019 -2.49682) (xy 3.5179 -2.49682) (xy 3.5179 3.5179)
			)
			(stroke
				(width 0)
				(type default)
			)
			(fill no)
			(layer "F.CrtYd")
		)
		(fp_rect
			(start -3.5179 3.5179)
			(end 3.5179 -3.5179)
			(stroke
				(width 0)
				(type default)
			)
			(fill no)
			(layer "F.Fab")
		)
		(pad "1" smd rect
			(at 1.299972 -2.474722 270)
			(size 0.3556 1.0668)
			(layers "F.Cu" "F.Mask" "F.Paste")
			(net "P1V5_OUT")
		)
		(pad "2" smd rect
			(at 0.649986 -2.474722 270)
			(size 0.3556 1.0668)
			(layers "F.Cu" "F.Mask" "F.Paste")
			(net "GND")
		)
		(pad "3" smd rect
			(at 0 -2.474722 270)
			(size 0.3556 1.0668)
			(layers "F.Cu" "F.Mask" "F.Paste")
			(net "GND")
		)
		(pad "4" smd rect
			(at -0.649986 -2.474722 270)
			(size 0.3556 1.0668)
			(layers "F.Cu" "F.Mask" "F.Paste")
			(net "GND")
		)
		(pad "5" smd rect
			(at -1.299972 -2.474722 270)
			(size 0.3556 1.0668)
			(layers "F.Cu" "F.Mask" "F.Paste")
			(net "P1V8_STBY")
		)
		(pad "6" smd rect
			(at -2.474722 -1.299972 270)
			(size 1.0668 0.3556)
			(layers "F.Cu" "F.Mask" "F.Paste")
			(net "P1V8_STBY")
		)
		(pad "7" smd rect
			(at -2.474722 -0.649986 270)
			(size 1.0668 0.3556)
			(layers "F.Cu" "F.Mask" "F.Paste")
			(net "P1V8_STBY")
		)
		(pad "8" smd rect
			(at -2.474722 0 270)
			(size 1.0668 0.3556)
			(layers "F.Cu" "F.Mask" "F.Paste")
			(net "P1V8_STBY")
		)
		(pad "9" smd rect
			(at -2.474722 0.649986 270)
			(size 1.0668 0.3556)
			(layers "F.Cu" "F.Mask" "F.Paste")
			(net "PWRGD_P1V5")
		)
		(pad "10" smd rect
			(at -2.474722 1.299972 270)
			(size 1.0668 0.3556)
			(layers "F.Cu" "F.Mask" "F.Paste")
			(net "TPS74801_1V5_BIAS")
		)
		(pad "11" smd rect
			(at -1.299972 2.474722 270)
			(size 0.3556 1.0668)
			(layers "F.Cu" "F.Mask" "F.Paste")
			(net "TPS74801_1V5_EN")
		)
		(pad "12" smd rect
			(at -0.649986 2.474722 270)
			(size 0.3556 1.0668)
			(layers "F.Cu" "F.Mask" "F.Paste")
			(net "GND")
		)
		(pad "13" smd rect
			(at 0 2.474722 270)
			(size 0.3556 1.0668)
			(layers "F.Cu" "F.Mask" "F.Paste")
			(net "GND")
		)
		(pad "14" smd rect
			(at 0.649986 2.474722 270)
			(size 0.3556 1.0668)
			(layers "F.Cu" "F.Mask" "F.Paste")
			(net "GND")
		)
		(pad "15" smd rect
			(at 1.299972 2.474722 270)
			(size 0.3556 1.0668)
			(layers "F.Cu" "F.Mask" "F.Paste")
			(net "TPS74801_1V5_SS")
		)
		(pad "16" smd rect
			(at 2.474722 1.299972 270)
			(size 1.0668 0.3556)
			(layers "F.Cu" "F.Mask" "F.Paste")
			(net "TPS74801_P1V5_FB")
		)
		(pad "17" smd rect
			(at 2.474722 0.649986 270)
			(size 1.0668 0.3556)
			(layers "F.Cu" "F.Mask" "F.Paste")
			(net "GND")
		)
		(pad "18" smd rect
			(at 2.474722 0 270)
			(size 1.0668 0.3556)
			(layers "F.Cu" "F.Mask" "F.Paste")
			(net "P1V5_OUT")
		)
		(pad "19" smd rect
			(at 2.474722 -0.649986 270)
			(size 1.0668 0.3556)
			(layers "F.Cu" "F.Mask" "F.Paste")
			(net "P1V5_OUT")
		)
		(pad "20" smd rect
			(at 2.474722 -1.299972 270)
			(size 1.0668 0.3556)
			(layers "F.Cu" "F.Mask" "F.Paste")
			(net "P1V5_OUT")
		)
		(pad "21" smd rect
			(at 0 0 270)
			(size 3.2512 3.2512)
			(layers "F.Cu" "F.Mask" "F.Paste")
			(net "GND")
		)
	)
	(footprint ""
		(layer "F.Cu")
		(at 179.324 -82.931)
		(property "Reference" "R628"
			(at 0 0 0)
			(layer "F.SilkS")
			(hide yes)
			(effects
				(font
					(size 1.27 1.27)
				)
			)
		)
		(property "Value" "4K7R2F-GP"
			(at 0.064008 -3.993896 0)
			(unlocked yes)
			(layer "F.Fab")
			(hide yes)
			(effects
				(font
					(size 1.016 1.016)
					(thickness 0.1524)
				)
			)
		)
		(property "Device Type" "R402H16"
			(at 0.064008 -5.517896 0)
			(unlocked yes)
			(layer "F.Fab")
			(hide yes)
			(effects
				(font
					(size 1.016 1.016)
					(thickness 0.1524)
				)
			)
		)
		(duplicate_pad_numbers_are_jumpers no)
		(fp_line
			(start -0.508 -0.9398)
			(end -0.508 0.9398)
			(stroke
				(width 0.1524)
				(type default)
			)
			(layer "F.SilkS")
		)
		(fp_line
			(start 0.508 -0.9398)
			(end -0.508 -0.9398)
			(stroke
				(width 0.1524)
				(type default)
			)
			(layer "F.SilkS")
		)
		(fp_rect
			(start -0.508 0.9398)
			(end 0.508 -0.9398)
			(stroke
				(width 0)
				(type default)
			)
			(fill no)
			(layer "F.CrtYd")
		)
		(fp_rect
			(start -0.508 0.9398)
			(end 0.508 -0.9398)
			(stroke
				(width 0)
				(type default)
			)
			(fill no)
			(layer "F.Fab")
		)
		(pad "1" smd custom
			(at 0 -0.4445)
			(size 0.1397 0.1397)
			(layers "F.Cu" "F.Mask" "F.Paste")
			(net "P1V8")
			(options
				(clearance outline)
				(anchor circle)
			)
			(primitives
				(gr_poly
					(pts
						(arc
							(start -0.1778 -0.2794)
							(mid -0.249642 -0.249642)
							(end -0.2794 -0.1778)
						)
						(arc
							(start -0.2794 0.1778)
							(mid -0.249642 0.249642)
							(end -0.1778 0.2794)
						)
						(arc
							(start 0.1778 0.2794)
							(mid 0.249642 0.249642)
							(end 0.2794 0.1778)
						)
						(arc
							(start 0.2794 -0.1778)
							(mid 0.249642 -0.249642)
							(end 0.1778 -0.2794)
						)
					)
					(width 0)
					(fill yes)
				)
			)
		)
		(pad "2" smd custom
			(at 0 0.4445)
			(size 0.1397 0.1397)
			(layers "F.Cu" "F.Mask" "F.Paste")
			(net "SYS_HALT1#")
			(options
				(clearance outline)
				(anchor circle)
			)
			(primitives
				(gr_poly
					(pts
						(arc
							(start -0.1778 -0.2794)
							(mid -0.249642 -0.249642)
							(end -0.2794 -0.1778)
						)
						(arc
							(start -0.2794 0.1778)
							(mid -0.249642 0.249642)
							(end -0.1778 0.2794)
						)
						(arc
							(start 0.1778 0.2794)
							(mid 0.249642 0.249642)
							(end 0.2794 0.1778)
						)
						(arc
							(start 0.2794 -0.1778)
							(mid 0.249642 -0.249642)
							(end 0.1778 -0.2794)
						)
					)
					(width 0)
					(fill yes)
				)
			)
		)
	)
	(footprint ""
		(layer "F.Cu")
		(at 199.893936 -128.4224 90)
		(property "Reference" "R548"
			(at 0 0 90)
			(layer "F.SilkS")
			(hide yes)
			(effects
				(font
					(size 1.27 1.27)
				)
			)
		)
		(property "Value" "4K75R2F-1-GP"
			(at 0.064008 -3.993896 90)
			(unlocked yes)
			(layer "F.Fab")
			(hide yes)
			(effects
				(font
					(size 1.016 1.016)
					(thickness 0.1524)
				)
			)
		)
		(property "Device Type" "R402H16"
			(at 0.064008 -5.517896 90)
			(unlocked yes)
			(layer "F.Fab")
			(hide yes)
			(effects
				(font
					(size 1.016 1.016)
					(thickness 0.1524)
				)
			)
		)
		(duplicate_pad_numbers_are_jumpers no)
		(fp_line
			(start 0.508 -0.9398)
			(end -0.508 -0.9398)
			(stroke
				(width 0.1524)
				(type default)
			)
			(layer "F.SilkS")
		)
		(fp_line
			(start -0.508 -0.9398)
			(end -0.508 0.9398)
			(stroke
				(width 0.1524)
				(type default)
			)
			(layer "F.SilkS")
		)
		(fp_rect
			(start -0.508 0.9398)
			(end 0.508 -0.9398)
			(stroke
				(width 0)
				(type default)
			)
			(fill no)
			(layer "F.CrtYd")
		)
		(fp_rect
			(start -0.508 0.9398)
			(end 0.508 -0.9398)
			(stroke
				(width 0)
				(type default)
			)
			(fill no)
			(layer "F.Fab")
		)
		(pad "1" smd custom
			(at 0 -0.4445 90)
			(size 0.1397 0.1397)
			(layers "F.Cu" "F.Mask" "F.Paste")
			(net "P3V3_STBY")
			(options
				(clearance outline)
				(anchor circle)
			)
			(primitives
				(gr_poly
					(pts
						(arc
							(start -0.1778 -0.2794)
							(mid -0.249642 -0.249642)
							(end -0.2794 -0.1778)
						)
						(arc
							(start -0.2794 0.1778)
							(mid -0.249642 0.249642)
							(end -0.1778 0.2794)
						)
						(arc
							(start 0.1778 0.2794)
							(mid 0.249642 0.249642)
							(end 0.2794 0.1778)
						)
						(arc
							(start 0.2794 -0.1778)
							(mid 0.249642 -0.249642)
							(end 0.1778 -0.2794)
						)
					)
					(width 0)
					(fill yes)
				)
			)
		)
		(pad "2" smd custom
			(at 0 0.4445 90)
			(size 0.1397 0.1397)
			(layers "F.Cu" "F.Mask" "F.Paste")
			(net "TPS74801_1V5_EN")
			(options
				(clearance outline)
				(anchor circle)
			)
			(primitives
				(gr_poly
					(pts
						(arc
							(start -0.1778 -0.2794)
							(mid -0.249642 -0.249642)
							(end -0.2794 -0.1778)
						)
						(arc
							(start -0.2794 0.1778)
							(mid -0.249642 0.249642)
							(end -0.1778 0.2794)
						)
						(arc
							(start 0.1778 0.2794)
							(mid 0.249642 0.249642)
							(end 0.2794 0.1778)
						)
						(arc
							(start 0.2794 -0.1778)
							(mid 0.249642 -0.249642)
							(end 0.1778 -0.2794)
						)
					)
					(width 0)
					(fill yes)
				)
			)
		)
	)
	(footprint ""
		(layer "F.Cu")
		(at 81.8134 -163.449)
		(property "Reference" "C242"
			(at 0 0 0)
			(layer "F.SilkS")
			(hide yes)
			(effects
				(font
					(size 1.27 1.27)
				)
			)
		)
		(property "Value" "SCD1U16V2KX-3GP"
			(at 1.1811 -2.7051 0)
			(unlocked yes)
			(layer "F.Fab")
			(hide yes)
			(effects
				(font
					(size 1.016 1.016)
					(thickness 0.1524)
				)
			)
		)
		(property "Device Type" "C402H22"
			(at 1.1811 -4.2291 0)
			(unlocked yes)
			(layer "F.Fab")
			(hide yes)
			(effects
				(font
					(size 1.016 1.016)
					(thickness 0.1524)
				)
			)
		)
		(duplicate_pad_numbers_are_jumpers no)
		(fp_rect
			(start -0.4318 0.9525)
			(end 0.4318 -0.9525)
			(stroke
				(width 0)
				(type default)
			)
			(fill no)
			(layer "F.CrtYd")
		)
		(fp_rect
			(start -0.4318 0.9525)
			(end 0.4318 -0.9525)
			(stroke
				(width 0)
				(type default)
			)
			(fill no)
			(layer "F.Fab")
		)
		(pad "1" smd custom
			(at 0 -0.4445)
			(size 0.1524 0.1524)
			(layers "F.Cu" "F.Mask" "F.Paste")
			(net "P1V8_STBY")
			(options
				(clearance outline)
				(anchor circle)
			)
			(primitives
				(gr_poly
					(pts
						(arc
							(start 0.3048 -0.2032)
							(mid 0.275042 -0.275042)
							(end 0.2032 -0.3048)
						)
						(arc
							(start -0.2032 -0.3048)
							(mid -0.275042 -0.275042)
							(end -0.3048 -0.2032)
						)
						(arc
							(start -0.3048 0.2032)
							(mid -0.275042 0.275042)
							(end -0.2032 0.3048)
						)
						(arc
							(start 0.2032 0.3048)
							(mid 0.275042 0.275042)
							(end 0.3048 0.2032)
						)
					)
					(width 0)
					(fill yes)
				)
			)
		)
		(pad "2" smd custom
			(at 0 0.4445)
			(size 0.1524 0.1524)
			(layers "F.Cu" "F.Mask" "F.Paste")
			(net "GND")
			(options
				(clearance outline)
				(anchor circle)
			)
			(primitives
				(gr_poly
					(pts
						(arc
							(start 0.3048 -0.2032)
							(mid 0.275042 -0.275042)
							(end 0.2032 -0.3048)
						)
						(arc
							(start -0.2032 -0.3048)
							(mid -0.275042 -0.275042)
							(end -0.3048 -0.2032)
						)
						(arc
							(start -0.3048 0.2032)
							(mid -0.275042 0.275042)
							(end -0.2032 0.3048)
						)
						(arc
							(start 0.2032 0.3048)
							(mid 0.275042 0.275042)
							(end 0.3048 0.2032)
						)
					)
					(width 0)
					(fill yes)
				)
			)
		)
	)
	(footprint ""
		(layer "F.Cu")
		(at 208.055972 -64.4144 90)
		(property "Reference" "C322"
			(at 0 0 90)
			(layer "F.SilkS")
			(hide yes)
			(effects
				(font
					(size 1.27 1.27)
				)
			)
		)
		(property "Value" "SCD01U16V1KX-GP"
			(at -2.8321 -1.7399 90)
			(unlocked yes)
			(layer "F.Fab")
			(hide yes)
			(effects
				(font
					(size 1.016 1.016)
					(thickness 0.1524)
				)
			)
		)
		(property "Device Type" "C0201H13"
			(at -2.8321 -3.2639 90)
			(unlocked yes)
			(layer "F.Fab")
			(hide yes)
			(effects
				(font
					(size 1.016 1.016)
					(thickness 0.1524)
				)
			)
		)
		(duplicate_pad_numbers_are_jumpers no)
		(fp_rect
			(start -0.2794 0.6477)
			(end 0.2794 -0.6477)
			(stroke
				(width 0)
				(type default)
			)
			(fill no)
			(layer "F.CrtYd")
		)
		(fp_rect
			(start -0.2794 0.6477)
			(end 0.2794 -0.6477)
			(stroke
				(width 0)
				(type default)
			)
			(fill no)
			(layer "F.Fab")
		)
		(pad "1" smd custom
			(at 0 -0.2794 90)
			(size 0.0762 0.0762)
			(layers "F.Cu" "F.Mask" "F.Paste")
			(net "PHY_IOC_TO_CON_B_3_DN_C")
			(options
				(clearance outline)
				(anchor circle)
			)
			(primitives
				(gr_poly
					(pts
						(arc
							(start 0.1524 -0.127)
							(mid 0.137521 -0.162921)
							(end 0.1016 -0.1778)
						)
						(arc
							(start -0.1016 -0.1778)
							(mid -0.137521 -0.162921)
							(end -0.1524 -0.127)
						)
						(arc
							(start -0.1524 0.127)
							(mid -0.137521 0.162921)
							(end -0.1016 0.1778)
						)
						(arc
							(start 0.1016 0.1778)
							(mid 0.137521 0.162921)
							(end 0.1524 0.127)
						)
					)
					(width 0)
					(fill yes)
				)
			)
		)
		(pad "2" smd custom
			(at 0 0.2794 90)
			(size 0.0762 0.0762)
			(layers "F.Cu" "F.Mask" "F.Paste")
			(net "PHY_IOC_TO_CON_B_3_DN")
			(options
				(clearance outline)
				(anchor circle)
			)
			(primitives
				(gr_poly
					(pts
						(arc
							(start 0.1524 -0.127)
							(mid 0.137521 -0.162921)
							(end 0.1016 -0.1778)
						)
						(arc
							(start -0.1016 -0.1778)
							(mid -0.137521 -0.162921)
							(end -0.1524 -0.127)
						)
						(arc
							(start -0.1524 0.127)
							(mid -0.137521 0.162921)
							(end -0.1016 0.1778)
						)
						(arc
							(start 0.1016 0.1778)
							(mid 0.137521 0.162921)
							(end 0.1524 0.127)
						)
					)
					(width 0)
					(fill yes)
				)
			)
		)
	)
	(footprint ""
		(layer "F.Cu")
		(at 190.881 -13.01242 180)
		(property "Reference" "R800"
			(at 0 0 180)
			(layer "F.SilkS")
			(hide yes)
			(effects
				(font
					(size 1.27 1.27)
				)
			)
		)
		(property "Value" "130R3F-GP"
			(at -0.0254 -2.5146 180)
			(unlocked yes)
			(layer "F.Fab")
			(hide yes)
			(effects
				(font
					(size 1.016 1.016)
					(thickness 0.1524)
				)
			)
		)
		(property "Device Type" "R603H22"
			(at -0.0254 -4.0386 180)
			(unlocked yes)
			(layer "F.Fab")
			(hide yes)
			(effects
				(font
					(size 1.016 1.016)
					(thickness 0.1524)
				)
			)
		)
		(duplicate_pad_numbers_are_jumpers no)
		(fp_line
			(start 0.2032 0)
			(end 0.4826 0)
			(stroke
				(width 0.2032)
				(type default)
			)
			(layer "F.SilkS")
		)
		(fp_line
			(start -0.4826 0)
			(end -0.2032 0)
			(stroke
				(width 0.2032)
				(type default)
			)
			(layer "F.SilkS")
		)
		(fp_rect
			(start -0.5842 1.3335)
			(end 0.5842 -1.3335)
			(stroke
				(width 0)
				(type default)
			)
			(fill no)
			(layer "F.CrtYd")
		)
		(fp_rect
			(start -0.5842 1.3335)
			(end 0.5842 -1.3335)
			(stroke
				(width 0)
				(type default)
			)
			(fill no)
			(layer "F.Fab")
		)
		(pad "1" smd custom
			(at 0 -0.762 180)
			(size 0.2159 0.2159)
			(layers "F.Cu" "F.Mask" "F.Paste")
			(net "EXT1_LED_BLUE")
			(options
				(clearance outline)
				(anchor circle)
			)
			(primitives
				(gr_poly
					(pts
						(arc
							(start -0.3302 -0.4318)
							(mid -0.402042 -0.402042)
							(end -0.4318 -0.3302)
						)
						(arc
							(start -0.4318 0.3302)
							(mid -0.402042 0.402042)
							(end -0.3302 0.4318)
						)
						(arc
							(start 0.3302 0.4318)
							(mid 0.402042 0.402042)
							(end 0.4318 0.3302)
						)
						(arc
							(start 0.4318 -0.3302)
							(mid 0.402042 -0.402042)
							(end 0.3302 -0.4318)
						)
					)
					(width 0)
					(fill yes)
				)
			)
		)
		(pad "2" smd custom
			(at 0 0.762 180)
			(size 0.2159 0.2159)
			(layers "F.Cu" "F.Mask" "F.Paste")
			(net "EXT1_LED_BLUE_D")
			(options
				(clearance outline)
				(anchor circle)
			)
			(primitives
				(gr_poly
					(pts
						(arc
							(start -0.3302 -0.4318)
							(mid -0.402042 -0.402042)
							(end -0.4318 -0.3302)
						)
						(arc
							(start -0.4318 0.3302)
							(mid -0.402042 0.402042)
							(end -0.3302 0.4318)
						)
						(arc
							(start 0.3302 0.4318)
							(mid 0.402042 0.402042)
							(end 0.4318 0.3302)
						)
						(arc
							(start 0.4318 -0.3302)
							(mid 0.402042 -0.402042)
							(end 0.3302 -0.4318)
						)
					)
					(width 0)
					(fill yes)
				)
			)
		)
	)
	(footprint ""
		(layer "F.Cu")
		(at 58.7502 -163.5252 180)
		(property "Reference" "R410"
			(at 0 0 180)
			(layer "F.SilkS")
			(hide yes)
			(effects
				(font
					(size 1.27 1.27)
				)
			)
		)
		(property "Value" "1KR2F-3-GP"
			(at 0.064008 -3.993896 180)
			(unlocked yes)
			(layer "F.Fab")
			(hide yes)
			(effects
				(font
					(size 1.016 1.016)
					(thickness 0.1524)
				)
			)
		)
		(property "Device Type" "R402H16"
			(at 0.064008 -5.517896 180)
			(unlocked yes)
			(layer "F.Fab")
			(hide yes)
			(effects
				(font
					(size 1.016 1.016)
					(thickness 0.1524)
				)
			)
		)
		(duplicate_pad_numbers_are_jumpers no)
		(fp_line
			(start 0.508 -0.9398)
			(end -0.508 -0.9398)
			(stroke
				(width 0.1524)
				(type default)
			)
			(layer "F.SilkS")
		)
		(fp_line
			(start -0.508 -0.9398)
			(end -0.508 0.9398)
			(stroke
				(width 0.1524)
				(type default)
			)
			(layer "F.SilkS")
		)
		(fp_rect
			(start -0.508 0.9398)
			(end 0.508 -0.9398)
			(stroke
				(width 0)
				(type default)
			)
			(fill no)
			(layer "F.CrtYd")
		)
		(fp_rect
			(start -0.508 0.9398)
			(end 0.508 -0.9398)
			(stroke
				(width 0)
				(type default)
			)
			(fill no)
			(layer "F.Fab")
		)
		(pad "1" smd custom
			(at 0 -0.4445 180)
			(size 0.1397 0.1397)
			(layers "F.Cu" "F.Mask" "F.Paste")
			(net "ADC_P3V3_STBY")
			(options
				(clearance outline)
				(anchor circle)
			)
			(primitives
				(gr_poly
					(pts
						(arc
							(start -0.1778 -0.2794)
							(mid -0.249642 -0.249642)
							(end -0.2794 -0.1778)
						)
						(arc
							(start -0.2794 0.1778)
							(mid -0.249642 0.249642)
							(end -0.1778 0.2794)
						)
						(arc
							(start 0.1778 0.2794)
							(mid 0.249642 0.249642)
							(end 0.2794 0.1778)
						)
						(arc
							(start 0.2794 -0.1778)
							(mid 0.249642 -0.249642)
							(end 0.1778 -0.2794)
						)
					)
					(width 0)
					(fill yes)
				)
			)
		)
		(pad "2" smd custom
			(at 0 0.4445 180)
			(size 0.1397 0.1397)
			(layers "F.Cu" "F.Mask" "F.Paste")
			(net "GND")
			(options
				(clearance outline)
				(anchor circle)
			)
			(primitives
				(gr_poly
					(pts
						(arc
							(start -0.1778 -0.2794)
							(mid -0.249642 -0.249642)
							(end -0.2794 -0.1778)
						)
						(arc
							(start -0.2794 0.1778)
							(mid -0.249642 0.249642)
							(end -0.1778 0.2794)
						)
						(arc
							(start 0.1778 0.2794)
							(mid 0.249642 0.249642)
							(end 0.2794 0.1778)
						)
						(arc
							(start 0.2794 -0.1778)
							(mid 0.249642 -0.249642)
							(end 0.1778 -0.2794)
						)
					)
					(width 0)
					(fill yes)
				)
			)
		)
	)
	(footprint ""
		(layer "F.Cu")
		(at 57.2516 -181.5592)
		(property "Reference" "C169"
			(at 0 0 0)
			(layer "F.SilkS")
			(hide yes)
			(effects
				(font
					(size 1.27 1.27)
				)
			)
		)
		(property "Value" "SCD1U16V2KX-3GP"
			(at 1.1811 -2.7051 0)
			(unlocked yes)
			(layer "F.Fab")
			(hide yes)
			(effects
				(font
					(size 1.016 1.016)
					(thickness 0.1524)
				)
			)
		)
		(property "Device Type" "C402H22"
			(at 1.1811 -4.2291 0)
			(unlocked yes)
			(layer "F.Fab")
			(hide yes)
			(effects
				(font
					(size 1.016 1.016)
					(thickness 0.1524)
				)
			)
		)
		(duplicate_pad_numbers_are_jumpers no)
		(fp_rect
			(start -0.4318 0.9525)
			(end 0.4318 -0.9525)
			(stroke
				(width 0)
				(type default)
			)
			(fill no)
			(layer "F.CrtYd")
		)
		(fp_rect
			(start -0.4318 0.9525)
			(end 0.4318 -0.9525)
			(stroke
				(width 0)
				(type default)
			)
			(fill no)
			(layer "F.Fab")
		)
		(pad "1" smd custom
			(at 0 -0.4445)
			(size 0.1524 0.1524)
			(layers "F.Cu" "F.Mask" "F.Paste")
			(net "P3V3_STBY_OUT")
			(options
				(clearance outline)
				(anchor circle)
			)
			(primitives
				(gr_poly
					(pts
						(arc
							(start 0.3048 -0.2032)
							(mid 0.275042 -0.275042)
							(end 0.2032 -0.3048)
						)
						(arc
							(start -0.2032 -0.3048)
							(mid -0.275042 -0.275042)
							(end -0.3048 -0.2032)
						)
						(arc
							(start -0.3048 0.2032)
							(mid -0.275042 0.275042)
							(end -0.2032 0.3048)
						)
						(arc
							(start 0.2032 0.3048)
							(mid 0.275042 0.275042)
							(end 0.3048 0.2032)
						)
					)
					(width 0)
					(fill yes)
				)
			)
		)
		(pad "2" smd custom
			(at 0 0.4445)
			(size 0.1524 0.1524)
			(layers "F.Cu" "F.Mask" "F.Paste")
			(net "GND")
			(options
				(clearance outline)
				(anchor circle)
			)
			(primitives
				(gr_poly
					(pts
						(arc
							(start 0.3048 -0.2032)
							(mid 0.275042 -0.275042)
							(end 0.2032 -0.3048)
						)
						(arc
							(start -0.2032 -0.3048)
							(mid -0.275042 -0.275042)
							(end -0.3048 -0.2032)
						)
						(arc
							(start -0.3048 0.2032)
							(mid -0.275042 0.275042)
							(end -0.2032 0.3048)
						)
						(arc
							(start 0.2032 0.3048)
							(mid 0.275042 0.275042)
							(end 0.3048 0.2032)
						)
					)
					(width 0)
					(fill yes)
				)
			)
		)
	)
	(footprint ""
		(layer "F.Cu")
		(at 143.22298 -13.310362 180)
		(property "Reference" "R801"
			(at 0 0 180)
			(layer "F.SilkS")
			(hide yes)
			(effects
				(font
					(size 1.27 1.27)
				)
			)
		)
		(property "Value" "130R3F-GP"
			(at -0.0254 -2.5146 180)
			(unlocked yes)
			(layer "F.Fab")
			(hide yes)
			(effects
				(font
					(size 1.016 1.016)
					(thickness 0.1524)
				)
			)
		)
		(property "Device Type" "R603H22"
			(at -0.0254 -4.0386 180)
			(unlocked yes)
			(layer "F.Fab")
			(hide yes)
			(effects
				(font
					(size 1.016 1.016)
					(thickness 0.1524)
				)
			)
		)
		(duplicate_pad_numbers_are_jumpers no)
		(fp_line
			(start 0.2032 0)
			(end 0.4826 0)
			(stroke
				(width 0.2032)
				(type default)
			)
			(layer "F.SilkS")
		)
		(fp_line
			(start -0.4826 0)
			(end -0.2032 0)
			(stroke
				(width 0.2032)
				(type default)
			)
			(layer "F.SilkS")
		)
		(fp_rect
			(start -0.5842 1.3335)
			(end 0.5842 -1.3335)
			(stroke
				(width 0)
				(type default)
			)
			(fill no)
			(layer "F.CrtYd")
		)
		(fp_rect
			(start -0.5842 1.3335)
			(end 0.5842 -1.3335)
			(stroke
				(width 0)
				(type default)
			)
			(fill no)
			(layer "F.Fab")
		)
		(pad "1" smd custom
			(at 0 -0.762 180)
			(size 0.2159 0.2159)
			(layers "F.Cu" "F.Mask" "F.Paste")
			(net "EXT2_LED_BLUE")
			(options
				(clearance outline)
				(anchor circle)
			)
			(primitives
				(gr_poly
					(pts
						(arc
							(start -0.3302 -0.4318)
							(mid -0.402042 -0.402042)
							(end -0.4318 -0.3302)
						)
						(arc
							(start -0.4318 0.3302)
							(mid -0.402042 0.402042)
							(end -0.3302 0.4318)
						)
						(arc
							(start 0.3302 0.4318)
							(mid 0.402042 0.402042)
							(end 0.4318 0.3302)
						)
						(arc
							(start 0.4318 -0.3302)
							(mid 0.402042 -0.402042)
							(end 0.3302 -0.4318)
						)
					)
					(width 0)
					(fill yes)
				)
			)
		)
		(pad "2" smd custom
			(at 0 0.762 180)
			(size 0.2159 0.2159)
			(layers "F.Cu" "F.Mask" "F.Paste")
			(net "EXT2_LED_BLUE_D")
			(options
				(clearance outline)
				(anchor circle)
			)
			(primitives
				(gr_poly
					(pts
						(arc
							(start -0.3302 -0.4318)
							(mid -0.402042 -0.402042)
							(end -0.4318 -0.3302)
						)
						(arc
							(start -0.4318 0.3302)
							(mid -0.402042 0.402042)
							(end -0.3302 0.4318)
						)
						(arc
							(start 0.3302 0.4318)
							(mid 0.402042 0.402042)
							(end 0.4318 0.3302)
						)
						(arc
							(start 0.4318 -0.3302)
							(mid 0.402042 -0.402042)
							(end 0.3302 -0.4318)
						)
					)
					(width 0)
					(fill yes)
				)
			)
		)
	)
	(footprint ""
		(layer "F.Cu")
		(at 44.714414 -125.91034 -90)
		(property "Reference" "R89"
			(at 0 0 270)
			(layer "F.SilkS")
			(hide yes)
			(effects
				(font
					(size 1.27 1.27)
				)
			)
		)
		(property "Value" "33D2R2F-GP"
			(at 0.064008 -3.993896 270)
			(unlocked yes)
			(layer "F.Fab")
			(hide yes)
			(effects
				(font
					(size 1.016 1.016)
					(thickness 0.1524)
				)
			)
		)
		(property "Device Type" "R402H16"
			(at 0.064008 -5.517896 270)
			(unlocked yes)
			(layer "F.Fab")
			(hide yes)
			(effects
				(font
					(size 1.016 1.016)
					(thickness 0.1524)
				)
			)
		)
		(duplicate_pad_numbers_are_jumpers no)
		(fp_line
			(start -0.508 -0.9398)
			(end -0.508 0.9398)
			(stroke
				(width 0.1524)
				(type default)
			)
			(layer "F.SilkS")
		)
		(fp_line
			(start 0.508 -0.9398)
			(end -0.508 -0.9398)
			(stroke
				(width 0.1524)
				(type default)
			)
			(layer "F.SilkS")
		)
		(fp_rect
			(start -0.508 0.9398)
			(end 0.508 -0.9398)
			(stroke
				(width 0)
				(type default)
			)
			(fill no)
			(layer "F.CrtYd")
		)
		(fp_rect
			(start -0.508 0.9398)
			(end 0.508 -0.9398)
			(stroke
				(width 0)
				(type default)
			)
			(fill no)
			(layer "F.Fab")
		)
		(pad "1" smd custom
			(at 0 -0.4445 270)
			(size 0.1397 0.1397)
			(layers "F.Cu" "F.Mask" "F.Paste")
			(net "BMC_SPI_MISO")
			(options
				(clearance outline)
				(anchor circle)
			)
			(primitives
				(gr_poly
					(pts
						(arc
							(start -0.1778 -0.2794)
							(mid -0.249642 -0.249642)
							(end -0.2794 -0.1778)
						)
						(arc
							(start -0.2794 0.1778)
							(mid -0.249642 0.249642)
							(end -0.1778 0.2794)
						)
						(arc
							(start 0.1778 0.2794)
							(mid 0.249642 0.249642)
							(end 0.2794 0.1778)
						)
						(arc
							(start 0.2794 -0.1778)
							(mid 0.249642 -0.249642)
							(end 0.1778 -0.2794)
						)
					)
					(width 0)
					(fill yes)
				)
			)
		)
		(pad "2" smd custom
			(at 0 0.4445 270)
			(size 0.1397 0.1397)
			(layers "F.Cu" "F.Mask" "F.Paste")
			(net "BMC_SPI_MISO_TPM")
			(options
				(clearance outline)
				(anchor circle)
			)
			(primitives
				(gr_poly
					(pts
						(arc
							(start -0.1778 -0.2794)
							(mid -0.249642 -0.249642)
							(end -0.2794 -0.1778)
						)
						(arc
							(start -0.2794 0.1778)
							(mid -0.249642 0.249642)
							(end -0.1778 0.2794)
						)
						(arc
							(start 0.1778 0.2794)
							(mid 0.249642 0.249642)
							(end 0.2794 0.1778)
						)
						(arc
							(start 0.2794 -0.1778)
							(mid 0.249642 -0.249642)
							(end 0.1778 -0.2794)
						)
					)
					(width 0)
					(fill yes)
				)
			)
		)
	)
	(footprint ""
		(layer "F.Cu")
		(at 84.184744 -167.69842)
		(property "Reference" "Q12"
			(at 0 0 0)
			(layer "F.SilkS")
			(hide yes)
			(effects
				(font
					(size 1.27 1.27)
				)
			)
		)
		(property "Value" "2N7002K-1-GP"
			(at 0.127 -8.9662 0)
			(unlocked yes)
			(layer "F.Fab")
			(hide yes)
			(effects
				(font
					(size 1.016 1.016)
					(thickness 0.1524)
				)
			)
		)
		(property "Device Type" "SOT23DGS2D4H44"
			(at 0.127 -10.4902 0)
			(unlocked yes)
			(layer "F.Fab")
			(hide yes)
			(effects
				(font
					(size 1.016 1.016)
					(thickness 0.1524)
				)
			)
		)
		(duplicate_pad_numbers_are_jumpers no)
		(fp_line
			(start -1.651 -1.778)
			(end -1.651 1.778)
			(stroke
				(width 0.1524)
				(type default)
			)
			(layer "F.SilkS")
		)
		(fp_line
			(start -1.651 1.778)
			(end 1.651 1.778)
			(stroke
				(width 0.1524)
				(type default)
			)
			(layer "F.SilkS")
		)
		(fp_line
			(start 1.651 -1.778)
			(end -1.651 -1.778)
			(stroke
				(width 0.1524)
				(type default)
			)
			(layer "F.SilkS")
		)
		(fp_line
			(start 1.651 1.778)
			(end 1.651 -1.778)
			(stroke
				(width 0.1524)
				(type default)
			)
			(layer "F.SilkS")
		)
		(fp_poly
			(pts
				(xy -1.778 1.8796) (xy -1.778 -1.8796) (xy 1.778 -1.8796) (xy 1.778 1.8796)
			)
			(stroke
				(width 0)
				(type default)
			)
			(fill no)
			(layer "F.CrtYd")
		)
		(fp_poly
			(pts
				(xy -1.778 1.8796) (xy -1.778 -1.8796) (xy 1.778 -1.8796) (xy 1.778 1.8796)
			)
			(stroke
				(width 0)
				(type default)
			)
			(fill no)
			(layer "F.Fab")
		)
		(pad "D" smd custom
			(at 0 -0.9525)
			(size 0.1905 0.1905)
			(layers "F.Cu" "F.Mask" "F.Paste")
			(net "IOM_STBY_PGOOD")
			(options
				(clearance outline)
				(anchor circle)
			)
			(primitives
				(gr_poly
					(pts
						(arc
							(start -0.1778 0.5715)
							(mid -0.321484 0.511984)
							(end -0.381 0.3683)
						)
						(arc
							(start -0.381 -0.3683)
							(mid -0.321484 -0.511984)
							(end -0.1778 -0.5715)
						)
						(arc
							(start 0.1778 -0.5715)
							(mid 0.321484 -0.511984)
							(end 0.381 -0.3683)
						)
						(arc
							(start 0.381 0.3683)
							(mid 0.321484 0.511984)
							(end 0.1778 0.5715)
						)
					)
					(width 0)
					(fill yes)
				)
			)
		)
		(pad "G" smd custom
			(at -0.98425 0.9525)
			(size 0.1905 0.1905)
			(layers "F.Cu" "F.Mask" "F.Paste")
			(net "P1V15_STBY_PG_G")
			(options
				(clearance outline)
				(anchor circle)
			)
			(primitives
				(gr_poly
					(pts
						(arc
							(start -0.1778 0.5715)
							(mid -0.321484 0.511984)
							(end -0.381 0.3683)
						)
						(arc
							(start -0.381 -0.3683)
							(mid -0.321484 -0.511984)
							(end -0.1778 -0.5715)
						)
						(arc
							(start 0.1778 -0.5715)
							(mid 0.321484 -0.511984)
							(end 0.381 -0.3683)
						)
						(arc
							(start 0.381 0.3683)
							(mid 0.321484 0.511984)
							(end 0.1778 0.5715)
						)
					)
					(width 0)
					(fill yes)
				)
			)
		)
		(pad "S" smd custom
			(at 0.98425 0.9525)
			(size 0.1905 0.1905)
			(layers "F.Cu" "F.Mask" "F.Paste")
			(net "GND")
			(options
				(clearance outline)
				(anchor circle)
			)
			(primitives
				(gr_poly
					(pts
						(arc
							(start -0.1778 0.5715)
							(mid -0.321484 0.511984)
							(end -0.381 0.3683)
						)
						(arc
							(start -0.381 -0.3683)
							(mid -0.321484 -0.511984)
							(end -0.1778 -0.5715)
						)
						(arc
							(start 0.1778 -0.5715)
							(mid 0.321484 -0.511984)
							(end 0.381 -0.3683)
						)
						(arc
							(start 0.381 0.3683)
							(mid 0.321484 0.511984)
							(end 0.1778 0.5715)
						)
					)
					(width 0)
					(fill yes)
				)
			)
		)
	)
	(footprint ""
		(layer "F.Cu")
		(at 48.101504 -161.180272 180)
		(property "Reference" "R204"
			(at 0 0 180)
			(layer "F.SilkS")
			(hide yes)
			(effects
				(font
					(size 1.27 1.27)
				)
			)
		)
		(property "Value" "2K2R2F-GP"
			(at 0.064008 -3.993896 180)
			(unlocked yes)
			(layer "F.Fab")
			(hide yes)
			(effects
				(font
					(size 1.016 1.016)
					(thickness 0.1524)
				)
			)
		)
		(property "Device Type" "R402H16"
			(at 0.064008 -5.517896 180)
			(unlocked yes)
			(layer "F.Fab")
			(hide yes)
			(effects
				(font
					(size 1.016 1.016)
					(thickness 0.1524)
				)
			)
		)
		(duplicate_pad_numbers_are_jumpers no)
		(fp_line
			(start 0.508 -0.9398)
			(end -0.508 -0.9398)
			(stroke
				(width 0.1524)
				(type default)
			)
			(layer "F.SilkS")
		)
		(fp_line
			(start -0.508 -0.9398)
			(end -0.508 0.9398)
			(stroke
				(width 0.1524)
				(type default)
			)
			(layer "F.SilkS")
		)
		(fp_rect
			(start -0.508 0.9398)
			(end 0.508 -0.9398)
			(stroke
				(width 0)
				(type default)
			)
			(fill no)
			(layer "F.CrtYd")
		)
		(fp_rect
			(start -0.508 0.9398)
			(end 0.508 -0.9398)
			(stroke
				(width 0)
				(type default)
			)
			(fill no)
			(layer "F.Fab")
		)
		(pad "1" smd custom
			(at 0 -0.4445 180)
			(size 0.1397 0.1397)
			(layers "F.Cu" "F.Mask" "F.Paste")
			(net "I2C_DPB_MISC_SDA_OUT")
			(options
				(clearance outline)
				(anchor circle)
			)
			(primitives
				(gr_poly
					(pts
						(arc
							(start -0.1778 -0.2794)
							(mid -0.249642 -0.249642)
							(end -0.2794 -0.1778)
						)
						(arc
							(start -0.2794 0.1778)
							(mid -0.249642 0.249642)
							(end -0.1778 0.2794)
						)
						(arc
							(start 0.1778 0.2794)
							(mid 0.249642 0.249642)
							(end 0.2794 0.1778)
						)
						(arc
							(start 0.2794 -0.1778)
							(mid 0.249642 -0.249642)
							(end 0.1778 -0.2794)
						)
					)
					(width 0)
					(fill yes)
				)
			)
		)
		(pad "2" smd custom
			(at 0 0.4445 180)
			(size 0.1397 0.1397)
			(layers "F.Cu" "F.Mask" "F.Paste")
			(net "P3V3_STBY")
			(options
				(clearance outline)
				(anchor circle)
			)
			(primitives
				(gr_poly
					(pts
						(arc
							(start -0.1778 -0.2794)
							(mid -0.249642 -0.249642)
							(end -0.2794 -0.1778)
						)
						(arc
							(start -0.2794 0.1778)
							(mid -0.249642 0.249642)
							(end -0.1778 0.2794)
						)
						(arc
							(start 0.1778 0.2794)
							(mid 0.249642 0.249642)
							(end 0.2794 0.1778)
						)
						(arc
							(start 0.2794 -0.1778)
							(mid 0.249642 -0.249642)
							(end 0.1778 -0.2794)
						)
					)
					(width 0)
					(fill yes)
				)
			)
		)
	)
	(footprint ""
		(layer "F.Cu")
		(at 222.50019 -14.99997)
		(property "Reference" ""
			(at 0 0 0)
			(layer "F.SilkS")
			(hide yes)
			(effects
				(font
					(size 1.27 1.27)
				)
			)
		)
		(property "Value" "*"
			(at 6.2484 0.3429 0)
			(unlocked yes)
			(layer "F.Fab")
			(hide yes)
			(effects
				(font
					(size 1.016 1.016)
					(thickness 0.1524)
				)
			)
		)
		(duplicate_pad_numbers_are_jumpers no)
		(fp_poly
			(pts
				(arc
					(start 5.0673 0)
					(mid -5.0673 0)
					(end 5.0673 0)
				)
			)
			(stroke
				(width 0)
				(type default)
			)
			(fill no)
			(layer "B.CrtYd")
		)
		(fp_poly
			(pts
				(arc
					(start 5.0673 0)
					(mid -5.0673 0)
					(end 5.0673 0)
				)
			)
			(stroke
				(width 0)
				(type default)
			)
			(fill no)
			(layer "F.CrtYd")
		)
		(fp_poly
			(pts
				(arc
					(start 5.0673 0)
					(mid -5.0673 0)
					(end 5.0673 0)
				)
			)
			(stroke
				(width 0)
				(type default)
			)
			(fill no)
			(layer "B.Fab")
		)
		(fp_poly
			(pts
				(arc
					(start 5.0673 0)
					(mid -5.0673 0)
					(end 5.0673 0)
				)
			)
			(stroke
				(width 0)
				(type default)
			)
			(fill no)
			(layer "F.Fab")
		)
		(pad "1" thru_hole circle
			(at 0 0)
			(size 9.525 9.525)
			(drill 4.0132)
			(layers "*.Cu" "*.Mask")
			(remove_unused_layers no)
			(net "Net_71")
			(clearance -2.2479)
			(thermal_gap 0.3048)
			(padstack
				(mode front_inner_back)
				(layer "Inner"
					(shape circle)
					(size 4.4196 4.4196)
					(clearance 0.3048)
				)
				(layer "B.Cu"
					(shape circle)
					(size 9.525 9.525)
					(clearance -2.2479)
				)
			)
		)
	)
	(footprint ""
		(layer "F.Cu")
		(at 175.5648 -77.8002 180)
		(property "Reference" "TP133"
			(at 0 0 180)
			(layer "F.SilkS")
			(hide yes)
			(effects
				(font
					(size 1.27 1.27)
				)
			)
		)
		(property "Value" "TPAD28-2-GP"
			(at -0.0127 -1.6637 180)
			(unlocked yes)
			(layer "F.Fab")
			(hide yes)
			(effects
				(font
					(size 1.016 1.016)
					(thickness 0.1524)
				)
			)
		)
		(property "Device Type" "TPAD28"
			(at -0.0127 -3.1877 180)
			(unlocked yes)
			(layer "F.Fab")
			(hide yes)
			(effects
				(font
					(size 1.016 1.016)
					(thickness 0.1524)
				)
			)
		)
		(duplicate_pad_numbers_are_jumpers no)
		(fp_poly
			(pts
				(arc
					(start -0.3556 0)
					(mid 0.3556 0)
					(end -0.3556 0)
				)
			)
			(stroke
				(width 0)
				(type default)
			)
			(fill no)
			(layer "F.CrtYd")
		)
		(fp_poly
			(pts
				(arc
					(start -0.6096 0)
					(mid 0.6096 0)
					(end -0.6096 0)
				)
			)
			(stroke
				(width 0)
				(type default)
			)
			(fill no)
			(layer "F.Fab")
		)
		(pad "1" smd circle
			(at 0 0 180)
			(size 0.7112 0.7112)
			(layers "F.Cu" "F.Mask" "F.Paste")
			(net "UART_SERCLK")
		)
	)
	(footprint ""
		(layer "F.Cu")
		(at 156.474668 -90.021664)
		(property "Reference" "U44"
			(at 0 0 0)
			(layer "F.SilkS")
			(hide yes)
			(effects
				(font
					(size 1.27 1.27)
				)
			)
		)
		(property "Value" "TXS0102DCUR-1-GP"
			(at 0 -11.1252 0)
			(unlocked yes)
			(layer "F.Fab")
			(hide yes)
			(effects
				(font
					(size 1.016 1.016)
					(thickness 0.1524)
				)
			)
		)
		(property "Device Type" "SSOIC8-4H36"
			(at 0 -12.6492 0)
			(unlocked yes)
			(layer "F.Fab")
			(hide yes)
			(effects
				(font
					(size 1.016 1.016)
					(thickness 0.1524)
				)
			)
		)
		(duplicate_pad_numbers_are_jumpers no)
		(fp_line
			(start -1.2954 0.4572)
			(end -1.2954 2.159)
			(stroke
				(width 0.4064)
				(type default)
			)
			(layer "F.SilkS")
		)
		(fp_line
			(start -1.2573 -2.1844)
			(end 1.2573 -2.1844)
			(stroke
				(width 0.1524)
				(type default)
			)
			(layer "F.SilkS")
		)
		(fp_line
			(start -1.2573 -0.3556)
			(end -1.2192 -0.3556)
			(stroke
				(width 0.1524)
				(type default)
			)
			(layer "F.SilkS")
		)
		(fp_line
			(start -1.2573 2.1844)
			(end -1.2573 -2.1844)
			(stroke
				(width 0.1524)
				(type default)
			)
			(layer "F.SilkS")
		)
		(fp_line
			(start -1.2192 -0.3556)
			(end -0.9017 -0.0381)
			(stroke
				(width 0.1524)
				(type default)
			)
			(layer "F.SilkS")
		)
		(fp_line
			(start -1.2065 0.2667)
			(end -1.27 0.2667)
			(stroke
				(width 0.1524)
				(type default)
			)
			(layer "F.SilkS")
		)
		(fp_line
			(start -0.9017 -0.0381)
			(end -1.2065 0.2667)
			(stroke
				(width 0.1524)
				(type default)
			)
			(layer "F.SilkS")
		)
		(fp_line
			(start 1.2573 -2.1844)
			(end 1.2573 2.1844)
			(stroke
				(width 0.1524)
				(type default)
			)
			(layer "F.SilkS")
		)
		(fp_line
			(start 1.2573 2.1844)
			(end -1.2573 2.1844)
			(stroke
				(width 0.1524)
				(type default)
			)
			(layer "F.SilkS")
		)
		(fp_poly
			(pts
				(xy -1.5113 2.4384) (xy 1.5113 2.4384) (xy 1.5113 -2.4384) (xy -1.5113 -2.4384)
			)
			(stroke
				(width 0)
				(type default)
			)
			(fill no)
			(layer "F.CrtYd")
		)
		(fp_poly
			(pts
				(xy -1.5113 -2.4384) (xy 1.5113 -2.4384) (xy 1.5113 2.4384) (xy -1.5113 2.4384)
			)
			(stroke
				(width 0)
				(type default)
			)
			(fill no)
			(layer "F.Fab")
		)
		(pad "1" smd rect
			(at -0.75057 1.1684)
			(size 0.3048 1.524)
			(layers "F.Cu" "F.Mask" "F.Paste")
			(net "IOC_UART_R_RX")
		)
		(pad "2" smd rect
			(at -0.25019 1.1684)
			(size 0.3048 1.524)
			(layers "F.Cu" "F.Mask" "F.Paste")
			(net "GND")
		)
		(pad "3" smd rect
			(at 0.25019 1.1684)
			(size 0.3048 1.524)
			(layers "F.Cu" "F.Mask" "F.Paste")
			(net "P1V8")
		)
		(pad "4" smd rect
			(at 0.75057 1.1684)
			(size 0.3048 1.524)
			(layers "F.Cu" "F.Mask" "F.Paste")
			(net "IOC_UART_0_RX_R")
		)
		(pad "5" smd rect
			(at 0.75057 -1.1684)
			(size 0.3048 1.524)
			(layers "F.Cu" "F.Mask" "F.Paste")
			(net "IOC_UART_0_TX_R")
		)
		(pad "6" smd rect
			(at 0.25019 -1.1684)
			(size 0.3048 1.524)
			(layers "F.Cu" "F.Mask" "F.Paste")
			(net "SYS_RST_N_0")
		)
		(pad "7" smd rect
			(at -0.25019 -1.1684)
			(size 0.3048 1.524)
			(layers "F.Cu" "F.Mask" "F.Paste")
			(net "P3V3")
		)
		(pad "8" smd rect
			(at -0.75057 -1.1684)
			(size 0.3048 1.524)
			(layers "F.Cu" "F.Mask" "F.Paste")
			(net "IOC_UART_R_TX")
		)
	)
	(footprint ""
		(layer "F.Cu")
		(at 59.8424 -155.3972)
		(property "Reference" "TP50"
			(at 0 0 0)
			(layer "F.SilkS")
			(hide yes)
			(effects
				(font
					(size 1.27 1.27)
				)
			)
		)
		(property "Value" "TPAD28-2-GP"
			(at -0.0127 -1.6637 0)
			(unlocked yes)
			(layer "F.Fab")
			(hide yes)
			(effects
				(font
					(size 1.016 1.016)
					(thickness 0.1524)
				)
			)
		)
		(property "Device Type" "TPAD28"
			(at -0.0127 -3.1877 0)
			(unlocked yes)
			(layer "F.Fab")
			(hide yes)
			(effects
				(font
					(size 1.016 1.016)
					(thickness 0.1524)
				)
			)
		)
		(duplicate_pad_numbers_are_jumpers no)
		(fp_poly
			(pts
				(arc
					(start 0.3556 0)
					(mid -0.3556 0)
					(end 0.3556 0)
				)
			)
			(stroke
				(width 0)
				(type default)
			)
			(fill no)
			(layer "F.CrtYd")
		)
		(fp_poly
			(pts
				(arc
					(start 0.6096 0)
					(mid -0.6096 0)
					(end 0.6096 0)
				)
			)
			(stroke
				(width 0)
				(type default)
			)
			(fill no)
			(layer "F.Fab")
		)
		(pad "1" smd circle
			(at 0 0)
			(size 0.7112 0.7112)
			(layers "F.Cu" "F.Mask" "F.Paste")
			(net "TP_BMC_GPIOT0")
		)
	)
	(footprint ""
		(layer "F.Cu")
		(at 54.280054 -172.699934)
		(property "Reference" "TPM1"
			(at 0 0 0)
			(layer "F.SilkS")
			(hide yes)
			(effects
				(font
					(size 1.27 1.27)
				)
			)
		)
		(property "Value" "FCI-CONN11-2-GP"
			(at -7.4803 1.3589 0)
			(unlocked yes)
			(layer "F.Fab")
			(hide yes)
			(effects
				(font
					(size 1.016 1.016)
					(thickness 0.1524)
				)
			)
		)
		(property "Device Type" "91932-31111LF"
			(at -7.4803 -0.1651 0)
			(unlocked yes)
			(layer "F.Fab")
			(hide yes)
			(effects
				(font
					(size 1.016 1.016)
					(thickness 0.1524)
				)
			)
		)
		(duplicate_pad_numbers_are_jumpers no)
		(fp_line
			(start -5.4102 -3.556)
			(end -5.4102 3.556)
			(stroke
				(width 0.1524)
				(type default)
			)
			(layer "F.SilkS")
		)
		(fp_line
			(start -5.4102 3.556)
			(end 5.4102 3.556)
			(stroke
				(width 0.1524)
				(type default)
			)
			(layer "F.SilkS")
		)
		(fp_line
			(start -2.8321 3.6449)
			(end -2.2479 3.6449)
			(stroke
				(width 0.3302)
				(type default)
			)
			(layer "F.SilkS")
		)
		(fp_line
			(start 5.4102 -3.556)
			(end -5.4102 -3.556)
			(stroke
				(width 0.1524)
				(type default)
			)
			(layer "F.SilkS")
		)
		(fp_line
			(start 5.4102 3.556)
			(end 5.4102 -3.556)
			(stroke
				(width 0.1524)
				(type default)
			)
			(layer "F.SilkS")
		)
		(fp_poly
			(pts
				(xy -2.546096 3.612642) (xy -3.181096 4.247642) (xy -1.911096 4.247642)
			)
			(stroke
				(width 0)
				(type default)
			)
			(fill yes)
			(layer "F.SilkS")
		)
		(fp_poly
			(pts
				(xy -2.8067 1.08839)
				(arc
					(start -2.8067 -0.422402)
					(mid -2.451868 -0.675672)
					(end -2.3114 -1.08839)
				)
				(arc
					(start 2.3114 -1.08839)
					(mid 2.451818 -0.675634)
					(end 2.8067 -0.422402)
				)
				(xy 2.8067 1.08839)
			)
			(stroke
				(width 0)
				(type default)
			)
			(fill yes)
			(layer "F.SilkS")
		)
		(fp_rect
			(start -5.1562 2.794)
			(end 5.1562 -2.794)
			(stroke
				(width 0)
				(type default)
			)
			(fill no)
			(layer "F.CrtYd")
		)
		(fp_poly
			(pts
				(xy 5.6642 -2.794) (xy -5.1562 -2.794) (xy -5.1562 2.794) (xy 5.1562 2.794) (xy 5.1562 -2.7813)
				(xy 5.6642 -2.7813) (xy 5.6642 3.81) (xy -5.6642 3.81) (xy -5.6642 -3.81) (xy 5.6642 -3.81)
			)
			(stroke
				(width 0)
				(type default)
			)
			(fill no)
			(layer "F.CrtYd")
		)
		(fp_rect
			(start -5.6642 3.81)
			(end 5.6642 -3.81)
			(stroke
				(width 0)
				(type default)
			)
			(fill no)
			(layer "F.Fab")
		)
		(pad "" np_thru_hole circle
			(at -3.0226 -1.100074)
			(size 0.254 0.254)
			(drill 0.8128)
			(layers "*.Cu" "*.Mask")
			(clearance 0.635)
			(thermal_gap 0.635)
		)
		(pad "" np_thru_hole circle
			(at 3.0226 -1.100074)
			(size 0.254 0.254)
			(drill 0.8128)
			(layers "*.Cu" "*.Mask")
			(clearance 0.635)
			(thermal_gap 0.635)
		)
		(pad "1" smd rect
			(at -2.500122 2.29489)
			(size 0.6096 2.0066)
			(layers "F.Cu" "F.Mask" "F.Paste")
			(net "Net_358")
		)
		(pad "2" smd rect
			(at -1.500124 2.29489)
			(size 0.6096 2.0066)
			(layers "F.Cu" "F.Mask" "F.Paste")
			(net "Net_357")
		)
		(pad "3" smd rect
			(at -0.500126 2.29489)
			(size 0.6096 2.0066)
			(layers "F.Cu" "F.Mask" "F.Paste")
			(net "Net_356")
		)
		(pad "4" smd rect
			(at 0.500126 2.29489)
			(size 0.6096 2.0066)
			(layers "F.Cu" "F.Mask" "F.Paste")
			(net "Net_355")
		)
		(pad "5" smd rect
			(at 1.500124 2.29489)
			(size 0.6096 2.0066)
			(layers "F.Cu" "F.Mask" "F.Paste")
			(net "Net_354")
		)
		(pad "6" smd rect
			(at 2.500122 2.29489)
			(size 0.6096 2.0066)
			(layers "F.Cu" "F.Mask" "F.Paste")
			(net "I2C_TPM_SDA")
		)
		(pad "7" smd rect
			(at -1.999996 -2.29489)
			(size 0.6096 2.0066)
			(layers "F.Cu" "F.Mask" "F.Paste")
			(net "P3V3_STBY")
		)
		(pad "8" smd rect
			(at -0.999998 -2.29489)
			(size 0.6096 2.0066)
			(layers "F.Cu" "F.Mask" "F.Paste")
			(net "FM_TPM_PRSNT_RST_N")
		)
		(pad "9" smd rect
			(at 0 -2.29489)
			(size 0.6096 2.0066)
			(layers "F.Cu" "F.Mask" "F.Paste")
			(net "Net_359")
		)
		(pad "10" smd rect
			(at 0.999998 -2.29489)
			(size 0.6096 2.0066)
			(layers "F.Cu" "F.Mask" "F.Paste")
			(net "I2C_TPM_SCL")
		)
		(pad "11" smd rect
			(at 1.999996 -2.29489)
			(size 0.6096 2.0066)
			(layers "F.Cu" "F.Mask" "F.Paste")
			(net "GND")
		)
		(pad "G1" smd custom
			(at -4.219956 0)
			(size 0.34925 0.34925)
			(layers "F.Cu" "F.Mask" "F.Paste")
			(net "GND")
			(options
				(clearance outline)
				(anchor circle)
			)
			(primitives
				(gr_poly
					(pts
						(xy -0.6985 2.921) (xy -0.6985 -2.921) (xy 0.6985 -2.921)
						(arc
							(start 0.6985 -1.610106)
							(mid 0.482924 -1.100074)
							(end 0.6985 -0.590042)
						)
						(xy 0.6985 2.921)
					)
					(width 0)
					(fill yes)
				)
			)
		)
		(pad "G2" smd custom
			(at 4.219956 0)
			(size 0.34925 0.34925)
			(layers "F.Cu" "F.Mask" "F.Paste")
			(net "GND")
			(options
				(clearance outline)
				(anchor circle)
			)
			(primitives
				(gr_poly
					(pts
						(xy -0.6985 2.921)
						(arc
							(start -0.6985 -0.590042)
							(mid -0.482924 -1.100074)
							(end -0.6985 -1.610106)
						)
						(xy -0.6985 -2.921) (xy 0.6985 -2.921) (xy 0.6985 2.921)
					)
					(width 0)
					(fill yes)
				)
			)
		)
		(zone
			(layer "F.Cu")
			(hatch none 0.5)
			(connect_pads
				(clearance 0)
			)
			(min_thickness 0.25)
			(keepout
				(tracks not_allowed)
				(vias allowed)
				(pads allowed)
				(copperpour not_allowed)
				(footprints allowed)
			)
			(placement
				(enabled no)
				(sheetname "")
			)
			(fill
				(thermal_gap 0.5)
				(thermal_bridge_width 0.5)
				(island_removal_mode 0)
			)
			(polygon
				(pts
					(xy 51.473354 -171.408344) (xy 57.086754 -171.408344) (xy 57.086754 -173.991524) (xy 51.473354 -173.991524)
				)
			)
		)
		(zone
			(layer "F.Cu")
			(hatch none 0.5)
			(connect_pads
				(clearance 0)
			)
			(min_thickness 0.25)
			(keepout
				(tracks allowed)
				(vias not_allowed)
				(pads allowed)
				(copperpour not_allowed)
				(footprints allowed)
			)
			(placement
				(enabled no)
				(sheetname "")
			)
			(fill
				(thermal_gap 0.5)
				(thermal_bridge_width 0.5)
				(island_removal_mode 0)
			)
			(polygon
				(pts
					(xy 51.473354 -171.408344) (xy 57.086754 -171.408344) (xy 57.086754 -173.991524) (xy 51.473354 -173.991524)
				)
			)
		)
		(zone
			(layer "F.Cu")
			(hatch none 0.5)
			(connect_pads
				(clearance 0)
			)
			(min_thickness 0.25)
			(keepout
				(tracks allowed)
				(vias not_allowed)
				(pads allowed)
				(copperpour not_allowed)
				(footprints allowed)
			)
			(placement
				(enabled no)
				(sheetname "")
			)
			(fill
				(thermal_gap 0.5)
				(thermal_bridge_width 0.5)
				(island_removal_mode 0)
			)
			(polygon
				(pts
					(xy 51.473354 -171.408344) (xy 57.086754 -171.408344) (xy 57.086754 -171.916344) (xy 51.473354 -171.916344)
				)
			)
		)
		(zone
			(layer "F.Cu")
			(hatch none 0.5)
			(connect_pads
				(clearance 0)
			)
			(min_thickness 0.25)
			(keepout
				(tracks allowed)
				(vias not_allowed)
				(pads allowed)
				(copperpour not_allowed)
				(footprints allowed)
			)
			(placement
				(enabled no)
				(sheetname "")
			)
			(fill
				(thermal_gap 0.5)
				(thermal_bridge_width 0.5)
				(island_removal_mode 0)
			)
			(polygon
				(pts
					(xy 51.968654 -173.483524) (xy 56.591454 -173.483524) (xy 56.591454 -173.991524) (xy 51.968654 -173.991524)
				)
			)
		)
		(zone
			(layers "F.Cu" "B.Cu" "In1.Cu" "In2.Cu" "In3.Cu" "In4.Cu" "In5.Cu" "In6.Cu")
			(hatch none 0.5)
			(connect_pads
				(clearance 0)
			)
			(min_thickness 0.25)
			(keepout
				(tracks not_allowed)
				(vias allowed)
				(pads allowed)
				(copperpour not_allowed)
				(footprints allowed)
			)
			(placement
				(enabled no)
				(sheetname "")
			)
			(fill
				(thermal_gap 0.5)
				(thermal_bridge_width 0.5)
				(island_removal_mode 0)
			)
			(polygon
				(pts
					(arc
						(start 51.968654 -173.800008)
						(mid 50.546254 -173.800008)
						(end 51.968654 -173.800008)
					)
				)
			)
		)
		(zone
			(layers "F.Cu" "B.Cu" "In1.Cu" "In2.Cu" "In3.Cu" "In4.Cu" "In5.Cu" "In6.Cu")
			(hatch none 0.5)
			(connect_pads
				(clearance 0)
			)
			(min_thickness 0.25)
			(keepout
				(tracks not_allowed)
				(vias allowed)
				(pads allowed)
				(copperpour not_allowed)
				(footprints allowed)
			)
			(placement
				(enabled no)
				(sheetname "")
			)
			(fill
				(thermal_gap 0.5)
				(thermal_bridge_width 0.5)
				(island_removal_mode 0)
			)
			(polygon
				(pts
					(arc
						(start 58.013854 -173.800008)
						(mid 56.591454 -173.800008)
						(end 58.013854 -173.800008)
					)
				)
			)
		)
	)
	(footprint ""
		(layer "F.Cu")
		(at 213.221316 -122.3391 90)
		(property "Reference" "C250"
			(at 0 0 90)
			(layer "F.SilkS")
			(hide yes)
			(effects
				(font
					(size 1.27 1.27)
				)
			)
		)
		(property "Value" "SC10U6D3V5KX-4GP"
			(at -0.0762 -6.1214 90)
			(unlocked yes)
			(layer "F.Fab")
			(hide yes)
			(effects
				(font
					(size 1.016 1.016)
					(thickness 0.1524)
				)
			)
		)
		(property "Device Type" "C805H58"
			(at -0.0762 -8.1534 90)
			(unlocked yes)
			(layer "F.Fab")
			(hide yes)
			(effects
				(font
					(size 1.016 1.016)
					(thickness 0.1524)
				)
			)
		)
		(duplicate_pad_numbers_are_jumpers no)
		(fp_line
			(start 0.635 0)
			(end -0.635 0)
			(stroke
				(width 0.508)
				(type default)
			)
			(layer "F.SilkS")
		)
		(fp_rect
			(start -0.9652 1.778)
			(end 0.9652 -1.778)
			(stroke
				(width 0)
				(type default)
			)
			(fill no)
			(layer "F.CrtYd")
		)
		(fp_poly
			(pts
				(xy -0.9652 -1.778) (xy 0.9652 -1.778) (xy 0.9652 1.778) (xy -0.9652 1.778)
			)
			(stroke
				(width 0)
				(type default)
			)
			(fill no)
			(layer "F.Fab")
		)
		(pad "1" smd rect
			(at 0 -0.9652 90)
			(size 1.397 1.143)
			(layers "F.Cu" "F.Mask" "F.Paste")
			(net "P1V5_OUT")
		)
		(pad "2" smd rect
			(at 0 0.9652 90)
			(size 1.397 1.143)
			(layers "F.Cu" "F.Mask" "F.Paste")
			(net "GND")
		)
	)
	(footprint ""
		(layer "F.Cu")
		(at 172.942504 -140.215366 -90)
		(property "Reference" "C153"
			(at 0 0 270)
			(layer "F.SilkS")
			(hide yes)
			(effects
				(font
					(size 1.27 1.27)
				)
			)
		)
		(property "Value" "SC10U16V5KX-7-GP-U"
			(at -0.0762 -6.1214 270)
			(unlocked yes)
			(layer "F.Fab")
			(hide yes)
			(effects
				(font
					(size 1.016 1.016)
					(thickness 0.1524)
				)
			)
		)
		(property "Device Type" "C805H58"
			(at -0.0762 -8.1534 270)
			(unlocked yes)
			(layer "F.Fab")
			(hide yes)
			(effects
				(font
					(size 1.016 1.016)
					(thickness 0.1524)
				)
			)
		)
		(duplicate_pad_numbers_are_jumpers no)
		(fp_line
			(start 0.635 0)
			(end -0.635 0)
			(stroke
				(width 0.508)
				(type default)
			)
			(layer "F.SilkS")
		)
		(fp_rect
			(start -0.9652 1.778)
			(end 0.9652 -1.778)
			(stroke
				(width 0)
				(type default)
			)
			(fill no)
			(layer "F.CrtYd")
		)
		(fp_poly
			(pts
				(xy -0.9652 -1.778) (xy 0.9652 -1.778) (xy 0.9652 1.778) (xy -0.9652 1.778)
			)
			(stroke
				(width 0)
				(type default)
			)
			(fill no)
			(layer "F.Fab")
		)
		(pad "1" smd rect
			(at 0 -0.9652 270)
			(size 1.397 1.143)
			(layers "F.Cu" "F.Mask" "F.Paste")
			(net "P12V_STBY_VIN_PU1")
		)
		(pad "2" smd rect
			(at 0 0.9652 270)
			(size 1.397 1.143)
			(layers "F.Cu" "F.Mask" "F.Paste")
			(net "GND")
		)
	)
	(footprint ""
		(layer "F.Cu")
		(at 176.9364 -63.3476 -90)
		(property "Reference" "R574"
			(at 0 0 270)
			(layer "F.SilkS")
			(hide yes)
			(effects
				(font
					(size 1.27 1.27)
				)
			)
		)
		(property "Value" "10KR2F-2-GP"
			(at 0.064008 -3.993896 270)
			(unlocked yes)
			(layer "F.Fab")
			(hide yes)
			(effects
				(font
					(size 1.016 1.016)
					(thickness 0.1524)
				)
			)
		)
		(property "Device Type" "R402H16"
			(at 0.064008 -5.517896 270)
			(unlocked yes)
			(layer "F.Fab")
			(hide yes)
			(effects
				(font
					(size 1.016 1.016)
					(thickness 0.1524)
				)
			)
		)
		(duplicate_pad_numbers_are_jumpers no)
		(fp_line
			(start -0.508 -0.9398)
			(end -0.508 0.9398)
			(stroke
				(width 0.1524)
				(type default)
			)
			(layer "F.SilkS")
		)
		(fp_line
			(start 0.508 -0.9398)
			(end -0.508 -0.9398)
			(stroke
				(width 0.1524)
				(type default)
			)
			(layer "F.SilkS")
		)
		(fp_rect
			(start -0.508 0.9398)
			(end 0.508 -0.9398)
			(stroke
				(width 0)
				(type default)
			)
			(fill no)
			(layer "F.CrtYd")
		)
		(fp_rect
			(start -0.508 0.9398)
			(end 0.508 -0.9398)
			(stroke
				(width 0)
				(type default)
			)
			(fill no)
			(layer "F.Fab")
		)
		(pad "1" smd custom
			(at 0 -0.4445 270)
			(size 0.1397 0.1397)
			(layers "F.Cu" "F.Mask" "F.Paste")
			(net "GND")
			(options
				(clearance outline)
				(anchor circle)
			)
			(primitives
				(gr_poly
					(pts
						(arc
							(start -0.1778 -0.2794)
							(mid -0.249642 -0.249642)
							(end -0.2794 -0.1778)
						)
						(arc
							(start -0.2794 0.1778)
							(mid -0.249642 0.249642)
							(end -0.1778 0.2794)
						)
						(arc
							(start 0.1778 0.2794)
							(mid 0.249642 0.249642)
							(end 0.2794 0.1778)
						)
						(arc
							(start 0.2794 -0.1778)
							(mid 0.249642 -0.249642)
							(end 0.1778 -0.2794)
						)
					)
					(width 0)
					(fill yes)
				)
			)
		)
		(pad "2" smd custom
			(at 0 0.4445 270)
			(size 0.1397 0.1397)
			(layers "F.Cu" "F.Mask" "F.Paste")
			(net "IOC_CLK_SEL0")
			(options
				(clearance outline)
				(anchor circle)
			)
			(primitives
				(gr_poly
					(pts
						(arc
							(start -0.1778 -0.2794)
							(mid -0.249642 -0.249642)
							(end -0.2794 -0.1778)
						)
						(arc
							(start -0.2794 0.1778)
							(mid -0.249642 0.249642)
							(end -0.1778 0.2794)
						)
						(arc
							(start 0.1778 0.2794)
							(mid 0.249642 0.249642)
							(end 0.2794 0.1778)
						)
						(arc
							(start 0.2794 -0.1778)
							(mid 0.249642 -0.249642)
							(end 0.1778 -0.2794)
						)
					)
					(width 0)
					(fill yes)
				)
			)
		)
	)
	(footprint ""
		(layer "F.Cu")
		(at 83.358228 -94.937072 90)
		(property "Reference" "VIA16"
			(at 0 0 90)
			(layer "F.SilkS")
			(hide yes)
			(effects
				(font
					(size 1.27 1.27)
				)
			)
		)
		(property "Value" "85OHM-8L-1D6MM-L16L18-GP"
			(at 4.064 0.6096 90)
			(unlocked yes)
			(layer "F.Fab")
			(hide yes)
			(effects
				(font
					(size 1.016 1.016)
					(thickness 0.1524)
				)
			)
		)
		(property "Device Type" "VIA-PCIE-4P-368076"
			(at 4.064 -0.9144 90)
			(unlocked yes)
			(layer "F.Fab")
			(hide yes)
			(effects
				(font
					(size 1.016 1.016)
					(thickness 0.1524)
				)
			)
		)
		(duplicate_pad_numbers_are_jumpers no)
		(fp_rect
			(start -1.8415 0.381)
			(end 1.8415 -0.381)
			(stroke
				(width 0)
				(type default)
			)
			(fill no)
			(layer "F.CrtYd")
		)
		(fp_rect
			(start -1.8415 0.381)
			(end 1.8415 -0.381)
			(stroke
				(width 0)
				(type default)
			)
			(fill no)
			(layer "F.Fab")
		)
		(pad "1" thru_hole circle
			(at -1.4605 0 90)
			(size 0.508 0.508)
			(drill 0.254)
			(layers "*.Cu" "*.Mask")
			(remove_unused_layers no)
			(net "GND")
			(clearance 0.127)
			(thermal_gap 0.127)
		)
		(pad "2" thru_hole circle
			(at -0.4445 0 90)
			(size 0.508 0.508)
			(drill 0.254)
			(layers "*.Cu" "*.Mask")
			(remove_unused_layers no)
			(net "PCIE_IOM_TO_COMP_23_DP")
			(clearance 0.127)
			(thermal_gap 0.127)
		)
		(pad "3" thru_hole circle
			(at 0.4445 0 90)
			(size 0.508 0.508)
			(drill 0.254)
			(layers "*.Cu" "*.Mask")
			(remove_unused_layers no)
			(net "PCIE_IOM_TO_COMP_23_DN")
			(clearance 0.127)
			(thermal_gap 0.127)
		)
		(pad "4" thru_hole circle
			(at 1.4605 0 90)
			(size 0.508 0.508)
			(drill 0.254)
			(layers "*.Cu" "*.Mask")
			(remove_unused_layers no)
			(net "GND")
			(clearance 0.127)
			(thermal_gap 0.127)
		)
	)
	(footprint ""
		(layer "F.Cu")
		(at 208.055972 -64.9732 90)
		(property "Reference" "C321"
			(at 0 0 90)
			(layer "F.SilkS")
			(hide yes)
			(effects
				(font
					(size 1.27 1.27)
				)
			)
		)
		(property "Value" "SCD01U16V1KX-GP"
			(at -2.8321 -1.7399 90)
			(unlocked yes)
			(layer "F.Fab")
			(hide yes)
			(effects
				(font
					(size 1.016 1.016)
					(thickness 0.1524)
				)
			)
		)
		(property "Device Type" "C0201H13"
			(at -2.8321 -3.2639 90)
			(unlocked yes)
			(layer "F.Fab")
			(hide yes)
			(effects
				(font
					(size 1.016 1.016)
					(thickness 0.1524)
				)
			)
		)
		(duplicate_pad_numbers_are_jumpers no)
		(fp_rect
			(start -0.2794 0.6477)
			(end 0.2794 -0.6477)
			(stroke
				(width 0)
				(type default)
			)
			(fill no)
			(layer "F.CrtYd")
		)
		(fp_rect
			(start -0.2794 0.6477)
			(end 0.2794 -0.6477)
			(stroke
				(width 0)
				(type default)
			)
			(fill no)
			(layer "F.Fab")
		)
		(pad "1" smd custom
			(at 0 -0.2794 90)
			(size 0.0762 0.0762)
			(layers "F.Cu" "F.Mask" "F.Paste")
			(net "PHY_IOC_TO_CON_B_3_DP_C")
			(options
				(clearance outline)
				(anchor circle)
			)
			(primitives
				(gr_poly
					(pts
						(arc
							(start 0.1524 -0.127)
							(mid 0.137521 -0.162921)
							(end 0.1016 -0.1778)
						)
						(arc
							(start -0.1016 -0.1778)
							(mid -0.137521 -0.162921)
							(end -0.1524 -0.127)
						)
						(arc
							(start -0.1524 0.127)
							(mid -0.137521 0.162921)
							(end -0.1016 0.1778)
						)
						(arc
							(start 0.1016 0.1778)
							(mid 0.137521 0.162921)
							(end 0.1524 0.127)
						)
					)
					(width 0)
					(fill yes)
				)
			)
		)
		(pad "2" smd custom
			(at 0 0.2794 90)
			(size 0.0762 0.0762)
			(layers "F.Cu" "F.Mask" "F.Paste")
			(net "PHY_IOC_TO_CON_B_3_DP")
			(options
				(clearance outline)
				(anchor circle)
			)
			(primitives
				(gr_poly
					(pts
						(arc
							(start 0.1524 -0.127)
							(mid 0.137521 -0.162921)
							(end 0.1016 -0.1778)
						)
						(arc
							(start -0.1016 -0.1778)
							(mid -0.137521 -0.162921)
							(end -0.1524 -0.127)
						)
						(arc
							(start -0.1524 0.127)
							(mid -0.137521 0.162921)
							(end -0.1016 0.1778)
						)
						(arc
							(start 0.1016 0.1778)
							(mid 0.137521 0.162921)
							(end 0.1524 0.127)
						)
					)
					(width 0)
					(fill yes)
				)
			)
		)
	)
	(footprint ""
		(layer "F.Cu")
		(at 10.269982 -172.706284 -90)
		(property "Reference" "R535"
			(at 0 0 270)
			(layer "F.SilkS")
			(hide yes)
			(effects
				(font
					(size 1.27 1.27)
				)
			)
		)
		(property "Value" "0R2J-2-GP"
			(at 0.064008 -3.993896 270)
			(unlocked yes)
			(layer "F.Fab")
			(hide yes)
			(effects
				(font
					(size 1.016 1.016)
					(thickness 0.1524)
				)
			)
		)
		(property "Device Type" "R402H16"
			(at 0.064008 -5.517896 270)
			(unlocked yes)
			(layer "F.Fab")
			(hide yes)
			(effects
				(font
					(size 1.016 1.016)
					(thickness 0.1524)
				)
			)
		)
		(duplicate_pad_numbers_are_jumpers no)
		(fp_line
			(start -0.508 -0.9398)
			(end -0.508 0.9398)
			(stroke
				(width 0.1524)
				(type default)
			)
			(layer "F.SilkS")
		)
		(fp_line
			(start 0.508 -0.9398)
			(end -0.508 -0.9398)
			(stroke
				(width 0.1524)
				(type default)
			)
			(layer "F.SilkS")
		)
		(fp_rect
			(start -0.508 0.9398)
			(end 0.508 -0.9398)
			(stroke
				(width 0)
				(type default)
			)
			(fill no)
			(layer "F.CrtYd")
		)
		(fp_rect
			(start -0.508 0.9398)
			(end 0.508 -0.9398)
			(stroke
				(width 0)
				(type default)
			)
			(fill no)
			(layer "F.Fab")
		)
		(pad "1" smd custom
			(at 0 -0.4445 270)
			(size 0.1397 0.1397)
			(layers "F.Cu" "F.Mask" "F.Paste")
			(net "TPS74801_P1V2_STBY_EN")
			(options
				(clearance outline)
				(anchor circle)
			)
			(primitives
				(gr_poly
					(pts
						(arc
							(start -0.1778 -0.2794)
							(mid -0.249642 -0.249642)
							(end -0.2794 -0.1778)
						)
						(arc
							(start -0.2794 0.1778)
							(mid -0.249642 0.249642)
							(end -0.1778 0.2794)
						)
						(arc
							(start 0.1778 0.2794)
							(mid 0.249642 0.249642)
							(end 0.2794 0.1778)
						)
						(arc
							(start 0.2794 -0.1778)
							(mid 0.249642 -0.249642)
							(end 0.1778 -0.2794)
						)
					)
					(width 0)
					(fill yes)
				)
			)
		)
		(pad "2" smd custom
			(at 0 0.4445 270)
			(size 0.1397 0.1397)
			(layers "F.Cu" "F.Mask" "F.Paste")
			(net "PWRGD_P1V8_STBY")
			(options
				(clearance outline)
				(anchor circle)
			)
			(primitives
				(gr_poly
					(pts
						(arc
							(start -0.1778 -0.2794)
							(mid -0.249642 -0.249642)
							(end -0.2794 -0.1778)
						)
						(arc
							(start -0.2794 0.1778)
							(mid -0.249642 0.249642)
							(end -0.1778 0.2794)
						)
						(arc
							(start 0.1778 0.2794)
							(mid 0.249642 0.249642)
							(end 0.2794 0.1778)
						)
						(arc
							(start 0.2794 -0.1778)
							(mid 0.249642 -0.249642)
							(end 0.1778 -0.2794)
						)
					)
					(width 0)
					(fill yes)
				)
			)
		)
	)
	(footprint ""
		(layer "F.Cu")
		(at 87.294212 -131.339844 90)
		(property "Reference" "R135"
			(at 0 0 90)
			(layer "F.SilkS")
			(hide yes)
			(effects
				(font
					(size 1.27 1.27)
				)
			)
		)
		(property "Value" "8K2R2J-3-GP"
			(at 0.064008 -3.993896 90)
			(unlocked yes)
			(layer "F.Fab")
			(hide yes)
			(effects
				(font
					(size 1.016 1.016)
					(thickness 0.1524)
				)
			)
		)
		(property "Device Type" "R402H16"
			(at 0.064008 -5.517896 90)
			(unlocked yes)
			(layer "F.Fab")
			(hide yes)
			(effects
				(font
					(size 1.016 1.016)
					(thickness 0.1524)
				)
			)
		)
		(duplicate_pad_numbers_are_jumpers no)
		(fp_line
			(start 0.508 -0.9398)
			(end -0.508 -0.9398)
			(stroke
				(width 0.1524)
				(type default)
			)
			(layer "F.SilkS")
		)
		(fp_line
			(start -0.508 -0.9398)
			(end -0.508 0.9398)
			(stroke
				(width 0.1524)
				(type default)
			)
			(layer "F.SilkS")
		)
		(fp_rect
			(start -0.508 0.9398)
			(end 0.508 -0.9398)
			(stroke
				(width 0)
				(type default)
			)
			(fill no)
			(layer "F.CrtYd")
		)
		(fp_rect
			(start -0.508 0.9398)
			(end 0.508 -0.9398)
			(stroke
				(width 0)
				(type default)
			)
			(fill no)
			(layer "F.Fab")
		)
		(pad "1" smd custom
			(at 0 -0.4445 90)
			(size 0.1397 0.1397)
			(layers "F.Cu" "F.Mask" "F.Paste")
			(net "P3V3_STBY")
			(options
				(clearance outline)
				(anchor circle)
			)
			(primitives
				(gr_poly
					(pts
						(arc
							(start -0.1778 -0.2794)
							(mid -0.249642 -0.249642)
							(end -0.2794 -0.1778)
						)
						(arc
							(start -0.2794 0.1778)
							(mid -0.249642 0.249642)
							(end -0.1778 0.2794)
						)
						(arc
							(start 0.1778 0.2794)
							(mid 0.249642 0.249642)
							(end 0.2794 0.1778)
						)
						(arc
							(start 0.2794 -0.1778)
							(mid 0.249642 -0.249642)
							(end 0.1778 -0.2794)
						)
					)
					(width 0)
					(fill yes)
				)
			)
		)
		(pad "2" smd custom
			(at 0 0.4445 90)
			(size 0.1397 0.1397)
			(layers "F.Cu" "F.Mask" "F.Paste")
			(net "EEPROM_A2")
			(options
				(clearance outline)
				(anchor circle)
			)
			(primitives
				(gr_poly
					(pts
						(arc
							(start -0.1778 -0.2794)
							(mid -0.249642 -0.249642)
							(end -0.2794 -0.1778)
						)
						(arc
							(start -0.2794 0.1778)
							(mid -0.249642 0.249642)
							(end -0.1778 0.2794)
						)
						(arc
							(start 0.1778 0.2794)
							(mid 0.249642 0.249642)
							(end 0.2794 0.1778)
						)
						(arc
							(start 0.2794 -0.1778)
							(mid 0.249642 -0.249642)
							(end 0.1778 -0.2794)
						)
					)
					(width 0)
					(fill yes)
				)
			)
		)
	)
	(footprint ""
		(layer "F.Cu")
		(at 35.7378 -165.5572)
		(property "Reference" "R707"
			(at 0 0 0)
			(layer "F.SilkS")
			(hide yes)
			(effects
				(font
					(size 1.27 1.27)
				)
			)
		)
		(property "Value" "4K7R2F-GP"
			(at 0.064008 -3.993896 0)
			(unlocked yes)
			(layer "F.Fab")
			(hide yes)
			(effects
				(font
					(size 1.016 1.016)
					(thickness 0.1524)
				)
			)
		)
		(property "Device Type" "R402H16"
			(at 0.064008 -5.517896 0)
			(unlocked yes)
			(layer "F.Fab")
			(hide yes)
			(effects
				(font
					(size 1.016 1.016)
					(thickness 0.1524)
				)
			)
		)
		(duplicate_pad_numbers_are_jumpers no)
		(fp_line
			(start -0.508 -0.9398)
			(end -0.508 0.9398)
			(stroke
				(width 0.1524)
				(type default)
			)
			(layer "F.SilkS")
		)
		(fp_line
			(start 0.508 -0.9398)
			(end -0.508 -0.9398)
			(stroke
				(width 0.1524)
				(type default)
			)
			(layer "F.SilkS")
		)
		(fp_rect
			(start -0.508 0.9398)
			(end 0.508 -0.9398)
			(stroke
				(width 0)
				(type default)
			)
			(fill no)
			(layer "F.CrtYd")
		)
		(fp_rect
			(start -0.508 0.9398)
			(end 0.508 -0.9398)
			(stroke
				(width 0)
				(type default)
			)
			(fill no)
			(layer "F.Fab")
		)
		(pad "1" smd custom
			(at 0 -0.4445)
			(size 0.1397 0.1397)
			(layers "F.Cu" "F.Mask" "F.Paste")
			(net "P3V3_STBY")
			(options
				(clearance outline)
				(anchor circle)
			)
			(primitives
				(gr_poly
					(pts
						(arc
							(start -0.1778 -0.2794)
							(mid -0.249642 -0.249642)
							(end -0.2794 -0.1778)
						)
						(arc
							(start -0.2794 0.1778)
							(mid -0.249642 0.249642)
							(end -0.1778 0.2794)
						)
						(arc
							(start 0.1778 0.2794)
							(mid 0.249642 0.249642)
							(end 0.2794 0.1778)
						)
						(arc
							(start 0.2794 -0.1778)
							(mid 0.249642 -0.249642)
							(end 0.1778 -0.2794)
						)
					)
					(width 0)
					(fill yes)
				)
			)
		)
		(pad "2" smd custom
			(at 0 0.4445)
			(size 0.1397 0.1397)
			(layers "F.Cu" "F.Mask" "F.Paste")
			(net "IOM_TYPE0")
			(options
				(clearance outline)
				(anchor circle)
			)
			(primitives
				(gr_poly
					(pts
						(arc
							(start -0.1778 -0.2794)
							(mid -0.249642 -0.249642)
							(end -0.2794 -0.1778)
						)
						(arc
							(start -0.2794 0.1778)
							(mid -0.249642 0.249642)
							(end -0.1778 0.2794)
						)
						(arc
							(start 0.1778 0.2794)
							(mid 0.249642 0.249642)
							(end 0.2794 0.1778)
						)
						(arc
							(start 0.2794 -0.1778)
							(mid 0.249642 -0.249642)
							(end 0.1778 -0.2794)
						)
					)
					(width 0)
					(fill yes)
				)
			)
		)
	)
	(footprint ""
		(layer "F.Cu")
		(at 91.639644 -162.52952 -90)
		(property "Reference" "C17"
			(at 0 0 270)
			(layer "F.SilkS")
			(hide yes)
			(effects
				(font
					(size 1.27 1.27)
				)
			)
		)
		(property "Value" "SC18P50V2JN-1-GP"
			(at 1.1811 -2.7051 270)
			(unlocked yes)
			(layer "F.Fab")
			(hide yes)
			(effects
				(font
					(size 1.016 1.016)
					(thickness 0.1524)
				)
			)
		)
		(property "Device Type" "C402H22"
			(at 1.1811 -4.2291 270)
			(unlocked yes)
			(layer "F.Fab")
			(hide yes)
			(effects
				(font
					(size 1.016 1.016)
					(thickness 0.1524)
				)
			)
		)
		(duplicate_pad_numbers_are_jumpers no)
		(fp_rect
			(start -0.4318 0.9525)
			(end 0.4318 -0.9525)
			(stroke
				(width 0)
				(type default)
			)
			(fill no)
			(layer "F.CrtYd")
		)
		(fp_rect
			(start -0.4318 0.9525)
			(end 0.4318 -0.9525)
			(stroke
				(width 0)
				(type default)
			)
			(fill no)
			(layer "F.Fab")
		)
		(pad "1" smd custom
			(at 0 -0.4445 270)
			(size 0.1524 0.1524)
			(layers "F.Cu" "F.Mask" "F.Paste")
			(net "USB_HUB_XTAL_IN")
			(options
				(clearance outline)
				(anchor circle)
			)
			(primitives
				(gr_poly
					(pts
						(arc
							(start 0.3048 -0.2032)
							(mid 0.275042 -0.275042)
							(end 0.2032 -0.3048)
						)
						(arc
							(start -0.2032 -0.3048)
							(mid -0.275042 -0.275042)
							(end -0.3048 -0.2032)
						)
						(arc
							(start -0.3048 0.2032)
							(mid -0.275042 0.275042)
							(end -0.2032 0.3048)
						)
						(arc
							(start 0.2032 0.3048)
							(mid 0.275042 0.275042)
							(end 0.3048 0.2032)
						)
					)
					(width 0)
					(fill yes)
				)
			)
		)
		(pad "2" smd custom
			(at 0 0.4445 270)
			(size 0.1524 0.1524)
			(layers "F.Cu" "F.Mask" "F.Paste")
			(net "GND")
			(options
				(clearance outline)
				(anchor circle)
			)
			(primitives
				(gr_poly
					(pts
						(arc
							(start 0.3048 -0.2032)
							(mid 0.275042 -0.275042)
							(end 0.2032 -0.3048)
						)
						(arc
							(start -0.2032 -0.3048)
							(mid -0.275042 -0.275042)
							(end -0.3048 -0.2032)
						)
						(arc
							(start -0.3048 0.2032)
							(mid -0.275042 0.275042)
							(end -0.2032 0.3048)
						)
						(arc
							(start 0.2032 0.3048)
							(mid 0.275042 0.275042)
							(end 0.3048 0.2032)
						)
					)
					(width 0)
					(fill yes)
				)
			)
		)
	)
	(footprint ""
		(layer "F.Cu")
		(at 73.6092 -168.1988)
		(property "Reference" "R540"
			(at 0 0 0)
			(layer "F.SilkS")
			(hide yes)
			(effects
				(font
					(size 1.27 1.27)
				)
			)
		)
		(property "Value" "0R2J-2-GP"
			(at 0.064008 -3.993896 0)
			(unlocked yes)
			(layer "F.Fab")
			(hide yes)
			(effects
				(font
					(size 1.016 1.016)
					(thickness 0.1524)
				)
			)
		)
		(property "Device Type" "R402H16"
			(at 0.064008 -5.517896 0)
			(unlocked yes)
			(layer "F.Fab")
			(hide yes)
			(effects
				(font
					(size 1.016 1.016)
					(thickness 0.1524)
				)
			)
		)
		(duplicate_pad_numbers_are_jumpers no)
		(fp_line
			(start -0.508 -0.9398)
			(end -0.508 0.9398)
			(stroke
				(width 0.1524)
				(type default)
			)
			(layer "F.SilkS")
		)
		(fp_line
			(start 0.508 -0.9398)
			(end -0.508 -0.9398)
			(stroke
				(width 0.1524)
				(type default)
			)
			(layer "F.SilkS")
		)
		(fp_rect
			(start -0.508 0.9398)
			(end 0.508 -0.9398)
			(stroke
				(width 0)
				(type default)
			)
			(fill no)
			(layer "F.CrtYd")
		)
		(fp_rect
			(start -0.508 0.9398)
			(end 0.508 -0.9398)
			(stroke
				(width 0)
				(type default)
			)
			(fill no)
			(layer "F.Fab")
		)
		(pad "1" smd custom
			(at 0 -0.4445)
			(size 0.1397 0.1397)
			(layers "F.Cu" "F.Mask" "F.Paste")
			(net "P5V_STBY")
			(options
				(clearance outline)
				(anchor circle)
			)
			(primitives
				(gr_poly
					(pts
						(arc
							(start -0.1778 -0.2794)
							(mid -0.249642 -0.249642)
							(end -0.2794 -0.1778)
						)
						(arc
							(start -0.2794 0.1778)
							(mid -0.249642 0.249642)
							(end -0.1778 0.2794)
						)
						(arc
							(start 0.1778 0.2794)
							(mid 0.249642 0.249642)
							(end 0.2794 0.1778)
						)
						(arc
							(start 0.2794 -0.1778)
							(mid 0.249642 -0.249642)
							(end 0.1778 -0.2794)
						)
					)
					(width 0)
					(fill yes)
				)
			)
		)
		(pad "2" smd custom
			(at 0 0.4445)
			(size 0.1397 0.1397)
			(layers "F.Cu" "F.Mask" "F.Paste")
			(net "TPS74801_P1V15_STBY_BIAS")
			(options
				(clearance outline)
				(anchor circle)
			)
			(primitives
				(gr_poly
					(pts
						(arc
							(start -0.1778 -0.2794)
							(mid -0.249642 -0.249642)
							(end -0.2794 -0.1778)
						)
						(arc
							(start -0.2794 0.1778)
							(mid -0.249642 0.249642)
							(end -0.1778 0.2794)
						)
						(arc
							(start 0.1778 0.2794)
							(mid 0.249642 0.249642)
							(end 0.2794 0.1778)
						)
						(arc
							(start 0.2794 -0.1778)
							(mid 0.249642 -0.249642)
							(end 0.1778 -0.2794)
						)
					)
					(width 0)
					(fill yes)
				)
			)
		)
	)
	(footprint ""
		(layer "F.Cu")
		(at 20.591272 -129.074164 180)
		(property "Reference" "R225"
			(at 0 0 180)
			(layer "F.SilkS")
			(hide yes)
			(effects
				(font
					(size 1.27 1.27)
				)
			)
		)
		(property "Value" "120R2F-GP"
			(at 0.064008 -3.993896 180)
			(unlocked yes)
			(layer "F.Fab")
			(hide yes)
			(effects
				(font
					(size 1.016 1.016)
					(thickness 0.1524)
				)
			)
		)
		(property "Device Type" "R402H16"
			(at 0.064008 -5.517896 180)
			(unlocked yes)
			(layer "F.Fab")
			(hide yes)
			(effects
				(font
					(size 1.016 1.016)
					(thickness 0.1524)
				)
			)
		)
		(duplicate_pad_numbers_are_jumpers no)
		(fp_line
			(start 0.508 -0.9398)
			(end -0.508 -0.9398)
			(stroke
				(width 0.1524)
				(type default)
			)
			(layer "F.SilkS")
		)
		(fp_line
			(start -0.508 -0.9398)
			(end -0.508 0.9398)
			(stroke
				(width 0.1524)
				(type default)
			)
			(layer "F.SilkS")
		)
		(fp_rect
			(start -0.508 0.9398)
			(end 0.508 -0.9398)
			(stroke
				(width 0)
				(type default)
			)
			(fill no)
			(layer "F.CrtYd")
		)
		(fp_rect
			(start -0.508 0.9398)
			(end 0.508 -0.9398)
			(stroke
				(width 0)
				(type default)
			)
			(fill no)
			(layer "F.Fab")
		)
		(pad "1" smd custom
			(at 0 -0.4445 180)
			(size 0.1397 0.1397)
			(layers "F.Cu" "F.Mask" "F.Paste")
			(net "GND")
			(options
				(clearance outline)
				(anchor circle)
			)
			(primitives
				(gr_poly
					(pts
						(arc
							(start -0.1778 -0.2794)
							(mid -0.249642 -0.249642)
							(end -0.2794 -0.1778)
						)
						(arc
							(start -0.2794 0.1778)
							(mid -0.249642 0.249642)
							(end -0.1778 0.2794)
						)
						(arc
							(start 0.1778 0.2794)
							(mid 0.249642 0.249642)
							(end 0.2794 0.1778)
						)
						(arc
							(start 0.2794 -0.1778)
							(mid 0.249642 -0.249642)
							(end 0.1778 -0.2794)
						)
					)
					(width 0)
					(fill yes)
				)
			)
		)
		(pad "2" smd custom
			(at 0 0.4445 180)
			(size 0.1397 0.1397)
			(layers "F.Cu" "F.Mask" "F.Paste")
			(net "MEMCASN")
			(options
				(clearance outline)
				(anchor circle)
			)
			(primitives
				(gr_poly
					(pts
						(arc
							(start -0.1778 -0.2794)
							(mid -0.249642 -0.249642)
							(end -0.2794 -0.1778)
						)
						(arc
							(start -0.2794 0.1778)
							(mid -0.249642 0.249642)
							(end -0.1778 0.2794)
						)
						(arc
							(start 0.1778 0.2794)
							(mid 0.249642 0.249642)
							(end 0.2794 0.1778)
						)
						(arc
							(start 0.2794 -0.1778)
							(mid 0.249642 -0.249642)
							(end 0.1778 -0.2794)
						)
					)
					(width 0)
					(fill yes)
				)
			)
		)
	)
	(footprint ""
		(layer "F.Cu")
		(at 93.177106 -142.653766 -90)
		(property "Reference" "U34"
			(at 0 0 270)
			(layer "F.SilkS")
			(hide yes)
			(effects
				(font
					(size 1.27 1.27)
				)
			)
		)
		(property "Value" "TCA9555PWR-GP"
			(at 0 -6.9342 270)
			(unlocked yes)
			(layer "F.Fab")
			(hide yes)
			(effects
				(font
					(size 1.016 1.016)
					(thickness 0.1524)
				)
			)
		)
		(property "Device Type" "TSOIC24H48"
			(at 0 -8.5852 270)
			(unlocked yes)
			(layer "F.Fab")
			(hide yes)
			(effects
				(font
					(size 1.016 1.016)
					(thickness 0.1524)
				)
			)
		)
		(duplicate_pad_numbers_are_jumpers no)
		(fp_line
			(start -4.2291 3.937)
			(end -4.2291 -1.397)
			(stroke
				(width 0.1524)
				(type default)
			)
			(layer "F.SilkS")
		)
		(fp_line
			(start -4.22656 3.81)
			(end -4.2291 1.397)
			(stroke
				(width 0.508)
				(type default)
			)
			(layer "F.SilkS")
		)
		(fp_line
			(start 3.81 1.397)
			(end -4.2291 1.397)
			(stroke
				(width 0.1524)
				(type default)
			)
			(layer "F.SilkS")
		)
		(fp_line
			(start -3.429 0)
			(end -4.2291 0.8001)
			(stroke
				(width 0.1524)
				(type default)
			)
			(layer "F.SilkS")
		)
		(fp_line
			(start -4.2291 -0.8001)
			(end -3.429 0)
			(stroke
				(width 0.1524)
				(type default)
			)
			(layer "F.SilkS")
		)
		(fp_line
			(start -4.2291 -1.397)
			(end 3.81 -1.397)
			(stroke
				(width 0.1524)
				(type default)
			)
			(layer "F.SilkS")
		)
		(fp_line
			(start 3.81 -1.397)
			(end 3.81 1.397)
			(stroke
				(width 0.1524)
				(type default)
			)
			(layer "F.SilkS")
		)
		(fp_poly
			(pts
				(xy -3.90652 -1.8542) (xy 3.90652 -1.8542) (xy 3.90652 1.8542) (xy -3.90652 1.8542)
			)
			(stroke
				(width 0)
				(type default)
			)
			(fill yes)
			(layer "F.SilkS")
		)
		(fp_poly
			(pts
				(xy -4.2164 3.81) (xy 4.2164 3.81) (xy 4.22656 -3.81) (xy -4.2164 -3.81)
			)
			(stroke
				(width 0)
				(type default)
			)
			(fill no)
			(layer "F.CrtYd")
		)
		(fp_poly
			(pts
				(xy -4.22656 -3.81) (xy 4.22656 -3.81) (xy 4.22656 3.81) (xy -4.22656 3.81)
			)
			(stroke
				(width 0)
				(type default)
			)
			(fill no)
			(layer "F.Fab")
		)
		(pad "1" smd rect
			(at -3.57632 2.8194 270)
			(size 0.3556 1.524)
			(layers "F.Cu" "F.Mask" "F.Paste")
			(net "IO_EXP0_RESET#_FLT")
		)
		(pad "2" smd rect
			(at -2.92608 2.8194 270)
			(size 0.3556 1.524)
			(layers "F.Cu" "F.Mask" "F.Paste")
			(net "TCA9555_A1")
		)
		(pad "3" smd rect
			(at -2.27584 2.8194 270)
			(size 0.3556 1.524)
			(layers "F.Cu" "F.Mask" "F.Paste")
			(net "TCA9555_A2")
		)
		(pad "4" smd rect
			(at -1.6256 2.8194 270)
			(size 0.3556 1.524)
			(layers "F.Cu" "F.Mask" "F.Paste")
			(net "LED_POSTCODE_0")
		)
		(pad "5" smd rect
			(at -0.97536 2.8194 270)
			(size 0.3556 1.524)
			(layers "F.Cu" "F.Mask" "F.Paste")
			(net "LED_POSTCODE_1")
		)
		(pad "6" smd rect
			(at -0.32512 2.8194 270)
			(size 0.3556 1.524)
			(layers "F.Cu" "F.Mask" "F.Paste")
			(net "LED_POSTCODE_2")
		)
		(pad "7" smd rect
			(at 0.32512 2.8194 270)
			(size 0.3556 1.524)
			(layers "F.Cu" "F.Mask" "F.Paste")
			(net "LED_POSTCODE_3")
		)
		(pad "8" smd rect
			(at 0.97536 2.8194 270)
			(size 0.3556 1.524)
			(layers "F.Cu" "F.Mask" "F.Paste")
			(net "LED_POSTCODE_4")
		)
		(pad "9" smd rect
			(at 1.6256 2.8194 270)
			(size 0.3556 1.524)
			(layers "F.Cu" "F.Mask" "F.Paste")
			(net "LED_POSTCODE_5")
		)
		(pad "10" smd rect
			(at 2.27584 2.8194 270)
			(size 0.3556 1.524)
			(layers "F.Cu" "F.Mask" "F.Paste")
			(net "LED_POSTCODE_6")
		)
		(pad "11" smd rect
			(at 2.92608 2.8194 270)
			(size 0.3556 1.524)
			(layers "F.Cu" "F.Mask" "F.Paste")
			(net "LED_POSTCODE_7")
		)
		(pad "12" smd rect
			(at 3.57632 2.8194 270)
			(size 0.3556 1.524)
			(layers "F.Cu" "F.Mask" "F.Paste")
			(net "GND")
		)
		(pad "13" smd rect
			(at 3.57632 -2.8194 270)
			(size 0.3556 1.524)
			(layers "F.Cu" "F.Mask" "F.Paste")
			(net "DEBUG_RST_BTN_N")
		)
		(pad "14" smd rect
			(at 2.92608 -2.8194 270)
			(size 0.3556 1.524)
			(layers "F.Cu" "F.Mask" "F.Paste")
			(net "DEBUG_GPIO_BMC_1")
		)
		(pad "15" smd rect
			(at 2.27584 -2.8194 270)
			(size 0.3556 1.524)
			(layers "F.Cu" "F.Mask" "F.Paste")
			(net "DEBUG_GPIO_BMC_2")
		)
		(pad "16" smd rect
			(at 1.6256 -2.8194 270)
			(size 0.3556 1.524)
			(layers "F.Cu" "F.Mask" "F.Paste")
			(net "DEBUG_GPIO_BMC_3")
		)
		(pad "17" smd rect
			(at 0.97536 -2.8194 270)
			(size 0.3556 1.524)
			(layers "F.Cu" "F.Mask" "F.Paste")
			(net "DEBUG_GPIO_BMC_4")
		)
		(pad "18" smd rect
			(at 0.32512 -2.8194 270)
			(size 0.3556 1.524)
			(layers "F.Cu" "F.Mask" "F.Paste")
			(net "DEBUG_GPIO_BMC_5")
		)
		(pad "19" smd rect
			(at -0.32512 -2.8194 270)
			(size 0.3556 1.524)
			(layers "F.Cu" "F.Mask" "F.Paste")
			(net "DEBUG_GPIO_BMC_6")
		)
		(pad "20" smd rect
			(at -0.97536 -2.8194 270)
			(size 0.3556 1.524)
			(layers "F.Cu" "F.Mask" "F.Paste")
			(net "DEBUG_HDR_UART_SEL")
		)
		(pad "21" smd rect
			(at -1.6256 -2.8194 270)
			(size 0.3556 1.524)
			(layers "F.Cu" "F.Mask" "F.Paste")
			(net "TCA9555_A0")
		)
		(pad "22" smd rect
			(at -2.27584 -2.8194 270)
			(size 0.3556 1.524)
			(layers "F.Cu" "F.Mask" "F.Paste")
			(net "I2C_DEBUG_SCL_R")
		)
		(pad "23" smd rect
			(at -2.92608 -2.8194 270)
			(size 0.3556 1.524)
			(layers "F.Cu" "F.Mask" "F.Paste")
			(net "I2C_DEBUG_SDA_R")
		)
		(pad "24" smd rect
			(at -3.57632 -2.8194 270)
			(size 0.3556 1.524)
			(layers "F.Cu" "F.Mask" "F.Paste")
			(net "P3V3_STBY")
		)
	)
	(footprint ""
		(layer "F.Cu")
		(at 74.423016 -174.78248 -90)
		(property "Reference" "C190"
			(at 0 0 270)
			(layer "F.SilkS")
			(hide yes)
			(effects
				(font
					(size 1.27 1.27)
				)
			)
		)
		(property "Value" "SC1KP50V2KX-1GP"
			(at 1.1811 -2.7051 270)
			(unlocked yes)
			(layer "F.Fab")
			(hide yes)
			(effects
				(font
					(size 1.016 1.016)
					(thickness 0.1524)
				)
			)
		)
		(property "Device Type" "C402H22"
			(at 1.1811 -4.2291 270)
			(unlocked yes)
			(layer "F.Fab")
			(hide yes)
			(effects
				(font
					(size 1.016 1.016)
					(thickness 0.1524)
				)
			)
		)
		(duplicate_pad_numbers_are_jumpers no)
		(fp_rect
			(start -0.4318 0.9525)
			(end 0.4318 -0.9525)
			(stroke
				(width 0)
				(type default)
			)
			(fill no)
			(layer "F.CrtYd")
		)
		(fp_rect
			(start -0.4318 0.9525)
			(end 0.4318 -0.9525)
			(stroke
				(width 0)
				(type default)
			)
			(fill no)
			(layer "F.Fab")
		)
		(pad "1" smd custom
			(at 0 -0.4445 270)
			(size 0.1524 0.1524)
			(layers "F.Cu" "F.Mask" "F.Paste")
			(net "TPS74801_P2V5_STBY_OUT")
			(options
				(clearance outline)
				(anchor circle)
			)
			(primitives
				(gr_poly
					(pts
						(arc
							(start 0.3048 -0.2032)
							(mid 0.275042 -0.275042)
							(end 0.2032 -0.3048)
						)
						(arc
							(start -0.2032 -0.3048)
							(mid -0.275042 -0.275042)
							(end -0.3048 -0.2032)
						)
						(arc
							(start -0.3048 0.2032)
							(mid -0.275042 0.275042)
							(end -0.2032 0.3048)
						)
						(arc
							(start 0.2032 0.3048)
							(mid 0.275042 0.275042)
							(end 0.3048 0.2032)
						)
					)
					(width 0)
					(fill yes)
				)
			)
		)
		(pad "2" smd custom
			(at 0 0.4445 270)
			(size 0.1524 0.1524)
			(layers "F.Cu" "F.Mask" "F.Paste")
			(net "TPS74801_P2V5_STBY_FB")
			(options
				(clearance outline)
				(anchor circle)
			)
			(primitives
				(gr_poly
					(pts
						(arc
							(start 0.3048 -0.2032)
							(mid 0.275042 -0.275042)
							(end 0.2032 -0.3048)
						)
						(arc
							(start -0.2032 -0.3048)
							(mid -0.275042 -0.275042)
							(end -0.3048 -0.2032)
						)
						(arc
							(start -0.3048 0.2032)
							(mid -0.275042 0.275042)
							(end -0.2032 0.3048)
						)
						(arc
							(start 0.2032 0.3048)
							(mid 0.275042 0.275042)
							(end 0.3048 0.2032)
						)
					)
					(width 0)
					(fill yes)
				)
			)
		)
	)
	(footprint ""
		(layer "F.Cu")
		(at 98.27895 -176.116234 -90)
		(property "Reference" "R736"
			(at 0 0 270)
			(layer "F.SilkS")
			(hide yes)
			(effects
				(font
					(size 1.27 1.27)
				)
			)
		)
		(property "Value" "0R2J-2-GP"
			(at 0.064008 -3.993896 270)
			(unlocked yes)
			(layer "F.Fab")
			(hide yes)
			(effects
				(font
					(size 1.016 1.016)
					(thickness 0.1524)
				)
			)
		)
		(property "Device Type" "R402H16"
			(at 0.064008 -5.517896 270)
			(unlocked yes)
			(layer "F.Fab")
			(hide yes)
			(effects
				(font
					(size 1.016 1.016)
					(thickness 0.1524)
				)
			)
		)
		(duplicate_pad_numbers_are_jumpers no)
		(fp_line
			(start -0.508 -0.9398)
			(end -0.508 0.9398)
			(stroke
				(width 0.1524)
				(type default)
			)
			(layer "F.SilkS")
		)
		(fp_line
			(start 0.508 -0.9398)
			(end -0.508 -0.9398)
			(stroke
				(width 0.1524)
				(type default)
			)
			(layer "F.SilkS")
		)
		(fp_rect
			(start -0.508 0.9398)
			(end 0.508 -0.9398)
			(stroke
				(width 0)
				(type default)
			)
			(fill no)
			(layer "F.CrtYd")
		)
		(fp_rect
			(start -0.508 0.9398)
			(end 0.508 -0.9398)
			(stroke
				(width 0)
				(type default)
			)
			(fill no)
			(layer "F.Fab")
		)
		(pad "1" smd custom
			(at 0 -0.4445 270)
			(size 0.1397 0.1397)
			(layers "F.Cu" "F.Mask" "F.Paste")
			(net "PWRGD_P3V3_STBY_N")
			(options
				(clearance outline)
				(anchor circle)
			)
			(primitives
				(gr_poly
					(pts
						(arc
							(start -0.1778 -0.2794)
							(mid -0.249642 -0.249642)
							(end -0.2794 -0.1778)
						)
						(arc
							(start -0.2794 0.1778)
							(mid -0.249642 0.249642)
							(end -0.1778 0.2794)
						)
						(arc
							(start 0.1778 0.2794)
							(mid 0.249642 0.249642)
							(end 0.2794 0.1778)
						)
						(arc
							(start 0.2794 -0.1778)
							(mid 0.249642 -0.249642)
							(end 0.1778 -0.2794)
						)
					)
					(width 0)
					(fill yes)
				)
			)
		)
		(pad "2" smd custom
			(at 0 0.4445 270)
			(size 0.1397 0.1397)
			(layers "F.Cu" "F.Mask" "F.Paste")
			(net "PWRGD_P3V3_STBY_N_R2")
			(options
				(clearance outline)
				(anchor circle)
			)
			(primitives
				(gr_poly
					(pts
						(arc
							(start -0.1778 -0.2794)
							(mid -0.249642 -0.249642)
							(end -0.2794 -0.1778)
						)
						(arc
							(start -0.2794 0.1778)
							(mid -0.249642 0.249642)
							(end -0.1778 0.2794)
						)
						(arc
							(start 0.1778 0.2794)
							(mid 0.249642 0.249642)
							(end 0.2794 0.1778)
						)
						(arc
							(start 0.2794 -0.1778)
							(mid 0.249642 -0.249642)
							(end 0.1778 -0.2794)
						)
					)
					(width 0)
					(fill yes)
				)
			)
		)
	)
	(footprint ""
		(layer "F.Cu")
		(at 204.1144 -85.1916 135)
		(property "Reference" "VIA17"
			(at 0 0 135)
			(layer "F.SilkS")
			(hide yes)
			(effects
				(font
					(size 1.27 1.27)
				)
			)
		)
		(property "Value" "85OHM-8L-1D6MM-L16L18-GP"
			(at 4.064105 0.609655 135)
			(unlocked yes)
			(layer "F.Fab")
			(hide yes)
			(effects
				(font
					(size 1.016 1.016)
					(thickness 0.1524)
				)
			)
		)
		(property "Device Type" "VIA-PCIE-4P-368076"
			(at 4.064105 -0.914474 135)
			(unlocked yes)
			(layer "F.Fab")
			(hide yes)
			(effects
				(font
					(size 1.016 1.016)
					(thickness 0.1524)
				)
			)
		)
		(duplicate_pad_numbers_are_jumpers no)
		(fp_poly
			(pts
				(xy -1.841491 -0.381057) (xy 1.841509 -0.381058) (xy 1.841508 0.380942) (xy -1.841491 0.380942)
			)
			(stroke
				(width 0)
				(type default)
			)
			(fill no)
			(layer "F.CrtYd")
		)
		(fp_poly
			(pts
				(xy -1.841491 -0.381057) (xy 1.841509 -0.381058) (xy 1.841508 0.380942) (xy -1.841491 0.380942)
			)
			(stroke
				(width 0)
				(type default)
			)
			(fill no)
			(layer "F.Fab")
		)
		(pad "1" thru_hole circle
			(at -1.460499 0 135)
			(size 0.508 0.508)
			(drill 0.254)
			(layers "*.Cu" "*.Mask")
			(remove_unused_layers no)
			(net "GND")
			(clearance 0.127)
			(thermal_gap 0.127)
		)
		(pad "2" thru_hole circle
			(at -0.4445 0 135)
			(size 0.508 0.508)
			(drill 0.254)
			(layers "*.Cu" "*.Mask")
			(remove_unused_layers no)
			(net "PCIE_COMP_TO_IOM_8_DP")
			(clearance 0.127)
			(thermal_gap 0.127)
		)
		(pad "3" thru_hole circle
			(at 0.4445 0 135)
			(size 0.508 0.508)
			(drill 0.254)
			(layers "*.Cu" "*.Mask")
			(remove_unused_layers no)
			(net "PCIE_COMP_TO_IOM_8_DN")
			(clearance 0.127)
			(thermal_gap 0.127)
		)
		(pad "4" thru_hole circle
			(at 1.460499 0 135)
			(size 0.508 0.508)
			(drill 0.254)
			(layers "*.Cu" "*.Mask")
			(remove_unused_layers no)
			(net "GND")
			(clearance 0.127)
			(thermal_gap 0.127)
		)
	)
	(footprint ""
		(layer "F.Cu")
		(at 185.928 -86.7156)
		(property "Reference" "TP145"
			(at 0 0 0)
			(layer "F.SilkS")
			(hide yes)
			(effects
				(font
					(size 1.27 1.27)
				)
			)
		)
		(property "Value" "TPAD28-2-GP"
			(at -0.0127 -1.6637 0)
			(unlocked yes)
			(layer "F.Fab")
			(hide yes)
			(effects
				(font
					(size 1.016 1.016)
					(thickness 0.1524)
				)
			)
		)
		(property "Device Type" "TPAD28"
			(at -0.0127 -3.1877 0)
			(unlocked yes)
			(layer "F.Fab")
			(hide yes)
			(effects
				(font
					(size 1.016 1.016)
					(thickness 0.1524)
				)
			)
		)
		(duplicate_pad_numbers_are_jumpers no)
		(fp_poly
			(pts
				(arc
					(start 0.3556 0)
					(mid -0.3556 0)
					(end 0.3556 0)
				)
			)
			(stroke
				(width 0)
				(type default)
			)
			(fill no)
			(layer "F.CrtYd")
		)
		(fp_poly
			(pts
				(arc
					(start 0.6096 0)
					(mid -0.6096 0)
					(end 0.6096 0)
				)
			)
			(stroke
				(width 0)
				(type default)
			)
			(fill no)
			(layer "F.Fab")
		)
		(pad "1" smd circle
			(at 0 0)
			(size 0.7112 0.7112)
			(layers "F.Cu" "F.Mask" "F.Paste")
			(net "SYS_ERROR1")
		)
	)
	(footprint ""
		(layer "F.Cu")
		(at 152.4762 -145.8976)
		(property "Reference" "CN5"
			(at 0 0 0)
			(layer "F.SilkS")
			(hide yes)
			(effects
				(font
					(size 1.27 1.27)
				)
			)
		)
		(property "Value" "PIN-CON3-5-GP"
			(at -5.334 -8.128 0)
			(unlocked yes)
			(layer "F.Fab")
			(hide yes)
			(effects
				(font
					(size 1.016 1.016)
					(thickness 0.1524)
				)
			)
		)
		(property "Device Type" "211-91-03GB01"
			(at -5.334 -9.652 0)
			(unlocked yes)
			(layer "F.Fab")
			(hide yes)
			(effects
				(font
					(size 1.016 1.016)
					(thickness 0.1524)
				)
			)
		)
		(duplicate_pad_numbers_are_jumpers no)
		(fp_line
			(start -3.8862 -10.16)
			(end -3.8862 0.9652)
			(stroke
				(width 0.1524)
				(type default)
			)
			(layer "F.SilkS")
		)
		(fp_line
			(start -3.8862 0.9652)
			(end 3.8862 0.9652)
			(stroke
				(width 0.1524)
				(type default)
			)
			(layer "F.SilkS")
		)
		(fp_line
			(start 2.742438 1.09601)
			(end 4.012438 1.09601)
			(stroke
				(width 0.4064)
				(type default)
			)
			(layer "F.SilkS")
		)
		(fp_line
			(start 3.8862 -10.16)
			(end -3.8862 -10.16)
			(stroke
				(width 0.1524)
				(type default)
			)
			(layer "F.SilkS")
		)
		(fp_line
			(start 3.8862 0.9652)
			(end 3.8862 -10.16)
			(stroke
				(width 0.1524)
				(type default)
			)
			(layer "F.SilkS")
		)
		(fp_line
			(start 4.012438 1.09601)
			(end 4.012438 -0.17399)
			(stroke
				(width 0.4064)
				(type default)
			)
			(layer "F.SilkS")
		)
		(fp_circle
			(center -2.54 0)
			(end -1.4732 0)
			(stroke
				(width 0.3048)
				(type default)
			)
			(fill no)
			(layer "F.SilkS")
		)
		(fp_circle
			(center 0 0)
			(end 1.0668 0)
			(stroke
				(width 0.3048)
				(type default)
			)
			(fill no)
			(layer "F.SilkS")
		)
		(fp_circle
			(center 2.54 0)
			(end 3.6068 0)
			(stroke
				(width 0.3048)
				(type default)
			)
			(fill no)
			(layer "F.SilkS")
		)
		(fp_rect
			(start -3.6322 0.3302)
			(end 3.6322 -9.906)
			(stroke
				(width 0)
				(type default)
			)
			(fill no)
			(layer "F.CrtYd")
		)
		(fp_poly
			(pts
				(xy 4.1402 -9.906) (xy -3.6322 -9.906) (xy -3.6322 0.3302) (xy 3.6322 0.3302) (xy 3.6322 -9.8933)
				(xy 4.1402 -9.8933) (xy 4.1402 1.2192) (xy -4.1402 1.2192) (xy -4.1402 -10.414) (xy 4.1402 -10.414)
			)
			(stroke
				(width 0)
				(type default)
			)
			(fill no)
			(layer "F.CrtYd")
		)
		(fp_rect
			(start -4.1402 1.2192)
			(end 4.1402 -10.414)
			(stroke
				(width 0)
				(type default)
			)
			(fill no)
			(layer "F.Fab")
		)
		(pad "1" thru_hole circle
			(at 2.54 0)
			(size 1.4224 1.4224)
			(drill 1.016)
			(layers "*.Cu" "*.Mask")
			(remove_unused_layers no)
			(net "IOM_IOC_UART_TX")
			(clearance 0.1524)
			(thermal_gap 0.1524)
		)
		(pad "2" thru_hole circle
			(at 0 0)
			(size 1.4224 1.4224)
			(drill 1.016)
			(layers "*.Cu" "*.Mask")
			(remove_unused_layers no)
			(net "IOM_IOC_UART_RX")
			(clearance 0.1524)
			(thermal_gap 0.1524)
		)
		(pad "3" thru_hole circle
			(at -2.54 0)
			(size 1.4224 1.4224)
			(drill 1.016)
			(layers "*.Cu" "*.Mask")
			(remove_unused_layers no)
			(net "GND")
			(clearance 0.1524)
			(thermal_gap 0.1524)
		)
	)
	(footprint ""
		(layer "F.Cu")
		(at 79.99984 -119.99976)
		(property "Reference" ""
			(at 0 0 0)
			(layer "F.SilkS")
			(hide yes)
			(effects
				(font
					(size 1.27 1.27)
				)
			)
		)
		(property "Value" "*"
			(at -6.38175 0.19685 0)
			(unlocked yes)
			(layer "F.Fab")
			(hide yes)
			(effects
				(font
					(size 1.016 1.016)
					(thickness 0.1524)
				)
			)
		)
		(duplicate_pad_numbers_are_jumpers no)
		(fp_poly
			(pts
				(arc
					(start 5.0673 0)
					(mid -5.0673 0)
					(end 5.0673 0)
				)
			)
			(stroke
				(width 0)
				(type default)
			)
			(fill no)
			(layer "B.CrtYd")
		)
		(fp_poly
			(pts
				(arc
					(start 5.0673 0)
					(mid -5.0673 0)
					(end 5.0673 0)
				)
			)
			(stroke
				(width 0)
				(type default)
			)
			(fill no)
			(layer "F.CrtYd")
		)
		(fp_poly
			(pts
				(arc
					(start 5.0673 0)
					(mid -5.0673 0)
					(end 5.0673 0)
				)
			)
			(stroke
				(width 0)
				(type default)
			)
			(fill no)
			(layer "B.Fab")
		)
		(fp_poly
			(pts
				(arc
					(start 5.0673 0)
					(mid -5.0673 0)
					(end 5.0673 0)
				)
			)
			(stroke
				(width 0)
				(type default)
			)
			(fill no)
			(layer "F.Fab")
		)
		(pad "1" thru_hole circle
			(at 0 0)
			(size 9.525 9.525)
			(drill 3.5052)
			(layers "*.Cu" "*.Mask")
			(remove_unused_layers no)
			(net "Net_9")
			(clearance -2.5019)
			(thermal_gap 0.3048)
			(padstack
				(mode front_inner_back)
				(layer "Inner"
					(shape circle)
					(size 3.9116 3.9116)
					(clearance 0.3048)
				)
				(layer "B.Cu"
					(shape circle)
					(size 9.525 9.525)
					(clearance -2.5019)
				)
			)
		)
	)
	(footprint ""
		(layer "F.Cu")
		(at 8.879332 -136.716516 90)
		(property "Reference" "R207"
			(at 0 0 90)
			(layer "F.SilkS")
			(hide yes)
			(effects
				(font
					(size 1.27 1.27)
				)
			)
		)
		(property "Value" "120R2F-GP"
			(at 0.064008 -3.993896 90)
			(unlocked yes)
			(layer "F.Fab")
			(hide yes)
			(effects
				(font
					(size 1.016 1.016)
					(thickness 0.1524)
				)
			)
		)
		(property "Device Type" "R402H16"
			(at 0.064008 -5.517896 90)
			(unlocked yes)
			(layer "F.Fab")
			(hide yes)
			(effects
				(font
					(size 1.016 1.016)
					(thickness 0.1524)
				)
			)
		)
		(duplicate_pad_numbers_are_jumpers no)
		(fp_line
			(start 0.508 -0.9398)
			(end -0.508 -0.9398)
			(stroke
				(width 0.1524)
				(type default)
			)
			(layer "F.SilkS")
		)
		(fp_line
			(start -0.508 -0.9398)
			(end -0.508 0.9398)
			(stroke
				(width 0.1524)
				(type default)
			)
			(layer "F.SilkS")
		)
		(fp_rect
			(start -0.508 0.9398)
			(end 0.508 -0.9398)
			(stroke
				(width 0)
				(type default)
			)
			(fill no)
			(layer "F.CrtYd")
		)
		(fp_rect
			(start -0.508 0.9398)
			(end 0.508 -0.9398)
			(stroke
				(width 0)
				(type default)
			)
			(fill no)
			(layer "F.Fab")
		)
		(pad "1" smd custom
			(at 0 -0.4445 90)
			(size 0.1397 0.1397)
			(layers "F.Cu" "F.Mask" "F.Paste")
			(net "GND")
			(options
				(clearance outline)
				(anchor circle)
			)
			(primitives
				(gr_poly
					(pts
						(arc
							(start -0.1778 -0.2794)
							(mid -0.249642 -0.249642)
							(end -0.2794 -0.1778)
						)
						(arc
							(start -0.2794 0.1778)
							(mid -0.249642 0.249642)
							(end -0.1778 0.2794)
						)
						(arc
							(start 0.1778 0.2794)
							(mid 0.249642 0.249642)
							(end 0.2794 0.1778)
						)
						(arc
							(start 0.2794 -0.1778)
							(mid 0.249642 -0.249642)
							(end 0.1778 -0.2794)
						)
					)
					(width 0)
					(fill yes)
				)
			)
		)
		(pad "2" smd custom
			(at 0 0.4445 90)
			(size 0.1397 0.1397)
			(layers "F.Cu" "F.Mask" "F.Paste")
			(net "DDR4_RST_N")
			(options
				(clearance outline)
				(anchor circle)
			)
			(primitives
				(gr_poly
					(pts
						(arc
							(start -0.1778 -0.2794)
							(mid -0.249642 -0.249642)
							(end -0.2794 -0.1778)
						)
						(arc
							(start -0.2794 0.1778)
							(mid -0.249642 0.249642)
							(end -0.1778 0.2794)
						)
						(arc
							(start 0.1778 0.2794)
							(mid 0.249642 0.249642)
							(end 0.2794 0.1778)
						)
						(arc
							(start 0.2794 -0.1778)
							(mid 0.249642 -0.249642)
							(end 0.1778 -0.2794)
						)
					)
					(width 0)
					(fill yes)
				)
			)
		)
	)
	(footprint ""
		(layer "F.Cu")
		(at 111.0742 -13.324078 -90)
		(property "Reference" "C149"
			(at 0 0 270)
			(layer "F.SilkS")
			(hide yes)
			(effects
				(font
					(size 1.27 1.27)
				)
			)
		)
		(property "Value" "SCD1U50V3KX-GP"
			(at 0 -2.8194 270)
			(unlocked yes)
			(layer "F.Fab")
			(hide yes)
			(effects
				(font
					(size 1.016 1.016)
					(thickness 0.1524)
				)
			)
		)
		(property "Device Type" "C603H36"
			(at 0 -4.3434 270)
			(unlocked yes)
			(layer "F.Fab")
			(hide yes)
			(effects
				(font
					(size 1.016 1.016)
					(thickness 0.1524)
				)
			)
		)
		(duplicate_pad_numbers_are_jumpers no)
		(fp_line
			(start 0.508 0)
			(end -0.508 0)
			(stroke
				(width 0.2032)
				(type default)
			)
			(layer "F.SilkS")
		)
		(fp_rect
			(start -0.5842 1.3335)
			(end 0.5842 -1.3335)
			(stroke
				(width 0)
				(type default)
			)
			(fill no)
			(layer "F.CrtYd")
		)
		(fp_rect
			(start -0.5842 1.3335)
			(end 0.5842 -1.3335)
			(stroke
				(width 0)
				(type default)
			)
			(fill no)
			(layer "F.Fab")
		)
		(pad "1" smd custom
			(at 0 -0.762 270)
			(size 0.2159 0.2159)
			(layers "F.Cu" "F.Mask" "F.Paste")
			(net "MB0_PSET_R")
			(options
				(clearance outline)
				(anchor circle)
			)
			(primitives
				(gr_poly
					(pts
						(arc
							(start -0.3302 -0.4318)
							(mid -0.402042 -0.402042)
							(end -0.4318 -0.3302)
						)
						(arc
							(start -0.4318 0.3302)
							(mid -0.402042 0.402042)
							(end -0.3302 0.4318)
						)
						(arc
							(start 0.3302 0.4318)
							(mid 0.402042 0.402042)
							(end 0.4318 0.3302)
						)
						(arc
							(start 0.4318 -0.3302)
							(mid 0.402042 -0.402042)
							(end 0.3302 -0.4318)
						)
					)
					(width 0)
					(fill yes)
				)
			)
		)
		(pad "2" smd custom
			(at 0 0.762 270)
			(size 0.2159 0.2159)
			(layers "F.Cu" "F.Mask" "F.Paste")
			(net "AGND_CURRENT_MON")
			(options
				(clearance outline)
				(anchor circle)
			)
			(primitives
				(gr_poly
					(pts
						(arc
							(start -0.3302 -0.4318)
							(mid -0.402042 -0.402042)
							(end -0.4318 -0.3302)
						)
						(arc
							(start -0.4318 0.3302)
							(mid -0.402042 0.402042)
							(end -0.3302 0.4318)
						)
						(arc
							(start 0.3302 0.4318)
							(mid 0.402042 0.402042)
							(end 0.4318 0.3302)
						)
						(arc
							(start 0.4318 -0.3302)
							(mid 0.402042 -0.402042)
							(end 0.3302 -0.4318)
						)
					)
					(width 0)
					(fill yes)
				)
			)
		)
	)
	(footprint ""
		(layer "F.Cu")
		(at 112.856264 -9.689338 -90)
		(property "Reference" "R462"
			(at 0 0 270)
			(layer "F.SilkS")
			(hide yes)
			(effects
				(font
					(size 1.27 1.27)
				)
			)
		)
		(property "Value" "22K6R2F-1-GP"
			(at 0.064008 -3.993896 270)
			(unlocked yes)
			(layer "F.Fab")
			(hide yes)
			(effects
				(font
					(size 1.016 1.016)
					(thickness 0.1524)
				)
			)
		)
		(property "Device Type" "R402H16"
			(at 0.064008 -5.517896 270)
			(unlocked yes)
			(layer "F.Fab")
			(hide yes)
			(effects
				(font
					(size 1.016 1.016)
					(thickness 0.1524)
				)
			)
		)
		(duplicate_pad_numbers_are_jumpers no)
		(fp_line
			(start -0.508 -0.9398)
			(end -0.508 0.9398)
			(stroke
				(width 0.1524)
				(type default)
			)
			(layer "F.SilkS")
		)
		(fp_line
			(start 0.508 -0.9398)
			(end -0.508 -0.9398)
			(stroke
				(width 0.1524)
				(type default)
			)
			(layer "F.SilkS")
		)
		(fp_rect
			(start -0.508 0.9398)
			(end 0.508 -0.9398)
			(stroke
				(width 0)
				(type default)
			)
			(fill no)
			(layer "F.CrtYd")
		)
		(fp_rect
			(start -0.508 0.9398)
			(end 0.508 -0.9398)
			(stroke
				(width 0)
				(type default)
			)
			(fill no)
			(layer "F.Fab")
		)
		(pad "1" smd custom
			(at 0 -0.4445 270)
			(size 0.1397 0.1397)
			(layers "F.Cu" "F.Mask" "F.Paste")
			(net "MB0_ISTART_R")
			(options
				(clearance outline)
				(anchor circle)
			)
			(primitives
				(gr_poly
					(pts
						(arc
							(start -0.1778 -0.2794)
							(mid -0.249642 -0.249642)
							(end -0.2794 -0.1778)
						)
						(arc
							(start -0.2794 0.1778)
							(mid -0.249642 0.249642)
							(end -0.1778 0.2794)
						)
						(arc
							(start 0.1778 0.2794)
							(mid 0.249642 0.249642)
							(end 0.2794 0.1778)
						)
						(arc
							(start 0.2794 -0.1778)
							(mid 0.249642 -0.249642)
							(end 0.1778 -0.2794)
						)
					)
					(width 0)
					(fill yes)
				)
			)
		)
		(pad "2" smd custom
			(at 0 0.4445 270)
			(size 0.1397 0.1397)
			(layers "F.Cu" "F.Mask" "F.Paste")
			(net "AGND_CURRENT_MON")
			(options
				(clearance outline)
				(anchor circle)
			)
			(primitives
				(gr_poly
					(pts
						(arc
							(start -0.1778 -0.2794)
							(mid -0.249642 -0.249642)
							(end -0.2794 -0.1778)
						)
						(arc
							(start -0.2794 0.1778)
							(mid -0.249642 0.249642)
							(end -0.1778 0.2794)
						)
						(arc
							(start 0.1778 0.2794)
							(mid 0.249642 0.249642)
							(end 0.2794 0.1778)
						)
						(arc
							(start 0.2794 -0.1778)
							(mid 0.249642 -0.249642)
							(end 0.1778 -0.2794)
						)
					)
					(width 0)
					(fill yes)
				)
			)
		)
	)
	(footprint ""
		(layer "F.Cu")
		(at 195.436236 -131.699 -90)
		(property "Reference" "R551"
			(at 0 0 270)
			(layer "F.SilkS")
			(hide yes)
			(effects
				(font
					(size 1.27 1.27)
				)
			)
		)
		(property "Value" "4K7R2F-GP"
			(at 0.064008 -3.993896 270)
			(unlocked yes)
			(layer "F.Fab")
			(hide yes)
			(effects
				(font
					(size 1.016 1.016)
					(thickness 0.1524)
				)
			)
		)
		(property "Device Type" "R402H16"
			(at 0.064008 -5.517896 270)
			(unlocked yes)
			(layer "F.Fab")
			(hide yes)
			(effects
				(font
					(size 1.016 1.016)
					(thickness 0.1524)
				)
			)
		)
		(duplicate_pad_numbers_are_jumpers no)
		(fp_line
			(start -0.508 -0.9398)
			(end -0.508 0.9398)
			(stroke
				(width 0.1524)
				(type default)
			)
			(layer "F.SilkS")
		)
		(fp_line
			(start 0.508 -0.9398)
			(end -0.508 -0.9398)
			(stroke
				(width 0.1524)
				(type default)
			)
			(layer "F.SilkS")
		)
		(fp_rect
			(start -0.508 0.9398)
			(end 0.508 -0.9398)
			(stroke
				(width 0)
				(type default)
			)
			(fill no)
			(layer "F.CrtYd")
		)
		(fp_rect
			(start -0.508 0.9398)
			(end 0.508 -0.9398)
			(stroke
				(width 0)
				(type default)
			)
			(fill no)
			(layer "F.Fab")
		)
		(pad "1" smd custom
			(at 0 -0.4445 270)
			(size 0.1397 0.1397)
			(layers "F.Cu" "F.Mask" "F.Paste")
			(net "P3V3_STBY")
			(options
				(clearance outline)
				(anchor circle)
			)
			(primitives
				(gr_poly
					(pts
						(arc
							(start -0.1778 -0.2794)
							(mid -0.249642 -0.249642)
							(end -0.2794 -0.1778)
						)
						(arc
							(start -0.2794 0.1778)
							(mid -0.249642 0.249642)
							(end -0.1778 0.2794)
						)
						(arc
							(start 0.1778 0.2794)
							(mid 0.249642 0.249642)
							(end 0.2794 0.1778)
						)
						(arc
							(start 0.2794 -0.1778)
							(mid 0.249642 -0.249642)
							(end 0.1778 -0.2794)
						)
					)
					(width 0)
					(fill yes)
				)
			)
		)
		(pad "2" smd custom
			(at 0 0.4445 270)
			(size 0.1397 0.1397)
			(layers "F.Cu" "F.Mask" "F.Paste")
			(net "Q8_G")
			(options
				(clearance outline)
				(anchor circle)
			)
			(primitives
				(gr_poly
					(pts
						(arc
							(start -0.1778 -0.2794)
							(mid -0.249642 -0.249642)
							(end -0.2794 -0.1778)
						)
						(arc
							(start -0.2794 0.1778)
							(mid -0.249642 0.249642)
							(end -0.1778 0.2794)
						)
						(arc
							(start 0.1778 0.2794)
							(mid 0.249642 0.249642)
							(end 0.2794 0.1778)
						)
						(arc
							(start 0.2794 -0.1778)
							(mid 0.249642 -0.249642)
							(end 0.1778 -0.2794)
						)
					)
					(width 0)
					(fill yes)
				)
			)
		)
	)
	(footprint ""
		(layer "F.Cu")
		(at 221.900242 -98.434652)
		(property "Reference" "C374"
			(at 0 0 0)
			(layer "F.SilkS")
			(hide yes)
			(effects
				(font
					(size 1.27 1.27)
				)
			)
		)
		(property "Value" "SC100U6D3V6MX-GP"
			(at -0.0762 -5.1308 0)
			(unlocked yes)
			(layer "F.Fab")
			(hide yes)
			(effects
				(font
					(size 1.016 1.016)
					(thickness 0.1524)
				)
			)
		)
		(property "Device Type" "C1206H71"
			(at -0.127 -6.6548 0)
			(unlocked yes)
			(layer "F.Fab")
			(hide yes)
			(effects
				(font
					(size 1.016 1.016)
					(thickness 0.1524)
				)
			)
		)
		(duplicate_pad_numbers_are_jumpers no)
		(fp_line
			(start -1.016 -2.2352)
			(end 1.016 -2.2352)
			(stroke
				(width 0.1524)
				(type default)
			)
			(layer "F.SilkS")
		)
		(fp_line
			(start -1.016 -0.8382)
			(end -1.016 -2.2352)
			(stroke
				(width 0.1524)
				(type default)
			)
			(layer "F.SilkS")
		)
		(fp_line
			(start -1.016 2.2352)
			(end -1.016 0.8382)
			(stroke
				(width 0.1524)
				(type default)
			)
			(layer "F.SilkS")
		)
		(fp_line
			(start 1.016 -2.2352)
			(end 1.016 -0.8382)
			(stroke
				(width 0.1524)
				(type default)
			)
			(layer "F.SilkS")
		)
		(fp_line
			(start 1.016 0.8382)
			(end 1.016 2.2352)
			(stroke
				(width 0.1524)
				(type default)
			)
			(layer "F.SilkS")
		)
		(fp_line
			(start 1.016 2.2352)
			(end -1.016 2.2352)
			(stroke
				(width 0.1524)
				(type default)
			)
			(layer "F.SilkS")
		)
		(fp_rect
			(start -1.0922 2.3114)
			(end 1.0922 -2.3114)
			(stroke
				(width 0)
				(type default)
			)
			(fill no)
			(layer "F.CrtYd")
		)
		(fp_poly
			(pts
				(xy 1.0922 -2.3114) (xy 1.0922 2.3114) (xy -1.0922 2.3114) (xy -1.0922 -2.3114)
			)
			(stroke
				(width 0)
				(type default)
			)
			(fill no)
			(layer "F.Fab")
		)
		(pad "1" smd rect
			(at 0 -1.397)
			(size 1.651 1.27)
			(layers "F.Cu" "F.Mask" "F.Paste")
			(net "GND")
		)
		(pad "2" smd rect
			(at 0 1.397)
			(size 1.651 1.27)
			(layers "F.Cu" "F.Mask" "F.Paste")
			(net "SAS0_AVDD")
		)
	)
	(footprint ""
		(layer "F.Cu")
		(at 185.845704 -149.714966 180)
		(property "Reference" "R474"
			(at 0 0 180)
			(layer "F.SilkS")
			(hide yes)
			(effects
				(font
					(size 1.27 1.27)
				)
			)
		)
		(property "Value" "73K2R2F-GP"
			(at 0.064008 -3.993896 180)
			(unlocked yes)
			(layer "F.Fab")
			(hide yes)
			(effects
				(font
					(size 1.016 1.016)
					(thickness 0.1524)
				)
			)
		)
		(property "Device Type" "R402H16"
			(at 0.064008 -5.517896 180)
			(unlocked yes)
			(layer "F.Fab")
			(hide yes)
			(effects
				(font
					(size 1.016 1.016)
					(thickness 0.1524)
				)
			)
		)
		(duplicate_pad_numbers_are_jumpers no)
		(fp_line
			(start 0.508 -0.9398)
			(end -0.508 -0.9398)
			(stroke
				(width 0.1524)
				(type default)
			)
			(layer "F.SilkS")
		)
		(fp_line
			(start -0.508 -0.9398)
			(end -0.508 0.9398)
			(stroke
				(width 0.1524)
				(type default)
			)
			(layer "F.SilkS")
		)
		(fp_rect
			(start -0.508 0.9398)
			(end 0.508 -0.9398)
			(stroke
				(width 0)
				(type default)
			)
			(fill no)
			(layer "F.CrtYd")
		)
		(fp_rect
			(start -0.508 0.9398)
			(end 0.508 -0.9398)
			(stroke
				(width 0)
				(type default)
			)
			(fill no)
			(layer "F.Fab")
		)
		(pad "1" smd custom
			(at 0 -0.4445 180)
			(size 0.1397 0.1397)
			(layers "F.Cu" "F.Mask" "F.Paste")
			(net "P5V_VFB")
			(options
				(clearance outline)
				(anchor circle)
			)
			(primitives
				(gr_poly
					(pts
						(arc
							(start -0.1778 -0.2794)
							(mid -0.249642 -0.249642)
							(end -0.2794 -0.1778)
						)
						(arc
							(start -0.2794 0.1778)
							(mid -0.249642 0.249642)
							(end -0.1778 0.2794)
						)
						(arc
							(start 0.1778 0.2794)
							(mid 0.249642 0.249642)
							(end 0.2794 0.1778)
						)
						(arc
							(start 0.2794 -0.1778)
							(mid 0.249642 -0.249642)
							(end 0.1778 -0.2794)
						)
					)
					(width 0)
					(fill yes)
				)
			)
		)
		(pad "2" smd custom
			(at 0 0.4445 180)
			(size 0.1397 0.1397)
			(layers "F.Cu" "F.Mask" "F.Paste")
			(net "P5V_VFB_R")
			(options
				(clearance outline)
				(anchor circle)
			)
			(primitives
				(gr_poly
					(pts
						(arc
							(start -0.1778 -0.2794)
							(mid -0.249642 -0.249642)
							(end -0.2794 -0.1778)
						)
						(arc
							(start -0.2794 0.1778)
							(mid -0.249642 0.249642)
							(end -0.1778 0.2794)
						)
						(arc
							(start 0.1778 0.2794)
							(mid 0.249642 0.249642)
							(end 0.2794 0.1778)
						)
						(arc
							(start 0.2794 -0.1778)
							(mid 0.249642 -0.249642)
							(end 0.1778 -0.2794)
						)
					)
					(width 0)
					(fill yes)
				)
			)
		)
	)
	(footprint ""
		(layer "F.Cu")
		(at 192.02908 -32.13354 90)
		(property "Reference" "R39"
			(at 0 0 90)
			(layer "F.SilkS")
			(hide yes)
			(effects
				(font
					(size 1.27 1.27)
				)
			)
		)
		(property "Value" "1MR2F-GP"
			(at 0.064008 -3.993896 90)
			(unlocked yes)
			(layer "F.Fab")
			(hide yes)
			(effects
				(font
					(size 1.016 1.016)
					(thickness 0.1524)
				)
			)
		)
		(property "Device Type" "R402H16"
			(at 0.064008 -5.517896 90)
			(unlocked yes)
			(layer "F.Fab")
			(hide yes)
			(effects
				(font
					(size 1.016 1.016)
					(thickness 0.1524)
				)
			)
		)
		(duplicate_pad_numbers_are_jumpers no)
		(fp_line
			(start 0.508 -0.9398)
			(end -0.508 -0.9398)
			(stroke
				(width 0.1524)
				(type default)
			)
			(layer "F.SilkS")
		)
		(fp_line
			(start -0.508 -0.9398)
			(end -0.508 0.9398)
			(stroke
				(width 0.1524)
				(type default)
			)
			(layer "F.SilkS")
		)
		(fp_rect
			(start -0.508 0.9398)
			(end 0.508 -0.9398)
			(stroke
				(width 0)
				(type default)
			)
			(fill no)
			(layer "F.CrtYd")
		)
		(fp_rect
			(start -0.508 0.9398)
			(end 0.508 -0.9398)
			(stroke
				(width 0)
				(type default)
			)
			(fill no)
			(layer "F.Fab")
		)
		(pad "1" smd custom
			(at 0 -0.4445 90)
			(size 0.1397 0.1397)
			(layers "F.Cu" "F.Mask" "F.Paste")
			(net "EXT1_CONN_GND")
			(options
				(clearance outline)
				(anchor circle)
			)
			(primitives
				(gr_poly
					(pts
						(arc
							(start -0.1778 -0.2794)
							(mid -0.249642 -0.249642)
							(end -0.2794 -0.1778)
						)
						(arc
							(start -0.2794 0.1778)
							(mid -0.249642 0.249642)
							(end -0.1778 0.2794)
						)
						(arc
							(start 0.1778 0.2794)
							(mid 0.249642 0.249642)
							(end 0.2794 0.1778)
						)
						(arc
							(start 0.2794 -0.1778)
							(mid 0.249642 -0.249642)
							(end 0.1778 -0.2794)
						)
					)
					(width 0)
					(fill yes)
				)
			)
		)
		(pad "2" smd custom
			(at 0 0.4445 90)
			(size 0.1397 0.1397)
			(layers "F.Cu" "F.Mask" "F.Paste")
			(net "GND")
			(options
				(clearance outline)
				(anchor circle)
			)
			(primitives
				(gr_poly
					(pts
						(arc
							(start -0.1778 -0.2794)
							(mid -0.249642 -0.249642)
							(end -0.2794 -0.1778)
						)
						(arc
							(start -0.2794 0.1778)
							(mid -0.249642 0.249642)
							(end -0.1778 0.2794)
						)
						(arc
							(start 0.1778 0.2794)
							(mid 0.249642 0.249642)
							(end 0.2794 0.1778)
						)
						(arc
							(start 0.2794 -0.1778)
							(mid 0.249642 -0.249642)
							(end 0.1778 -0.2794)
						)
					)
					(width 0)
					(fill yes)
				)
			)
		)
	)
	(footprint ""
		(layer "F.Cu")
		(at 74.295 -137.922 -90)
		(property "Reference" "C32"
			(at 0 0 270)
			(layer "F.SilkS")
			(hide yes)
			(effects
				(font
					(size 1.27 1.27)
				)
			)
		)
		(property "Value" "SCD1U16V2KX-3GP"
			(at 1.1811 -2.7051 270)
			(unlocked yes)
			(layer "F.Fab")
			(hide yes)
			(effects
				(font
					(size 1.016 1.016)
					(thickness 0.1524)
				)
			)
		)
		(property "Device Type" "C402H22"
			(at 1.1811 -4.2291 270)
			(unlocked yes)
			(layer "F.Fab")
			(hide yes)
			(effects
				(font
					(size 1.016 1.016)
					(thickness 0.1524)
				)
			)
		)
		(duplicate_pad_numbers_are_jumpers no)
		(fp_rect
			(start -0.4318 0.9525)
			(end 0.4318 -0.9525)
			(stroke
				(width 0)
				(type default)
			)
			(fill no)
			(layer "F.CrtYd")
		)
		(fp_rect
			(start -0.4318 0.9525)
			(end 0.4318 -0.9525)
			(stroke
				(width 0)
				(type default)
			)
			(fill no)
			(layer "F.Fab")
		)
		(pad "1" smd custom
			(at 0 -0.4445 270)
			(size 0.1524 0.1524)
			(layers "F.Cu" "F.Mask" "F.Paste")
			(net "DEBUG_HDR_UART_SEL")
			(options
				(clearance outline)
				(anchor circle)
			)
			(primitives
				(gr_poly
					(pts
						(arc
							(start 0.3048 -0.2032)
							(mid 0.275042 -0.275042)
							(end 0.2032 -0.3048)
						)
						(arc
							(start -0.2032 -0.3048)
							(mid -0.275042 -0.275042)
							(end -0.3048 -0.2032)
						)
						(arc
							(start -0.3048 0.2032)
							(mid -0.275042 0.275042)
							(end -0.2032 0.3048)
						)
						(arc
							(start 0.2032 0.3048)
							(mid 0.275042 0.275042)
							(end 0.3048 0.2032)
						)
					)
					(width 0)
					(fill yes)
				)
			)
		)
		(pad "2" smd custom
			(at 0 0.4445 270)
			(size 0.1524 0.1524)
			(layers "F.Cu" "F.Mask" "F.Paste")
			(net "GND")
			(options
				(clearance outline)
				(anchor circle)
			)
			(primitives
				(gr_poly
					(pts
						(arc
							(start 0.3048 -0.2032)
							(mid 0.275042 -0.275042)
							(end 0.2032 -0.3048)
						)
						(arc
							(start -0.2032 -0.3048)
							(mid -0.275042 -0.275042)
							(end -0.3048 -0.2032)
						)
						(arc
							(start -0.3048 0.2032)
							(mid -0.275042 0.275042)
							(end -0.2032 0.3048)
						)
						(arc
							(start 0.2032 0.3048)
							(mid 0.275042 0.275042)
							(end 0.3048 0.2032)
						)
					)
					(width 0)
					(fill yes)
				)
			)
		)
	)
	(footprint ""
		(layer "F.Cu")
		(at 149.1742 -38.4556)
		(property "Reference" "TP178"
			(at 0 0 0)
			(layer "F.SilkS")
			(hide yes)
			(effects
				(font
					(size 1.27 1.27)
				)
			)
		)
		(property "Value" "TPAD28-2-GP"
			(at -0.0127 -1.6637 0)
			(unlocked yes)
			(layer "F.Fab")
			(hide yes)
			(effects
				(font
					(size 1.016 1.016)
					(thickness 0.1524)
				)
			)
		)
		(property "Device Type" "TPAD28"
			(at -0.0127 -3.1877 0)
			(unlocked yes)
			(layer "F.Fab")
			(hide yes)
			(effects
				(font
					(size 1.016 1.016)
					(thickness 0.1524)
				)
			)
		)
		(duplicate_pad_numbers_are_jumpers no)
		(fp_poly
			(pts
				(arc
					(start 0.3556 0)
					(mid -0.3556 0)
					(end 0.3556 0)
				)
			)
			(stroke
				(width 0)
				(type default)
			)
			(fill no)
			(layer "F.CrtYd")
		)
		(fp_poly
			(pts
				(arc
					(start 0.6096 0)
					(mid -0.6096 0)
					(end 0.6096 0)
				)
			)
			(stroke
				(width 0)
				(type default)
			)
			(fill no)
			(layer "F.Fab")
		)
		(pad "1" smd circle
			(at 0 0)
			(size 0.7112 0.7112)
			(layers "F.Cu" "F.Mask" "F.Paste")
			(net "ZDEF_EXTB_TP_A1")
		)
	)
	(footprint ""
		(layer "F.Cu")
		(at 34.294826 -181.57063 -90)
		(property "Reference" "PU2"
			(at 0 0 270)
			(layer "F.SilkS")
			(hide yes)
			(effects
				(font
					(size 1.27 1.27)
				)
			)
		)
		(property "Value" "TPS53318DQPR-GP"
			(at -5.022088 -6.851904 270)
			(unlocked yes)
			(layer "F.Fab")
			(hide yes)
			(effects
				(font
					(size 1.016 1.016)
					(thickness 0.1524)
				)
			)
		)
		(property "Device Type" "DFN22G6050-G6133H60"
			(at -5.022088 -8.375904 270)
			(unlocked yes)
			(layer "F.Fab")
			(hide yes)
			(effects
				(font
					(size 1.016 1.016)
					(thickness 0.1524)
				)
			)
		)
		(duplicate_pad_numbers_are_jumpers no)
		(fp_line
			(start -3.5052 3.5179)
			(end -2.2352 3.5179)
			(stroke
				(width 0.1524)
				(type default)
			)
			(layer "F.SilkS")
		)
		(fp_line
			(start 2.2352 3.5179)
			(end 3.5052 3.5179)
			(stroke
				(width 0.1524)
				(type default)
			)
			(layer "F.SilkS")
		)
		(fp_line
			(start 3.5052 3.5179)
			(end 3.5052 2.2479)
			(stroke
				(width 0.1524)
				(type default)
			)
			(layer "F.SilkS")
		)
		(fp_line
			(start -0.999998 3.262122)
			(end -0.999998 3.770122)
			(stroke
				(width 0.1524)
				(type default)
			)
			(layer "F.SilkS")
		)
		(fp_line
			(start 1.500124 3.262122)
			(end 1.500124 4.024122)
			(stroke
				(width 0.1524)
				(type default)
			)
			(layer "F.SilkS")
		)
		(fp_line
			(start -3.5052 2.2479)
			(end -3.5052 3.5179)
			(stroke
				(width 0.1524)
				(type default)
			)
			(layer "F.SilkS")
		)
		(fp_line
			(start -1.999996 -3.262122)
			(end -1.999996 -4.024122)
			(stroke
				(width 0.1524)
				(type default)
			)
			(layer "F.SilkS")
		)
		(fp_line
			(start 0.500126 -3.262122)
			(end 0.500126 -3.770122)
			(stroke
				(width 0.1524)
				(type default)
			)
			(layer "F.SilkS")
		)
		(fp_line
			(start -3.5052 -3.5179)
			(end -3.5052 -2.2479)
			(stroke
				(width 0.1524)
				(type default)
			)
			(layer "F.SilkS")
		)
		(fp_line
			(start -2.2352 -3.5179)
			(end -3.5052 -3.5179)
			(stroke
				(width 0.1524)
				(type default)
			)
			(layer "F.SilkS")
		)
		(fp_poly
			(pts
				(xy 3.5052 -3.5179) (xy 2.4765 -3.5179) (xy 3.5052 -2.4892)
			)
			(stroke
				(width 0)
				(type default)
			)
			(fill yes)
			(layer "F.SilkS")
		)
		(fp_rect
			(start -2.9972 2.5019)
			(end 2.9972 -2.5019)
			(stroke
				(width 0)
				(type default)
			)
			(fill no)
			(layer "F.CrtYd")
		)
		(fp_poly
			(pts
				(xy 3.556 -2.5019) (xy -2.9972 -2.5019) (xy -2.9972 2.5019) (xy 2.9972 2.5019) (xy 2.9972 -2.4892)
				(xy 3.556 -2.4892) (xy 3.556 3.5179) (xy -3.556 3.5179) (xy -3.556 -3.5179) (xy 3.556 -3.5179)
			)
			(stroke
				(width 0)
				(type default)
			)
			(fill no)
			(layer "F.CrtYd")
		)
		(fp_rect
			(start -3.556 3.5179)
			(end 3.556 -3.5179)
			(stroke
				(width 0)
				(type default)
			)
			(fill no)
			(layer "F.Fab")
		)
		(pad "1" smd rect
			(at 2.500122 -2.449322 270)
			(size 0.3048 1.1176)
			(layers "F.Cu" "F.Mask" "F.Paste")
			(net "P3V3_STBY_VFB")
		)
		(pad "2" smd rect
			(at 1.999996 -2.449322 270)
			(size 0.3048 1.1176)
			(layers "F.Cu" "F.Mask" "F.Paste")
			(net "P3V3_STBY_EN")
		)
		(pad "3" smd rect
			(at 1.500124 -2.449322 270)
			(size 0.3048 1.1176)
			(layers "F.Cu" "F.Mask" "F.Paste")
			(net "PWRGD_P3V3_STBY")
		)
		(pad "4" smd rect
			(at 0.999998 -2.449322 270)
			(size 0.3048 1.1176)
			(layers "F.Cu" "F.Mask" "F.Paste")
			(net "P3V3_VBST")
		)
		(pad "5" smd rect
			(at 0.500126 -2.449322 270)
			(size 0.3048 1.1176)
			(layers "F.Cu" "F.Mask" "F.Paste")
			(net "P3V3_STBY_ROVP")
		)
		(pad "6" smd rect
			(at 0 -2.449322 270)
			(size 0.3048 1.1176)
			(layers "F.Cu" "F.Mask" "F.Paste")
			(net "P3V3_STBY_LL")
		)
		(pad "7" smd rect
			(at -0.500126 -2.449322 270)
			(size 0.3048 1.1176)
			(layers "F.Cu" "F.Mask" "F.Paste")
			(net "P3V3_STBY_LL")
		)
		(pad "8" smd rect
			(at -0.999998 -2.449322 270)
			(size 0.3048 1.1176)
			(layers "F.Cu" "F.Mask" "F.Paste")
			(net "P3V3_STBY_LL")
		)
		(pad "9" smd rect
			(at -1.500124 -2.449322 270)
			(size 0.3048 1.1176)
			(layers "F.Cu" "F.Mask" "F.Paste")
			(net "P3V3_STBY_LL")
		)
		(pad "10" smd rect
			(at -1.999996 -2.449322 270)
			(size 0.3048 1.1176)
			(layers "F.Cu" "F.Mask" "F.Paste")
			(net "P3V3_STBY_LL")
		)
		(pad "11" smd rect
			(at -2.500122 -2.449322 270)
			(size 0.3048 1.1176)
			(layers "F.Cu" "F.Mask" "F.Paste")
			(net "P3V3_STBY_LL")
		)
		(pad "12" smd rect
			(at -2.500122 2.449322 270)
			(size 0.3048 1.1176)
			(layers "F.Cu" "F.Mask" "F.Paste")
			(net "P12V_STBY_VIN_PU2")
		)
		(pad "13" smd rect
			(at -1.999996 2.449322 270)
			(size 0.3048 1.1176)
			(layers "F.Cu" "F.Mask" "F.Paste")
			(net "P12V_STBY_VIN_PU2")
		)
		(pad "14" smd rect
			(at -1.500124 2.449322 270)
			(size 0.3048 1.1176)
			(layers "F.Cu" "F.Mask" "F.Paste")
			(net "P12V_STBY_VIN_PU2")
		)
		(pad "15" smd rect
			(at -0.999998 2.449322 270)
			(size 0.3048 1.1176)
			(layers "F.Cu" "F.Mask" "F.Paste")
			(net "P12V_STBY_VIN_PU2")
		)
		(pad "16" smd rect
			(at -0.500126 2.449322 270)
			(size 0.3048 1.1176)
			(layers "F.Cu" "F.Mask" "F.Paste")
			(net "P12V_STBY_VIN_PU2")
		)
		(pad "17" smd rect
			(at 0 2.449322 270)
			(size 0.3048 1.1176)
			(layers "F.Cu" "F.Mask" "F.Paste")
			(net "P12V_STBY_VIN_PU2")
		)
		(pad "18" smd rect
			(at 0.500126 2.449322 270)
			(size 0.3048 1.1176)
			(layers "F.Cu" "F.Mask" "F.Paste")
			(net "P3V3_STBY_VREG")
		)
		(pad "19" smd rect
			(at 0.999998 2.449322 270)
			(size 0.3048 1.1176)
			(layers "F.Cu" "F.Mask" "F.Paste")
			(net "P12V_STBY_VDD_PU2")
		)
		(pad "20" smd rect
			(at 1.500124 2.449322 270)
			(size 0.3048 1.1176)
			(layers "F.Cu" "F.Mask" "F.Paste")
			(net "P3V3_STBY_MODE")
		)
		(pad "21" smd rect
			(at 1.999996 2.449322 270)
			(size 0.3048 1.1176)
			(layers "F.Cu" "F.Mask" "F.Paste")
			(net "P3V3_STBY_TRIP")
		)
		(pad "22" smd rect
			(at 2.500122 2.449322 270)
			(size 0.3048 1.1176)
			(layers "F.Cu" "F.Mask" "F.Paste")
			(net "P3V3_STBY_RF")
		)
		(pad "23" smd custom
			(at 0 0 270)
			(size 0.83185 0.83185)
			(layers "F.Cu" "F.Mask" "F.Paste")
			(net "GND")
			(options
				(clearance outline)
				(anchor circle)
			)
			(primitives
				(gr_poly
					(pts
						(xy -2.7813 1.6637) (xy -2.7813 1.2954) (xy -3.048 1.2954) (xy -3.048 0.9525) (xy -2.7813 0.9525)
						(xy -2.7813 -0.9525) (xy -3.048 -0.9525) (xy -3.048 -1.2954) (xy -2.7813 -1.2954) (xy -2.7813 -1.6637)
						(xy 2.7813 -1.6637) (xy 2.7813 -1.2954) (xy 3.048 -1.2954) (xy 3.048 -0.9525) (xy 2.7813 -0.9525)
						(xy 2.7813 0.9525) (xy 3.048 0.9525) (xy 3.048 1.2954) (xy 2.7813 1.2954) (xy 2.7813 1.6637)
					)
					(width 0)
					(fill yes)
				)
			)
		)
	)
	(footprint ""
		(layer "F.Cu")
		(at 88.674194 -53.432456)
		(property "Reference" "PQ3"
			(at 0 0 0)
			(layer "F.SilkS")
			(hide yes)
			(effects
				(font
					(size 1.27 1.27)
				)
			)
		)
		(property "Value" "FDS8878-G-GP"
			(at -3.707384 -1.5367 0)
			(unlocked yes)
			(layer "F.Fab")
			(hide yes)
			(effects
				(font
					(size 1.016 1.016)
					(thickness 0.1524)
				)
			)
		)
		(property "Device Type" "SOIC8H69"
			(at -3.707384 -3.0607 0)
			(unlocked yes)
			(layer "F.Fab")
			(hide yes)
			(effects
				(font
					(size 1.016 1.016)
					(thickness 0.1524)
				)
			)
		)
		(duplicate_pad_numbers_are_jumpers no)
		(fp_line
			(start -2.7432 -1.4224)
			(end -2.7432 1.4224)
			(stroke
				(width 0.1524)
				(type default)
			)
			(layer "F.SilkS")
		)
		(fp_line
			(start -2.7432 1.4224)
			(end -2.6416 1.4224)
			(stroke
				(width 0.1524)
				(type default)
			)
			(layer "F.SilkS")
		)
		(fp_line
			(start -2.7432 1.4224)
			(end 2.1336 1.4224)
			(stroke
				(width 0.1524)
				(type default)
			)
			(layer "F.SilkS")
		)
		(fp_line
			(start -2.7178 -0.508)
			(end -2.1844 -0.0508)
			(stroke
				(width 0.1524)
				(type default)
			)
			(layer "F.SilkS")
		)
		(fp_line
			(start -2.6289 3.4417)
			(end -2.6289 1.4732)
			(stroke
				(width 0.381)
				(type default)
			)
			(layer "F.SilkS")
		)
		(fp_line
			(start -2.1844 -0.0508)
			(end -2.7178 0.508)
			(stroke
				(width 0.1524)
				(type default)
			)
			(layer "F.SilkS")
		)
		(fp_line
			(start 2.1336 -1.4224)
			(end -2.7432 -1.4224)
			(stroke
				(width 0.1524)
				(type default)
			)
			(layer "F.SilkS")
		)
		(fp_line
			(start 2.1336 1.4224)
			(end 2.1336 -1.4224)
			(stroke
				(width 0.1524)
				(type default)
			)
			(layer "F.SilkS")
		)
		(fp_poly
			(pts
				(xy -2.2098 -1.4224) (xy -2.2098 1.4224) (xy 2.2098 1.4224) (xy 2.2098 -1.4224)
			)
			(stroke
				(width 0)
				(type default)
			)
			(fill yes)
			(layer "F.SilkS")
		)
		(fp_rect
			(start -2.450084 2.999994)
			(end 2.450084 -2.999994)
			(stroke
				(width 0)
				(type default)
			)
			(fill no)
			(layer "F.CrtYd")
		)
		(fp_poly
			(pts
				(xy -2.8194 3.6322) (xy -2.8194 -3.6322) (xy 2.8194 -3.6322) (xy 2.8194 1.18364) (xy 2.450084 1.18364)
				(xy 2.450084 -2.999994) (xy -2.450084 -2.999994) (xy -2.450084 2.999994) (xy 2.450084 2.999994)
				(xy 2.450084 1.18618) (xy 2.8194 1.18618) (xy 2.8194 3.6322)
			)
			(stroke
				(width 0)
				(type default)
			)
			(fill no)
			(layer "F.CrtYd")
		)
		(fp_rect
			(start -2.8194 3.6322)
			(end 2.8194 -3.6322)
			(stroke
				(width 0)
				(type default)
			)
			(fill no)
			(layer "F.Fab")
		)
		(pad "1" smd rect
			(at -1.905 2.54)
			(size 0.635 1.651)
			(layers "F.Cu" "F.Mask" "F.Paste")
			(net "P3V3")
		)
		(pad "2" smd rect
			(at -0.635 2.54)
			(size 0.635 1.651)
			(layers "F.Cu" "F.Mask" "F.Paste")
			(net "P3V3")
		)
		(pad "3" smd rect
			(at 0.635 2.54)
			(size 0.635 1.651)
			(layers "F.Cu" "F.Mask" "F.Paste")
			(net "P3V3")
		)
		(pad "4" smd rect
			(at 1.905 2.54)
			(size 0.635 1.651)
			(layers "F.Cu" "F.Mask" "F.Paste")
			(net "PQ2_D")
		)
		(pad "5" smd rect
			(at 1.905 -2.54)
			(size 0.635 1.651)
			(layers "F.Cu" "F.Mask" "F.Paste")
			(net "P3V3_STBY")
		)
		(pad "6" smd rect
			(at 0.635 -2.54)
			(size 0.635 1.651)
			(layers "F.Cu" "F.Mask" "F.Paste")
			(net "P3V3_STBY")
		)
		(pad "7" smd rect
			(at -0.635 -2.54)
			(size 0.635 1.651)
			(layers "F.Cu" "F.Mask" "F.Paste")
			(net "P3V3_STBY")
		)
		(pad "8" smd rect
			(at -1.905 -2.54)
			(size 0.635 1.651)
			(layers "F.Cu" "F.Mask" "F.Paste")
			(net "P3V3_STBY")
		)
	)
	(footprint ""
		(layer "F.Cu")
		(at 90.59672 -149.190456)
		(property "Reference" "R25"
			(at 0 0 0)
			(layer "F.SilkS")
			(hide yes)
			(effects
				(font
					(size 1.27 1.27)
				)
			)
		)
		(property "Value" "15KR2F-GP"
			(at 0.064008 -3.993896 0)
			(unlocked yes)
			(layer "F.Fab")
			(hide yes)
			(effects
				(font
					(size 1.016 1.016)
					(thickness 0.1524)
				)
			)
		)
		(property "Device Type" "R402H16"
			(at 0.064008 -5.517896 0)
			(unlocked yes)
			(layer "F.Fab")
			(hide yes)
			(effects
				(font
					(size 1.016 1.016)
					(thickness 0.1524)
				)
			)
		)
		(duplicate_pad_numbers_are_jumpers no)
		(fp_line
			(start -0.508 -0.9398)
			(end -0.508 0.9398)
			(stroke
				(width 0.1524)
				(type default)
			)
			(layer "F.SilkS")
		)
		(fp_line
			(start 0.508 -0.9398)
			(end -0.508 -0.9398)
			(stroke
				(width 0.1524)
				(type default)
			)
			(layer "F.SilkS")
		)
		(fp_rect
			(start -0.508 0.9398)
			(end 0.508 -0.9398)
			(stroke
				(width 0)
				(type default)
			)
			(fill no)
			(layer "F.CrtYd")
		)
		(fp_rect
			(start -0.508 0.9398)
			(end 0.508 -0.9398)
			(stroke
				(width 0)
				(type default)
			)
			(fill no)
			(layer "F.Fab")
		)
		(pad "1" smd custom
			(at 0 -0.4445)
			(size 0.1397 0.1397)
			(layers "F.Cu" "F.Mask" "F.Paste")
			(net "USB_OCS_N1")
			(options
				(clearance outline)
				(anchor circle)
			)
			(primitives
				(gr_poly
					(pts
						(arc
							(start -0.1778 -0.2794)
							(mid -0.249642 -0.249642)
							(end -0.2794 -0.1778)
						)
						(arc
							(start -0.2794 0.1778)
							(mid -0.249642 0.249642)
							(end -0.1778 0.2794)
						)
						(arc
							(start 0.1778 0.2794)
							(mid 0.249642 0.249642)
							(end 0.2794 0.1778)
						)
						(arc
							(start 0.2794 -0.1778)
							(mid 0.249642 -0.249642)
							(end 0.1778 -0.2794)
						)
					)
					(width 0)
					(fill yes)
				)
			)
		)
		(pad "2" smd custom
			(at 0 0.4445)
			(size 0.1397 0.1397)
			(layers "F.Cu" "F.Mask" "F.Paste")
			(net "GND")
			(options
				(clearance outline)
				(anchor circle)
			)
			(primitives
				(gr_poly
					(pts
						(arc
							(start -0.1778 -0.2794)
							(mid -0.249642 -0.249642)
							(end -0.2794 -0.1778)
						)
						(arc
							(start -0.2794 0.1778)
							(mid -0.249642 0.249642)
							(end -0.1778 0.2794)
						)
						(arc
							(start 0.1778 0.2794)
							(mid 0.249642 0.249642)
							(end 0.2794 0.1778)
						)
						(arc
							(start 0.2794 -0.1778)
							(mid 0.249642 -0.249642)
							(end 0.1778 -0.2794)
						)
					)
					(width 0)
					(fill yes)
				)
			)
		)
	)
	(footprint ""
		(layer "F.Cu")
		(at 38.5826 -161.4424)
		(property "Reference" "R299"
			(at 0 0 0)
			(layer "F.SilkS")
			(hide yes)
			(effects
				(font
					(size 1.27 1.27)
				)
			)
		)
		(property "Value" "4K7R2F-GP"
			(at 0.064008 -3.993896 0)
			(unlocked yes)
			(layer "F.Fab")
			(hide yes)
			(effects
				(font
					(size 1.016 1.016)
					(thickness 0.1524)
				)
			)
		)
		(property "Device Type" "R402H16"
			(at 0.064008 -5.517896 0)
			(unlocked yes)
			(layer "F.Fab")
			(hide yes)
			(effects
				(font
					(size 1.016 1.016)
					(thickness 0.1524)
				)
			)
		)
		(duplicate_pad_numbers_are_jumpers no)
		(fp_line
			(start -0.508 -0.9398)
			(end -0.508 0.9398)
			(stroke
				(width 0.1524)
				(type default)
			)
			(layer "F.SilkS")
		)
		(fp_line
			(start 0.508 -0.9398)
			(end -0.508 -0.9398)
			(stroke
				(width 0.1524)
				(type default)
			)
			(layer "F.SilkS")
		)
		(fp_rect
			(start -0.508 0.9398)
			(end 0.508 -0.9398)
			(stroke
				(width 0)
				(type default)
			)
			(fill no)
			(layer "F.CrtYd")
		)
		(fp_rect
			(start -0.508 0.9398)
			(end 0.508 -0.9398)
			(stroke
				(width 0)
				(type default)
			)
			(fill no)
			(layer "F.Fab")
		)
		(pad "1" smd custom
			(at 0 -0.4445)
			(size 0.1397 0.1397)
			(layers "F.Cu" "F.Mask" "F.Paste")
			(net "P3V3_STBY")
			(options
				(clearance outline)
				(anchor circle)
			)
			(primitives
				(gr_poly
					(pts
						(arc
							(start -0.1778 -0.2794)
							(mid -0.249642 -0.249642)
							(end -0.2794 -0.1778)
						)
						(arc
							(start -0.2794 0.1778)
							(mid -0.249642 0.249642)
							(end -0.1778 0.2794)
						)
						(arc
							(start 0.1778 0.2794)
							(mid 0.249642 0.249642)
							(end 0.2794 0.1778)
						)
						(arc
							(start 0.2794 -0.1778)
							(mid 0.249642 -0.249642)
							(end 0.1778 -0.2794)
						)
					)
					(width 0)
					(fill yes)
				)
			)
		)
		(pad "2" smd custom
			(at 0 0.4445)
			(size 0.1397 0.1397)
			(layers "F.Cu" "F.Mask" "F.Paste")
			(net "UART_BMC_COMP_IN_RX")
			(options
				(clearance outline)
				(anchor circle)
			)
			(primitives
				(gr_poly
					(pts
						(arc
							(start -0.1778 -0.2794)
							(mid -0.249642 -0.249642)
							(end -0.2794 -0.1778)
						)
						(arc
							(start -0.2794 0.1778)
							(mid -0.249642 0.249642)
							(end -0.1778 0.2794)
						)
						(arc
							(start 0.1778 0.2794)
							(mid 0.249642 0.249642)
							(end 0.2794 0.1778)
						)
						(arc
							(start 0.2794 -0.1778)
							(mid 0.249642 -0.249642)
							(end 0.1778 -0.2794)
						)
					)
					(width 0)
					(fill yes)
				)
			)
		)
	)
	(footprint ""
		(layer "F.Cu")
		(at 180.42382 -124.60478 180)
		(property "Reference" "D5"
			(at 0 0 180)
			(layer "F.SilkS")
			(hide yes)
			(effects
				(font
					(size 1.27 1.27)
				)
			)
		)
		(property "Value" "SMF15A-GP"
			(at -2.0955 1.2192 180)
			(unlocked yes)
			(layer "F.Fab")
			(hide yes)
			(effects
				(font
					(size 1.016 1.016)
					(thickness 0.1524)
				)
			)
		)
		(property "Device Type" "SOD123AK-2H43"
			(at -2.0955 -0.3048 180)
			(unlocked yes)
			(layer "F.Fab")
			(hide yes)
			(effects
				(font
					(size 1.016 1.016)
					(thickness 0.1524)
				)
			)
		)
		(duplicate_pad_numbers_are_jumpers no)
		(fp_line
			(start 1.1557 2.921)
			(end -1.1557 2.921)
			(stroke
				(width 0.508)
				(type default)
			)
			(layer "F.SilkS")
		)
		(fp_line
			(start 1.1557 2.7686)
			(end 1.1557 -2.7686)
			(stroke
				(width 0.1524)
				(type default)
			)
			(layer "F.SilkS")
		)
		(fp_line
			(start 1.1557 -2.7686)
			(end -1.1557 -2.7686)
			(stroke
				(width 0.1524)
				(type default)
			)
			(layer "F.SilkS")
		)
		(fp_line
			(start -1.1557 2.7686)
			(end 1.1557 2.7686)
			(stroke
				(width 0.1524)
				(type default)
			)
			(layer "F.SilkS")
		)
		(fp_line
			(start -1.1557 -2.7686)
			(end -1.1557 2.7686)
			(stroke
				(width 0.1524)
				(type default)
			)
			(layer "F.SilkS")
		)
		(fp_poly
			(pts
				(xy -0.4572 1.8669) (xy -0.4572 1.397) (xy -0.9017 1.397) (xy -0.9017 -1.397) (xy -0.4572 -1.397)
				(xy -0.4572 -1.8669) (xy 0.4572 -1.8669) (xy 0.4572 -1.397) (xy 0.9017 -1.397) (xy 0.9017 1.397)
				(xy 0.4572 1.397) (xy 0.4572 1.8669)
			)
			(stroke
				(width 0)
				(type default)
			)
			(fill no)
			(layer "F.CrtYd")
		)
		(fp_poly
			(pts
				(xy -1.4097 2.8448) (xy -1.4097 -2.8448) (xy 1.4097 -2.8448) (xy 1.4097 1.3716) (xy 0.9017 1.3716)
				(xy 0.9017 -1.397) (xy 0.4572 -1.397) (xy 0.4572 -1.8669) (xy -0.4572 -1.8669) (xy -0.4572 -1.397)
				(xy -0.9017 -1.397) (xy -0.9017 1.397) (xy -0.4572 1.397) (xy -0.4572 1.8669) (xy 0.4572 1.8669)
				(xy 0.4572 1.397) (xy 0.9017 1.397) (xy 0.9017 1.3843) (xy 1.4097 1.3843) (xy 1.4097 2.8448)
			)
			(stroke
				(width 0)
				(type default)
			)
			(fill no)
			(layer "F.CrtYd")
		)
		(fp_rect
			(start -1.4097 2.8448)
			(end 1.4097 -2.8448)
			(stroke
				(width 0)
				(type default)
			)
			(fill no)
			(layer "F.Fab")
		)
		(pad "A" smd rect
			(at 0 -1.75768 180)
			(size 1.143 1.4986)
			(layers "F.Cu" "F.Mask" "F.Paste")
			(net "P1V8_EN")
		)
		(pad "K" smd rect
			(at 0 1.75768 180)
			(size 1.143 1.4986)
			(layers "F.Cu" "F.Mask" "F.Paste")
			(net "P3V3_PG")
		)
	)
	(footprint ""
		(layer "F.Cu")
		(at 79.67218 -178.479196 180)
		(property "Reference" "C193"
			(at 0 0 180)
			(layer "F.SilkS")
			(hide yes)
			(effects
				(font
					(size 1.27 1.27)
				)
			)
		)
		(property "Value" "SC10U6D3V5KX-4GP"
			(at -0.0762 -6.1214 180)
			(unlocked yes)
			(layer "F.Fab")
			(hide yes)
			(effects
				(font
					(size 1.016 1.016)
					(thickness 0.1524)
				)
			)
		)
		(property "Device Type" "C805H58"
			(at -0.0762 -8.1534 180)
			(unlocked yes)
			(layer "F.Fab")
			(hide yes)
			(effects
				(font
					(size 1.016 1.016)
					(thickness 0.1524)
				)
			)
		)
		(duplicate_pad_numbers_are_jumpers no)
		(fp_line
			(start 0.635 0)
			(end -0.635 0)
			(stroke
				(width 0.508)
				(type default)
			)
			(layer "F.SilkS")
		)
		(fp_rect
			(start -0.9652 1.778)
			(end 0.9652 -1.778)
			(stroke
				(width 0)
				(type default)
			)
			(fill no)
			(layer "F.CrtYd")
		)
		(fp_poly
			(pts
				(xy -0.9652 -1.778) (xy 0.9652 -1.778) (xy 0.9652 1.778) (xy -0.9652 1.778)
			)
			(stroke
				(width 0)
				(type default)
			)
			(fill no)
			(layer "F.Fab")
		)
		(pad "1" smd rect
			(at 0 -0.9652 180)
			(size 1.397 1.143)
			(layers "F.Cu" "F.Mask" "F.Paste")
			(net "TPS74801_P2V5_STBY_OUT")
		)
		(pad "2" smd rect
			(at 0 0.9652 180)
			(size 1.397 1.143)
			(layers "F.Cu" "F.Mask" "F.Paste")
			(net "GND")
		)
	)
	(footprint ""
		(layer "F.Cu")
		(at 121.2342 -16.002 180)
		(property "Reference" "C129"
			(at 0 0 180)
			(layer "F.SilkS")
			(hide yes)
			(effects
				(font
					(size 1.27 1.27)
				)
			)
		)
		(property "Value" "SC1KP50V2KX-1GP"
			(at 1.1811 -2.7051 180)
			(unlocked yes)
			(layer "F.Fab")
			(hide yes)
			(effects
				(font
					(size 1.016 1.016)
					(thickness 0.1524)
				)
			)
		)
		(property "Device Type" "C402H22"
			(at 1.1811 -4.2291 180)
			(unlocked yes)
			(layer "F.Fab")
			(hide yes)
			(effects
				(font
					(size 1.016 1.016)
					(thickness 0.1524)
				)
			)
		)
		(duplicate_pad_numbers_are_jumpers no)
		(fp_rect
			(start -0.4318 0.9525)
			(end 0.4318 -0.9525)
			(stroke
				(width 0)
				(type default)
			)
			(fill no)
			(layer "F.CrtYd")
		)
		(fp_rect
			(start -0.4318 0.9525)
			(end 0.4318 -0.9525)
			(stroke
				(width 0)
				(type default)
			)
			(fill no)
			(layer "F.Fab")
		)
		(pad "1" smd custom
			(at 0 -0.4445 180)
			(size 0.1524 0.1524)
			(layers "F.Cu" "F.Mask" "F.Paste")
			(net "MB0_TEMP")
			(options
				(clearance outline)
				(anchor circle)
			)
			(primitives
				(gr_poly
					(pts
						(arc
							(start 0.3048 -0.2032)
							(mid 0.275042 -0.275042)
							(end 0.2032 -0.3048)
						)
						(arc
							(start -0.2032 -0.3048)
							(mid -0.275042 -0.275042)
							(end -0.3048 -0.2032)
						)
						(arc
							(start -0.3048 0.2032)
							(mid -0.275042 0.275042)
							(end -0.2032 0.3048)
						)
						(arc
							(start 0.2032 0.3048)
							(mid 0.275042 0.275042)
							(end 0.3048 0.2032)
						)
					)
					(width 0)
					(fill yes)
				)
			)
		)
		(pad "2" smd custom
			(at 0 0.4445 180)
			(size 0.1524 0.1524)
			(layers "F.Cu" "F.Mask" "F.Paste")
			(net "GND")
			(options
				(clearance outline)
				(anchor circle)
			)
			(primitives
				(gr_poly
					(pts
						(arc
							(start 0.3048 -0.2032)
							(mid 0.275042 -0.275042)
							(end 0.2032 -0.3048)
						)
						(arc
							(start -0.2032 -0.3048)
							(mid -0.275042 -0.275042)
							(end -0.3048 -0.2032)
						)
						(arc
							(start -0.3048 0.2032)
							(mid -0.275042 0.275042)
							(end -0.2032 0.3048)
						)
						(arc
							(start 0.2032 0.3048)
							(mid 0.275042 0.275042)
							(end 0.3048 0.2032)
						)
					)
					(width 0)
					(fill yes)
				)
			)
		)
	)
	(footprint ""
		(layer "F.Cu")
		(at 205.1304 -120.269 -90)
		(property "Reference" "R544"
			(at 0 0 270)
			(layer "F.SilkS")
			(hide yes)
			(effects
				(font
					(size 1.27 1.27)
				)
			)
		)
		(property "Value" "4K22R2F-GP"
			(at 0.064008 -3.993896 270)
			(unlocked yes)
			(layer "F.Fab")
			(hide yes)
			(effects
				(font
					(size 1.016 1.016)
					(thickness 0.1524)
				)
			)
		)
		(property "Device Type" "R402H16"
			(at 0.064008 -5.517896 270)
			(unlocked yes)
			(layer "F.Fab")
			(hide yes)
			(effects
				(font
					(size 1.016 1.016)
					(thickness 0.1524)
				)
			)
		)
		(duplicate_pad_numbers_are_jumpers no)
		(fp_line
			(start -0.508 -0.9398)
			(end -0.508 0.9398)
			(stroke
				(width 0.1524)
				(type default)
			)
			(layer "F.SilkS")
		)
		(fp_line
			(start 0.508 -0.9398)
			(end -0.508 -0.9398)
			(stroke
				(width 0.1524)
				(type default)
			)
			(layer "F.SilkS")
		)
		(fp_rect
			(start -0.508 0.9398)
			(end 0.508 -0.9398)
			(stroke
				(width 0)
				(type default)
			)
			(fill no)
			(layer "F.CrtYd")
		)
		(fp_rect
			(start -0.508 0.9398)
			(end 0.508 -0.9398)
			(stroke
				(width 0)
				(type default)
			)
			(fill no)
			(layer "F.Fab")
		)
		(pad "1" smd custom
			(at 0 -0.4445 270)
			(size 0.1397 0.1397)
			(layers "F.Cu" "F.Mask" "F.Paste")
			(net "P1V5_OUT")
			(options
				(clearance outline)
				(anchor circle)
			)
			(primitives
				(gr_poly
					(pts
						(arc
							(start -0.1778 -0.2794)
							(mid -0.249642 -0.249642)
							(end -0.2794 -0.1778)
						)
						(arc
							(start -0.2794 0.1778)
							(mid -0.249642 0.249642)
							(end -0.1778 0.2794)
						)
						(arc
							(start 0.1778 0.2794)
							(mid 0.249642 0.249642)
							(end 0.2794 0.1778)
						)
						(arc
							(start 0.2794 -0.1778)
							(mid 0.249642 -0.249642)
							(end 0.1778 -0.2794)
						)
					)
					(width 0)
					(fill yes)
				)
			)
		)
		(pad "2" smd custom
			(at 0 0.4445 270)
			(size 0.1397 0.1397)
			(layers "F.Cu" "F.Mask" "F.Paste")
			(net "TPS74801_P1V5_FB")
			(options
				(clearance outline)
				(anchor circle)
			)
			(primitives
				(gr_poly
					(pts
						(arc
							(start -0.1778 -0.2794)
							(mid -0.249642 -0.249642)
							(end -0.2794 -0.1778)
						)
						(arc
							(start -0.2794 0.1778)
							(mid -0.249642 0.249642)
							(end -0.1778 0.2794)
						)
						(arc
							(start 0.1778 0.2794)
							(mid 0.249642 0.249642)
							(end 0.2794 0.1778)
						)
						(arc
							(start 0.2794 -0.1778)
							(mid 0.249642 -0.249642)
							(end 0.1778 -0.2794)
						)
					)
					(width 0)
					(fill yes)
				)
			)
		)
	)
	(footprint ""
		(layer "F.Cu")
		(at 28.194 -156.718 -90)
		(property "Reference" "R786"
			(at 0 0 270)
			(layer "F.SilkS")
			(hide yes)
			(effects
				(font
					(size 1.27 1.27)
				)
			)
		)
		(property "Value" "0R2J-2-GP"
			(at 0.064008 -3.993896 270)
			(unlocked yes)
			(layer "F.Fab")
			(hide yes)
			(effects
				(font
					(size 1.016 1.016)
					(thickness 0.1524)
				)
			)
		)
		(property "Device Type" "R402H16"
			(at 0.064008 -5.517896 270)
			(unlocked yes)
			(layer "F.Fab")
			(hide yes)
			(effects
				(font
					(size 1.016 1.016)
					(thickness 0.1524)
				)
			)
		)
		(duplicate_pad_numbers_are_jumpers no)
		(fp_line
			(start -0.508 -0.9398)
			(end -0.508 0.9398)
			(stroke
				(width 0.1524)
				(type default)
			)
			(layer "F.SilkS")
		)
		(fp_line
			(start 0.508 -0.9398)
			(end -0.508 -0.9398)
			(stroke
				(width 0.1524)
				(type default)
			)
			(layer "F.SilkS")
		)
		(fp_rect
			(start -0.508 0.9398)
			(end 0.508 -0.9398)
			(stroke
				(width 0)
				(type default)
			)
			(fill no)
			(layer "F.CrtYd")
		)
		(fp_rect
			(start -0.508 0.9398)
			(end 0.508 -0.9398)
			(stroke
				(width 0)
				(type default)
			)
			(fill no)
			(layer "F.Fab")
		)
		(pad "1" smd custom
			(at 0 -0.4445 270)
			(size 0.1397 0.1397)
			(layers "F.Cu" "F.Mask" "F.Paste")
			(net "FLA0_WP_N_R")
			(options
				(clearance outline)
				(anchor circle)
			)
			(primitives
				(gr_poly
					(pts
						(arc
							(start -0.1778 -0.2794)
							(mid -0.249642 -0.249642)
							(end -0.2794 -0.1778)
						)
						(arc
							(start -0.2794 0.1778)
							(mid -0.249642 0.249642)
							(end -0.1778 0.2794)
						)
						(arc
							(start 0.1778 0.2794)
							(mid 0.249642 0.249642)
							(end 0.2794 0.1778)
						)
						(arc
							(start 0.2794 -0.1778)
							(mid 0.249642 -0.249642)
							(end 0.1778 -0.2794)
						)
					)
					(width 0)
					(fill yes)
				)
			)
		)
		(pad "2" smd custom
			(at 0 0.4445 270)
			(size 0.1397 0.1397)
			(layers "F.Cu" "F.Mask" "F.Paste")
			(net "FLA0_WP_N")
			(options
				(clearance outline)
				(anchor circle)
			)
			(primitives
				(gr_poly
					(pts
						(arc
							(start -0.1778 -0.2794)
							(mid -0.249642 -0.249642)
							(end -0.2794 -0.1778)
						)
						(arc
							(start -0.2794 0.1778)
							(mid -0.249642 0.249642)
							(end -0.1778 0.2794)
						)
						(arc
							(start 0.1778 0.2794)
							(mid 0.249642 0.249642)
							(end 0.2794 0.1778)
						)
						(arc
							(start 0.2794 -0.1778)
							(mid 0.249642 -0.249642)
							(end 0.1778 -0.2794)
						)
					)
					(width 0)
					(fill yes)
				)
			)
		)
	)
	(footprint ""
		(layer "F.Cu")
		(at 175.8569 -124.387864 -90)
		(property "Reference" "Q6"
			(at 0 0 270)
			(layer "F.SilkS")
			(hide yes)
			(effects
				(font
					(size 1.27 1.27)
				)
			)
		)
		(property "Value" "2N7002K-1-GP"
			(at 0.127 -8.9662 270)
			(unlocked yes)
			(layer "F.Fab")
			(hide yes)
			(effects
				(font
					(size 1.016 1.016)
					(thickness 0.1524)
				)
			)
		)
		(property "Device Type" "SOT23DGS2D4H44"
			(at 0.127 -10.4902 270)
			(unlocked yes)
			(layer "F.Fab")
			(hide yes)
			(effects
				(font
					(size 1.016 1.016)
					(thickness 0.1524)
				)
			)
		)
		(duplicate_pad_numbers_are_jumpers no)
		(fp_line
			(start -1.651 1.778)
			(end 1.651 1.778)
			(stroke
				(width 0.1524)
				(type default)
			)
			(layer "F.SilkS")
		)
		(fp_line
			(start 1.651 1.778)
			(end 1.651 -1.778)
			(stroke
				(width 0.1524)
				(type default)
			)
			(layer "F.SilkS")
		)
		(fp_line
			(start -1.651 -1.778)
			(end -1.651 1.778)
			(stroke
				(width 0.1524)
				(type default)
			)
			(layer "F.SilkS")
		)
		(fp_line
			(start 1.651 -1.778)
			(end -1.651 -1.778)
			(stroke
				(width 0.1524)
				(type default)
			)
			(layer "F.SilkS")
		)
		(fp_poly
			(pts
				(xy -1.778 1.8796) (xy -1.778 -1.8796) (xy 1.778 -1.8796) (xy 1.778 1.8796)
			)
			(stroke
				(width 0)
				(type default)
			)
			(fill no)
			(layer "F.CrtYd")
		)
		(fp_poly
			(pts
				(xy -1.778 1.8796) (xy -1.778 -1.8796) (xy 1.778 -1.8796) (xy 1.778 1.8796)
			)
			(stroke
				(width 0)
				(type default)
			)
			(fill no)
			(layer "F.Fab")
		)
		(pad "D" smd custom
			(at 0 -0.9525 270)
			(size 0.1905 0.1905)
			(layers "F.Cu" "F.Mask" "F.Paste")
			(net "P3V3_PG")
			(options
				(clearance outline)
				(anchor circle)
			)
			(primitives
				(gr_poly
					(pts
						(arc
							(start -0.1778 0.5715)
							(mid -0.321484 0.511984)
							(end -0.381 0.3683)
						)
						(arc
							(start -0.381 -0.3683)
							(mid -0.321484 -0.511984)
							(end -0.1778 -0.5715)
						)
						(arc
							(start 0.1778 -0.5715)
							(mid 0.321484 -0.511984)
							(end 0.381 -0.3683)
						)
						(arc
							(start 0.381 0.3683)
							(mid 0.321484 0.511984)
							(end 0.1778 0.5715)
						)
					)
					(width 0)
					(fill yes)
				)
			)
		)
		(pad "G" smd custom
			(at -0.98425 0.9525 270)
			(size 0.1905 0.1905)
			(layers "F.Cu" "F.Mask" "F.Paste")
			(net "Q6_G")
			(options
				(clearance outline)
				(anchor circle)
			)
			(primitives
				(gr_poly
					(pts
						(arc
							(start -0.1778 0.5715)
							(mid -0.321484 0.511984)
							(end -0.381 0.3683)
						)
						(arc
							(start -0.381 -0.3683)
							(mid -0.321484 -0.511984)
							(end -0.1778 -0.5715)
						)
						(arc
							(start 0.1778 -0.5715)
							(mid 0.321484 -0.511984)
							(end 0.381 -0.3683)
						)
						(arc
							(start 0.381 0.3683)
							(mid 0.321484 0.511984)
							(end 0.1778 0.5715)
						)
					)
					(width 0)
					(fill yes)
				)
			)
		)
		(pad "S" smd custom
			(at 0.98425 0.9525 270)
			(size 0.1905 0.1905)
			(layers "F.Cu" "F.Mask" "F.Paste")
			(net "GND")
			(options
				(clearance outline)
				(anchor circle)
			)
			(primitives
				(gr_poly
					(pts
						(arc
							(start -0.1778 0.5715)
							(mid -0.321484 0.511984)
							(end -0.381 0.3683)
						)
						(arc
							(start -0.381 -0.3683)
							(mid -0.321484 -0.511984)
							(end -0.1778 -0.5715)
						)
						(arc
							(start 0.1778 -0.5715)
							(mid 0.321484 -0.511984)
							(end 0.381 -0.3683)
						)
						(arc
							(start 0.381 0.3683)
							(mid 0.321484 0.511984)
							(end 0.1778 0.5715)
						)
					)
					(width 0)
					(fill yes)
				)
			)
		)
	)
	(footprint ""
		(layer "F.Cu")
		(at 10.771124 -135.285988 90)
		(property "Reference" "R224"
			(at 0 0 90)
			(layer "F.SilkS")
			(hide yes)
			(effects
				(font
					(size 1.27 1.27)
				)
			)
		)
		(property "Value" "4K7R2F-GP"
			(at 0.064008 -3.993896 90)
			(unlocked yes)
			(layer "F.Fab")
			(hide yes)
			(effects
				(font
					(size 1.016 1.016)
					(thickness 0.1524)
				)
			)
		)
		(property "Device Type" "R402H16"
			(at 0.064008 -5.517896 90)
			(unlocked yes)
			(layer "F.Fab")
			(hide yes)
			(effects
				(font
					(size 1.016 1.016)
					(thickness 0.1524)
				)
			)
		)
		(duplicate_pad_numbers_are_jumpers no)
		(fp_line
			(start 0.508 -0.9398)
			(end -0.508 -0.9398)
			(stroke
				(width 0.1524)
				(type default)
			)
			(layer "F.SilkS")
		)
		(fp_line
			(start -0.508 -0.9398)
			(end -0.508 0.9398)
			(stroke
				(width 0.1524)
				(type default)
			)
			(layer "F.SilkS")
		)
		(fp_rect
			(start -0.508 0.9398)
			(end 0.508 -0.9398)
			(stroke
				(width 0)
				(type default)
			)
			(fill no)
			(layer "F.CrtYd")
		)
		(fp_rect
			(start -0.508 0.9398)
			(end 0.508 -0.9398)
			(stroke
				(width 0)
				(type default)
			)
			(fill no)
			(layer "F.Fab")
		)
		(pad "1" smd custom
			(at 0 -0.4445 90)
			(size 0.1397 0.1397)
			(layers "F.Cu" "F.Mask" "F.Paste")
			(net "MEM_PAR")
			(options
				(clearance outline)
				(anchor circle)
			)
			(primitives
				(gr_poly
					(pts
						(arc
							(start -0.1778 -0.2794)
							(mid -0.249642 -0.249642)
							(end -0.2794 -0.1778)
						)
						(arc
							(start -0.2794 0.1778)
							(mid -0.249642 0.249642)
							(end -0.1778 0.2794)
						)
						(arc
							(start 0.1778 0.2794)
							(mid 0.249642 0.249642)
							(end 0.2794 0.1778)
						)
						(arc
							(start 0.2794 -0.1778)
							(mid 0.249642 -0.249642)
							(end 0.1778 -0.2794)
						)
					)
					(width 0)
					(fill yes)
				)
			)
		)
		(pad "2" smd custom
			(at 0 0.4445 90)
			(size 0.1397 0.1397)
			(layers "F.Cu" "F.Mask" "F.Paste")
			(net "P1V2_STBY")
			(options
				(clearance outline)
				(anchor circle)
			)
			(primitives
				(gr_poly
					(pts
						(arc
							(start -0.1778 -0.2794)
							(mid -0.249642 -0.249642)
							(end -0.2794 -0.1778)
						)
						(arc
							(start -0.2794 0.1778)
							(mid -0.249642 0.249642)
							(end -0.1778 0.2794)
						)
						(arc
							(start 0.1778 0.2794)
							(mid 0.249642 0.249642)
							(end 0.2794 0.1778)
						)
						(arc
							(start 0.2794 -0.1778)
							(mid 0.249642 -0.249642)
							(end 0.1778 -0.2794)
						)
					)
					(width 0)
					(fill yes)
				)
			)
		)
	)
	(footprint ""
		(layer "F.Cu")
		(at 174.560738 -71.55942 90)
		(property "Reference" "R587"
			(at 0 0 90)
			(layer "F.SilkS")
			(hide yes)
			(effects
				(font
					(size 1.27 1.27)
				)
			)
		)
		(property "Value" "2K2R2F-GP"
			(at 0.064008 -3.993896 90)
			(unlocked yes)
			(layer "F.Fab")
			(hide yes)
			(effects
				(font
					(size 1.016 1.016)
					(thickness 0.1524)
				)
			)
		)
		(property "Device Type" "R402H16"
			(at 0.064008 -5.517896 90)
			(unlocked yes)
			(layer "F.Fab")
			(hide yes)
			(effects
				(font
					(size 1.016 1.016)
					(thickness 0.1524)
				)
			)
		)
		(duplicate_pad_numbers_are_jumpers no)
		(fp_line
			(start 0.508 -0.9398)
			(end -0.508 -0.9398)
			(stroke
				(width 0.1524)
				(type default)
			)
			(layer "F.SilkS")
		)
		(fp_line
			(start -0.508 -0.9398)
			(end -0.508 0.9398)
			(stroke
				(width 0.1524)
				(type default)
			)
			(layer "F.SilkS")
		)
		(fp_rect
			(start -0.508 0.9398)
			(end 0.508 -0.9398)
			(stroke
				(width 0)
				(type default)
			)
			(fill no)
			(layer "F.CrtYd")
		)
		(fp_rect
			(start -0.508 0.9398)
			(end 0.508 -0.9398)
			(stroke
				(width 0)
				(type default)
			)
			(fill no)
			(layer "F.Fab")
		)
		(pad "1" smd custom
			(at 0 -0.4445 90)
			(size 0.1397 0.1397)
			(layers "F.Cu" "F.Mask" "F.Paste")
			(net "P1V8")
			(options
				(clearance outline)
				(anchor circle)
			)
			(primitives
				(gr_poly
					(pts
						(arc
							(start -0.1778 -0.2794)
							(mid -0.249642 -0.249642)
							(end -0.2794 -0.1778)
						)
						(arc
							(start -0.2794 0.1778)
							(mid -0.249642 0.249642)
							(end -0.1778 0.2794)
						)
						(arc
							(start 0.1778 0.2794)
							(mid 0.249642 0.249642)
							(end 0.2794 0.1778)
						)
						(arc
							(start 0.2794 -0.1778)
							(mid 0.249642 -0.249642)
							(end 0.1778 -0.2794)
						)
					)
					(width 0)
					(fill yes)
				)
			)
		)
		(pad "2" smd custom
			(at 0 0.4445 90)
			(size 0.1397 0.1397)
			(layers "F.Cu" "F.Mask" "F.Paste")
			(net "IOC_SDA_4")
			(options
				(clearance outline)
				(anchor circle)
			)
			(primitives
				(gr_poly
					(pts
						(arc
							(start -0.1778 -0.2794)
							(mid -0.249642 -0.249642)
							(end -0.2794 -0.1778)
						)
						(arc
							(start -0.2794 0.1778)
							(mid -0.249642 0.249642)
							(end -0.1778 0.2794)
						)
						(arc
							(start 0.1778 0.2794)
							(mid 0.249642 0.249642)
							(end 0.2794 0.1778)
						)
						(arc
							(start 0.2794 -0.1778)
							(mid 0.249642 -0.249642)
							(end 0.1778 -0.2794)
						)
					)
					(width 0)
					(fill yes)
				)
			)
		)
	)
	(footprint ""
		(layer "F.Cu")
		(at 28.194 -155.702 -90)
		(property "Reference" "R772"
			(at 0 0 270)
			(layer "F.SilkS")
			(hide yes)
			(effects
				(font
					(size 1.27 1.27)
				)
			)
		)
		(property "Value" "0R2J-2-GP"
			(at 0.064008 -3.993896 270)
			(unlocked yes)
			(layer "F.Fab")
			(hide yes)
			(effects
				(font
					(size 1.016 1.016)
					(thickness 0.1524)
				)
			)
		)
		(property "Device Type" "R402H16"
			(at 0.064008 -5.517896 270)
			(unlocked yes)
			(layer "F.Fab")
			(hide yes)
			(effects
				(font
					(size 1.016 1.016)
					(thickness 0.1524)
				)
			)
		)
		(duplicate_pad_numbers_are_jumpers no)
		(fp_line
			(start -0.508 -0.9398)
			(end -0.508 0.9398)
			(stroke
				(width 0.1524)
				(type default)
			)
			(layer "F.SilkS")
		)
		(fp_line
			(start 0.508 -0.9398)
			(end -0.508 -0.9398)
			(stroke
				(width 0.1524)
				(type default)
			)
			(layer "F.SilkS")
		)
		(fp_rect
			(start -0.508 0.9398)
			(end 0.508 -0.9398)
			(stroke
				(width 0)
				(type default)
			)
			(fill no)
			(layer "F.CrtYd")
		)
		(fp_rect
			(start -0.508 0.9398)
			(end 0.508 -0.9398)
			(stroke
				(width 0)
				(type default)
			)
			(fill no)
			(layer "F.Fab")
		)
		(pad "1" smd custom
			(at 0 -0.4445 270)
			(size 0.1397 0.1397)
			(layers "F.Cu" "F.Mask" "F.Paste")
			(net "DEBUG_GPIO_BMC_R_5")
			(options
				(clearance outline)
				(anchor circle)
			)
			(primitives
				(gr_poly
					(pts
						(arc
							(start -0.1778 -0.2794)
							(mid -0.249642 -0.249642)
							(end -0.2794 -0.1778)
						)
						(arc
							(start -0.2794 0.1778)
							(mid -0.249642 0.249642)
							(end -0.1778 0.2794)
						)
						(arc
							(start 0.1778 0.2794)
							(mid 0.249642 0.249642)
							(end 0.2794 0.1778)
						)
						(arc
							(start 0.2794 -0.1778)
							(mid 0.249642 -0.249642)
							(end 0.1778 -0.2794)
						)
					)
					(width 0)
					(fill yes)
				)
			)
		)
		(pad "2" smd custom
			(at 0 0.4445 270)
			(size 0.1397 0.1397)
			(layers "F.Cu" "F.Mask" "F.Paste")
			(net "DEBUG_GPIO_BMC_5")
			(options
				(clearance outline)
				(anchor circle)
			)
			(primitives
				(gr_poly
					(pts
						(arc
							(start -0.1778 -0.2794)
							(mid -0.249642 -0.249642)
							(end -0.2794 -0.1778)
						)
						(arc
							(start -0.2794 0.1778)
							(mid -0.249642 0.249642)
							(end -0.1778 0.2794)
						)
						(arc
							(start 0.1778 0.2794)
							(mid 0.249642 0.249642)
							(end 0.2794 0.1778)
						)
						(arc
							(start 0.2794 -0.1778)
							(mid 0.249642 -0.249642)
							(end 0.1778 -0.2794)
						)
					)
					(width 0)
					(fill yes)
				)
			)
		)
	)
	(footprint ""
		(layer "F.Cu")
		(at 27.5844 -145.3515)
		(property "Reference" "R219"
			(at 0 0 0)
			(layer "F.SilkS")
			(hide yes)
			(effects
				(font
					(size 1.27 1.27)
				)
			)
		)
		(property "Value" "240R2F-1-GP"
			(at 0.064008 -3.993896 0)
			(unlocked yes)
			(layer "F.Fab")
			(hide yes)
			(effects
				(font
					(size 1.016 1.016)
					(thickness 0.1524)
				)
			)
		)
		(property "Device Type" "R402H16"
			(at 0.064008 -5.517896 0)
			(unlocked yes)
			(layer "F.Fab")
			(hide yes)
			(effects
				(font
					(size 1.016 1.016)
					(thickness 0.1524)
				)
			)
		)
		(duplicate_pad_numbers_are_jumpers no)
		(fp_line
			(start -0.508 -0.9398)
			(end -0.508 0.9398)
			(stroke
				(width 0.1524)
				(type default)
			)
			(layer "F.SilkS")
		)
		(fp_line
			(start 0.508 -0.9398)
			(end -0.508 -0.9398)
			(stroke
				(width 0.1524)
				(type default)
			)
			(layer "F.SilkS")
		)
		(fp_rect
			(start -0.508 0.9398)
			(end 0.508 -0.9398)
			(stroke
				(width 0)
				(type default)
			)
			(fill no)
			(layer "F.CrtYd")
		)
		(fp_rect
			(start -0.508 0.9398)
			(end 0.508 -0.9398)
			(stroke
				(width 0)
				(type default)
			)
			(fill no)
			(layer "F.Fab")
		)
		(pad "1" smd custom
			(at 0 -0.4445)
			(size 0.1397 0.1397)
			(layers "F.Cu" "F.Mask" "F.Paste")
			(net "GND")
			(options
				(clearance outline)
				(anchor circle)
			)
			(primitives
				(gr_poly
					(pts
						(arc
							(start -0.1778 -0.2794)
							(mid -0.249642 -0.249642)
							(end -0.2794 -0.1778)
						)
						(arc
							(start -0.2794 0.1778)
							(mid -0.249642 0.249642)
							(end -0.1778 0.2794)
						)
						(arc
							(start 0.1778 0.2794)
							(mid 0.249642 0.249642)
							(end 0.2794 0.1778)
						)
						(arc
							(start 0.2794 -0.1778)
							(mid 0.249642 -0.249642)
							(end 0.1778 -0.2794)
						)
					)
					(width 0)
					(fill yes)
				)
			)
		)
		(pad "2" smd custom
			(at 0 0.4445)
			(size 0.1397 0.1397)
			(layers "F.Cu" "F.Mask" "F.Paste")
			(net "PD_ZQ")
			(options
				(clearance outline)
				(anchor circle)
			)
			(primitives
				(gr_poly
					(pts
						(arc
							(start -0.1778 -0.2794)
							(mid -0.249642 -0.249642)
							(end -0.2794 -0.1778)
						)
						(arc
							(start -0.2794 0.1778)
							(mid -0.249642 0.249642)
							(end -0.1778 0.2794)
						)
						(arc
							(start 0.1778 0.2794)
							(mid 0.249642 0.249642)
							(end 0.2794 0.1778)
						)
						(arc
							(start 0.2794 -0.1778)
							(mid 0.249642 -0.249642)
							(end 0.1778 -0.2794)
						)
					)
					(width 0)
					(fill yes)
				)
			)
		)
	)
	(footprint ""
		(layer "F.Cu")
		(at 69.5452 -181.6354 -90)
		(property "Reference" "C201"
			(at 0 0 270)
			(layer "F.SilkS")
			(hide yes)
			(effects
				(font
					(size 1.27 1.27)
				)
			)
		)
		(property "Value" "SCD1U16V2KX-3GP"
			(at 1.1811 -2.7051 270)
			(unlocked yes)
			(layer "F.Fab")
			(hide yes)
			(effects
				(font
					(size 1.016 1.016)
					(thickness 0.1524)
				)
			)
		)
		(property "Device Type" "C402H22"
			(at 1.1811 -4.2291 270)
			(unlocked yes)
			(layer "F.Fab")
			(hide yes)
			(effects
				(font
					(size 1.016 1.016)
					(thickness 0.1524)
				)
			)
		)
		(duplicate_pad_numbers_are_jumpers no)
		(fp_rect
			(start -0.4318 0.9525)
			(end 0.4318 -0.9525)
			(stroke
				(width 0)
				(type default)
			)
			(fill no)
			(layer "F.CrtYd")
		)
		(fp_rect
			(start -0.4318 0.9525)
			(end 0.4318 -0.9525)
			(stroke
				(width 0)
				(type default)
			)
			(fill no)
			(layer "F.Fab")
		)
		(pad "1" smd custom
			(at 0 -0.4445 270)
			(size 0.1524 0.1524)
			(layers "F.Cu" "F.Mask" "F.Paste")
			(net "TPS74801_P2V5_STBY_EN")
			(options
				(clearance outline)
				(anchor circle)
			)
			(primitives
				(gr_poly
					(pts
						(arc
							(start 0.3048 -0.2032)
							(mid 0.275042 -0.275042)
							(end 0.2032 -0.3048)
						)
						(arc
							(start -0.2032 -0.3048)
							(mid -0.275042 -0.275042)
							(end -0.3048 -0.2032)
						)
						(arc
							(start -0.3048 0.2032)
							(mid -0.275042 0.275042)
							(end -0.2032 0.3048)
						)
						(arc
							(start 0.2032 0.3048)
							(mid 0.275042 0.275042)
							(end 0.3048 0.2032)
						)
					)
					(width 0)
					(fill yes)
				)
			)
		)
		(pad "2" smd custom
			(at 0 0.4445 270)
			(size 0.1524 0.1524)
			(layers "F.Cu" "F.Mask" "F.Paste")
			(net "GND")
			(options
				(clearance outline)
				(anchor circle)
			)
			(primitives
				(gr_poly
					(pts
						(arc
							(start 0.3048 -0.2032)
							(mid 0.275042 -0.275042)
							(end 0.2032 -0.3048)
						)
						(arc
							(start -0.2032 -0.3048)
							(mid -0.275042 -0.275042)
							(end -0.3048 -0.2032)
						)
						(arc
							(start -0.3048 0.2032)
							(mid -0.275042 0.275042)
							(end -0.2032 0.3048)
						)
						(arc
							(start 0.2032 0.3048)
							(mid 0.275042 0.275042)
							(end 0.3048 0.2032)
						)
					)
					(width 0)
					(fill yes)
				)
			)
		)
	)
	(footprint ""
		(layer "F.Cu")
		(at 147.85086 -13.12672)
		(property "Reference" "R737"
			(at 0 0 0)
			(layer "F.SilkS")
			(hide yes)
			(effects
				(font
					(size 1.27 1.27)
				)
			)
		)
		(property "Value" "120R3F-L-GP"
			(at -0.0254 -2.5146 0)
			(unlocked yes)
			(layer "F.Fab")
			(hide yes)
			(effects
				(font
					(size 1.016 1.016)
					(thickness 0.1524)
				)
			)
		)
		(property "Device Type" "R603H22"
			(at -0.0254 -4.0386 0)
			(unlocked yes)
			(layer "F.Fab")
			(hide yes)
			(effects
				(font
					(size 1.016 1.016)
					(thickness 0.1524)
				)
			)
		)
		(duplicate_pad_numbers_are_jumpers no)
		(fp_line
			(start -0.4826 0)
			(end -0.2032 0)
			(stroke
				(width 0.2032)
				(type default)
			)
			(layer "F.SilkS")
		)
		(fp_line
			(start 0.2032 0)
			(end 0.4826 0)
			(stroke
				(width 0.2032)
				(type default)
			)
			(layer "F.SilkS")
		)
		(fp_rect
			(start -0.5842 1.3335)
			(end 0.5842 -1.3335)
			(stroke
				(width 0)
				(type default)
			)
			(fill no)
			(layer "F.CrtYd")
		)
		(fp_rect
			(start -0.5842 1.3335)
			(end 0.5842 -1.3335)
			(stroke
				(width 0)
				(type default)
			)
			(fill no)
			(layer "F.Fab")
		)
		(pad "1" smd custom
			(at 0 -0.762)
			(size 0.2159 0.2159)
			(layers "F.Cu" "F.Mask" "F.Paste")
			(net "EXT2_LED_YELLOW_D1")
			(options
				(clearance outline)
				(anchor circle)
			)
			(primitives
				(gr_poly
					(pts
						(arc
							(start -0.3302 -0.4318)
							(mid -0.402042 -0.402042)
							(end -0.4318 -0.3302)
						)
						(arc
							(start -0.4318 0.3302)
							(mid -0.402042 0.402042)
							(end -0.3302 0.4318)
						)
						(arc
							(start 0.3302 0.4318)
							(mid 0.402042 0.402042)
							(end 0.4318 0.3302)
						)
						(arc
							(start 0.4318 -0.3302)
							(mid 0.402042 -0.402042)
							(end 0.3302 -0.4318)
						)
					)
					(width 0)
					(fill yes)
				)
			)
		)
		(pad "2" smd custom
			(at 0 0.762)
			(size 0.2159 0.2159)
			(layers "F.Cu" "F.Mask" "F.Paste")
			(net "EXT2_LED_YELLOW")
			(options
				(clearance outline)
				(anchor circle)
			)
			(primitives
				(gr_poly
					(pts
						(arc
							(start -0.3302 -0.4318)
							(mid -0.402042 -0.402042)
							(end -0.4318 -0.3302)
						)
						(arc
							(start -0.4318 0.3302)
							(mid -0.402042 0.402042)
							(end -0.3302 0.4318)
						)
						(arc
							(start 0.3302 0.4318)
							(mid 0.402042 0.402042)
							(end 0.4318 0.3302)
						)
						(arc
							(start 0.4318 -0.3302)
							(mid 0.402042 -0.402042)
							(end 0.3302 -0.4318)
						)
					)
					(width 0)
					(fill yes)
				)
			)
		)
	)
	(footprint ""
		(layer "F.Cu")
		(at 187.54471 -90.86469)
		(property "Reference" "R643"
			(at 0 0 0)
			(layer "F.SilkS")
			(hide yes)
			(effects
				(font
					(size 1.27 1.27)
				)
			)
		)
		(property "Value" "4K7R2F-GP"
			(at 0.064008 -3.993896 0)
			(unlocked yes)
			(layer "F.Fab")
			(hide yes)
			(effects
				(font
					(size 1.016 1.016)
					(thickness 0.1524)
				)
			)
		)
		(property "Device Type" "R402H16"
			(at 0.064008 -5.517896 0)
			(unlocked yes)
			(layer "F.Fab")
			(hide yes)
			(effects
				(font
					(size 1.016 1.016)
					(thickness 0.1524)
				)
			)
		)
		(duplicate_pad_numbers_are_jumpers no)
		(fp_line
			(start -0.508 -0.9398)
			(end -0.508 0.9398)
			(stroke
				(width 0.1524)
				(type default)
			)
			(layer "F.SilkS")
		)
		(fp_line
			(start 0.508 -0.9398)
			(end -0.508 -0.9398)
			(stroke
				(width 0.1524)
				(type default)
			)
			(layer "F.SilkS")
		)
		(fp_rect
			(start -0.508 0.9398)
			(end 0.508 -0.9398)
			(stroke
				(width 0)
				(type default)
			)
			(fill no)
			(layer "F.CrtYd")
		)
		(fp_rect
			(start -0.508 0.9398)
			(end 0.508 -0.9398)
			(stroke
				(width 0)
				(type default)
			)
			(fill no)
			(layer "F.Fab")
		)
		(pad "1" smd custom
			(at 0 -0.4445)
			(size 0.1397 0.1397)
			(layers "F.Cu" "F.Mask" "F.Paste")
			(net "P1V8")
			(options
				(clearance outline)
				(anchor circle)
			)
			(primitives
				(gr_poly
					(pts
						(arc
							(start -0.1778 -0.2794)
							(mid -0.249642 -0.249642)
							(end -0.2794 -0.1778)
						)
						(arc
							(start -0.2794 0.1778)
							(mid -0.249642 0.249642)
							(end -0.1778 0.2794)
						)
						(arc
							(start 0.1778 0.2794)
							(mid 0.249642 0.249642)
							(end 0.2794 0.1778)
						)
						(arc
							(start 0.2794 -0.1778)
							(mid 0.249642 -0.249642)
							(end 0.1778 -0.2794)
						)
					)
					(width 0)
					(fill yes)
				)
			)
		)
		(pad "2" smd custom
			(at 0 0.4445)
			(size 0.1397 0.1397)
			(layers "F.Cu" "F.Mask" "F.Paste")
			(net "SYS_DBMODE1")
			(options
				(clearance outline)
				(anchor circle)
			)
			(primitives
				(gr_poly
					(pts
						(arc
							(start -0.1778 -0.2794)
							(mid -0.249642 -0.249642)
							(end -0.2794 -0.1778)
						)
						(arc
							(start -0.2794 0.1778)
							(mid -0.249642 0.249642)
							(end -0.1778 0.2794)
						)
						(arc
							(start 0.1778 0.2794)
							(mid 0.249642 0.249642)
							(end 0.2794 0.1778)
						)
						(arc
							(start 0.2794 -0.1778)
							(mid 0.249642 -0.249642)
							(end 0.1778 -0.2794)
						)
					)
					(width 0)
					(fill yes)
				)
			)
		)
	)
	(footprint ""
		(layer "F.Cu")
		(at 184.1754 -114.0714 90)
		(property "Reference" "C272"
			(at 0 0 90)
			(layer "F.SilkS")
			(hide yes)
			(effects
				(font
					(size 1.27 1.27)
				)
			)
		)
		(property "Value" "SC10U16V5KX-7-GP-U"
			(at -0.0762 -6.1214 90)
			(unlocked yes)
			(layer "F.Fab")
			(hide yes)
			(effects
				(font
					(size 1.016 1.016)
					(thickness 0.1524)
				)
			)
		)
		(property "Device Type" "C805H58"
			(at -0.0762 -8.1534 90)
			(unlocked yes)
			(layer "F.Fab")
			(hide yes)
			(effects
				(font
					(size 1.016 1.016)
					(thickness 0.1524)
				)
			)
		)
		(duplicate_pad_numbers_are_jumpers no)
		(fp_line
			(start 0.635 0)
			(end -0.635 0)
			(stroke
				(width 0.508)
				(type default)
			)
			(layer "F.SilkS")
		)
		(fp_rect
			(start -0.9652 1.778)
			(end 0.9652 -1.778)
			(stroke
				(width 0)
				(type default)
			)
			(fill no)
			(layer "F.CrtYd")
		)
		(fp_poly
			(pts
				(xy -0.9652 -1.778) (xy 0.9652 -1.778) (xy 0.9652 1.778) (xy -0.9652 1.778)
			)
			(stroke
				(width 0)
				(type default)
			)
			(fill no)
			(layer "F.Fab")
		)
		(pad "1" smd rect
			(at 0 -0.9652 90)
			(size 1.397 1.143)
			(layers "F.Cu" "F.Mask" "F.Paste")
			(net "VT235_VDDH")
		)
		(pad "2" smd rect
			(at 0 0.9652 90)
			(size 1.397 1.143)
			(layers "F.Cu" "F.Mask" "F.Paste")
			(net "GND")
		)
	)
	(footprint ""
		(layer "F.Cu")
		(at 208.055972 -74.4728 90)
		(property "Reference" "C310"
			(at 0 0 90)
			(layer "F.SilkS")
			(hide yes)
			(effects
				(font
					(size 1.27 1.27)
				)
			)
		)
		(property "Value" "SCD01U16V1KX-GP"
			(at -2.8321 -1.7399 90)
			(unlocked yes)
			(layer "F.Fab")
			(hide yes)
			(effects
				(font
					(size 1.016 1.016)
					(thickness 0.1524)
				)
			)
		)
		(property "Device Type" "C0201H13"
			(at -2.8321 -3.2639 90)
			(unlocked yes)
			(layer "F.Fab")
			(hide yes)
			(effects
				(font
					(size 1.016 1.016)
					(thickness 0.1524)
				)
			)
		)
		(duplicate_pad_numbers_are_jumpers no)
		(fp_rect
			(start -0.2794 0.6477)
			(end 0.2794 -0.6477)
			(stroke
				(width 0)
				(type default)
			)
			(fill no)
			(layer "F.CrtYd")
		)
		(fp_rect
			(start -0.2794 0.6477)
			(end 0.2794 -0.6477)
			(stroke
				(width 0)
				(type default)
			)
			(fill no)
			(layer "F.Fab")
		)
		(pad "1" smd custom
			(at 0 -0.2794 90)
			(size 0.0762 0.0762)
			(layers "F.Cu" "F.Mask" "F.Paste")
			(net "PHY_IOC_TO_CON_A_1_DN_C")
			(options
				(clearance outline)
				(anchor circle)
			)
			(primitives
				(gr_poly
					(pts
						(arc
							(start 0.1524 -0.127)
							(mid 0.137521 -0.162921)
							(end 0.1016 -0.1778)
						)
						(arc
							(start -0.1016 -0.1778)
							(mid -0.137521 -0.162921)
							(end -0.1524 -0.127)
						)
						(arc
							(start -0.1524 0.127)
							(mid -0.137521 0.162921)
							(end -0.1016 0.1778)
						)
						(arc
							(start 0.1016 0.1778)
							(mid 0.137521 0.162921)
							(end 0.1524 0.127)
						)
					)
					(width 0)
					(fill yes)
				)
			)
		)
		(pad "2" smd custom
			(at 0 0.2794 90)
			(size 0.0762 0.0762)
			(layers "F.Cu" "F.Mask" "F.Paste")
			(net "PHY_IOC_TO_CON_A_1_DN")
			(options
				(clearance outline)
				(anchor circle)
			)
			(primitives
				(gr_poly
					(pts
						(arc
							(start 0.1524 -0.127)
							(mid 0.137521 -0.162921)
							(end 0.1016 -0.1778)
						)
						(arc
							(start -0.1016 -0.1778)
							(mid -0.137521 -0.162921)
							(end -0.1524 -0.127)
						)
						(arc
							(start -0.1524 0.127)
							(mid -0.137521 0.162921)
							(end -0.1016 0.1778)
						)
						(arc
							(start 0.1016 0.1778)
							(mid 0.137521 0.162921)
							(end 0.1524 0.127)
						)
					)
					(width 0)
					(fill yes)
				)
			)
		)
	)
	(footprint ""
		(layer "F.Cu")
		(at 27.99588 -122.859292)
		(property "Reference" "R85"
			(at 0 0 0)
			(layer "F.SilkS")
			(hide yes)
			(effects
				(font
					(size 1.27 1.27)
				)
			)
		)
		(property "Value" "100KR2F-L1-GP"
			(at 0.064008 -3.993896 0)
			(unlocked yes)
			(layer "F.Fab")
			(hide yes)
			(effects
				(font
					(size 1.016 1.016)
					(thickness 0.1524)
				)
			)
		)
		(property "Device Type" "R402H16"
			(at 0.064008 -5.517896 0)
			(unlocked yes)
			(layer "F.Fab")
			(hide yes)
			(effects
				(font
					(size 1.016 1.016)
					(thickness 0.1524)
				)
			)
		)
		(duplicate_pad_numbers_are_jumpers no)
		(fp_line
			(start -0.508 -0.9398)
			(end -0.508 0.9398)
			(stroke
				(width 0.1524)
				(type default)
			)
			(layer "F.SilkS")
		)
		(fp_line
			(start 0.508 -0.9398)
			(end -0.508 -0.9398)
			(stroke
				(width 0.1524)
				(type default)
			)
			(layer "F.SilkS")
		)
		(fp_rect
			(start -0.508 0.9398)
			(end 0.508 -0.9398)
			(stroke
				(width 0)
				(type default)
			)
			(fill no)
			(layer "F.CrtYd")
		)
		(fp_rect
			(start -0.508 0.9398)
			(end 0.508 -0.9398)
			(stroke
				(width 0)
				(type default)
			)
			(fill no)
			(layer "F.Fab")
		)
		(pad "1" smd custom
			(at 0 -0.4445)
			(size 0.1397 0.1397)
			(layers "F.Cu" "F.Mask" "F.Paste")
			(net "WP_ENABLE")
			(options
				(clearance outline)
				(anchor circle)
			)
			(primitives
				(gr_poly
					(pts
						(arc
							(start -0.1778 -0.2794)
							(mid -0.249642 -0.249642)
							(end -0.2794 -0.1778)
						)
						(arc
							(start -0.2794 0.1778)
							(mid -0.249642 0.249642)
							(end -0.1778 0.2794)
						)
						(arc
							(start 0.1778 0.2794)
							(mid 0.249642 0.249642)
							(end 0.2794 0.1778)
						)
						(arc
							(start 0.2794 -0.1778)
							(mid 0.249642 -0.249642)
							(end 0.1778 -0.2794)
						)
					)
					(width 0)
					(fill yes)
				)
			)
		)
		(pad "2" smd custom
			(at 0 0.4445)
			(size 0.1397 0.1397)
			(layers "F.Cu" "F.Mask" "F.Paste")
			(net "GND")
			(options
				(clearance outline)
				(anchor circle)
			)
			(primitives
				(gr_poly
					(pts
						(arc
							(start -0.1778 -0.2794)
							(mid -0.249642 -0.249642)
							(end -0.2794 -0.1778)
						)
						(arc
							(start -0.2794 0.1778)
							(mid -0.249642 0.249642)
							(end -0.1778 0.2794)
						)
						(arc
							(start 0.1778 0.2794)
							(mid 0.249642 0.249642)
							(end 0.2794 0.1778)
						)
						(arc
							(start 0.2794 -0.1778)
							(mid 0.249642 -0.249642)
							(end 0.1778 -0.2794)
						)
					)
					(width 0)
					(fill yes)
				)
			)
		)
	)
	(footprint ""
		(layer "F.Cu")
		(at 222.499936 -187.999878)
		(property "Reference" ""
			(at 0 0 0)
			(layer "F.SilkS")
			(hide yes)
			(effects
				(font
					(size 1.27 1.27)
				)
			)
		)
		(property "Value" "*"
			(at -6.38175 0.19685 0)
			(unlocked yes)
			(layer "F.Fab")
			(hide yes)
			(effects
				(font
					(size 1.016 1.016)
					(thickness 0.1524)
				)
			)
		)
		(duplicate_pad_numbers_are_jumpers no)
		(fp_poly
			(pts
				(arc
					(start 5.0673 0)
					(mid -5.0673 0)
					(end 5.0673 0)
				)
			)
			(stroke
				(width 0)
				(type default)
			)
			(fill no)
			(layer "B.CrtYd")
		)
		(fp_poly
			(pts
				(arc
					(start 5.0673 0)
					(mid -5.0673 0)
					(end 5.0673 0)
				)
			)
			(stroke
				(width 0)
				(type default)
			)
			(fill no)
			(layer "F.CrtYd")
		)
		(fp_poly
			(pts
				(arc
					(start 5.0673 0)
					(mid -5.0673 0)
					(end 5.0673 0)
				)
			)
			(stroke
				(width 0)
				(type default)
			)
			(fill no)
			(layer "B.Fab")
		)
		(fp_poly
			(pts
				(arc
					(start 5.0673 0)
					(mid -5.0673 0)
					(end 5.0673 0)
				)
			)
			(stroke
				(width 0)
				(type default)
			)
			(fill no)
			(layer "F.Fab")
		)
		(pad "1" thru_hole circle
			(at 0 0)
			(size 9.525 9.525)
			(drill 3.5052)
			(layers "*.Cu" "*.Mask")
			(remove_unused_layers no)
			(net "Net_14")
			(clearance -2.5019)
			(thermal_gap 0.3048)
			(padstack
				(mode front_inner_back)
				(layer "Inner"
					(shape circle)
					(size 3.9116 3.9116)
					(clearance 0.3048)
				)
				(layer "B.Cu"
					(shape circle)
					(size 9.525 9.525)
					(clearance -2.5019)
				)
			)
		)
	)
	(footprint ""
		(layer "F.Cu")
		(at 47.8536 -164.0078 180)
		(property "Reference" "R367"
			(at 0 0 180)
			(layer "F.SilkS")
			(hide yes)
			(effects
				(font
					(size 1.27 1.27)
				)
			)
		)
		(property "Value" "18KR2F-5-GP"
			(at 0.064008 -3.993896 180)
			(unlocked yes)
			(layer "F.Fab")
			(hide yes)
			(effects
				(font
					(size 1.016 1.016)
					(thickness 0.1524)
				)
			)
		)
		(property "Device Type" "R402H16"
			(at 0.064008 -5.517896 180)
			(unlocked yes)
			(layer "F.Fab")
			(hide yes)
			(effects
				(font
					(size 1.016 1.016)
					(thickness 0.1524)
				)
			)
		)
		(duplicate_pad_numbers_are_jumpers no)
		(fp_line
			(start 0.508 -0.9398)
			(end -0.508 -0.9398)
			(stroke
				(width 0.1524)
				(type default)
			)
			(layer "F.SilkS")
		)
		(fp_line
			(start -0.508 -0.9398)
			(end -0.508 0.9398)
			(stroke
				(width 0.1524)
				(type default)
			)
			(layer "F.SilkS")
		)
		(fp_rect
			(start -0.508 0.9398)
			(end 0.508 -0.9398)
			(stroke
				(width 0)
				(type default)
			)
			(fill no)
			(layer "F.CrtYd")
		)
		(fp_rect
			(start -0.508 0.9398)
			(end 0.508 -0.9398)
			(stroke
				(width 0)
				(type default)
			)
			(fill no)
			(layer "F.Fab")
		)
		(pad "1" smd custom
			(at 0 -0.4445 180)
			(size 0.1397 0.1397)
			(layers "F.Cu" "F.Mask" "F.Paste")
			(net "GND")
			(options
				(clearance outline)
				(anchor circle)
			)
			(primitives
				(gr_poly
					(pts
						(arc
							(start -0.1778 -0.2794)
							(mid -0.249642 -0.249642)
							(end -0.2794 -0.1778)
						)
						(arc
							(start -0.2794 0.1778)
							(mid -0.249642 0.249642)
							(end -0.1778 0.2794)
						)
						(arc
							(start 0.1778 0.2794)
							(mid 0.249642 0.249642)
							(end 0.2794 0.1778)
						)
						(arc
							(start 0.2794 -0.1778)
							(mid 0.249642 -0.249642)
							(end 0.1778 -0.2794)
						)
					)
					(width 0)
					(fill yes)
				)
			)
		)
		(pad "2" smd custom
			(at 0 0.4445 180)
			(size 0.1397 0.1397)
			(layers "F.Cu" "F.Mask" "F.Paste")
			(net "DACRSET")
			(options
				(clearance outline)
				(anchor circle)
			)
			(primitives
				(gr_poly
					(pts
						(arc
							(start -0.1778 -0.2794)
							(mid -0.249642 -0.249642)
							(end -0.2794 -0.1778)
						)
						(arc
							(start -0.2794 0.1778)
							(mid -0.249642 0.249642)
							(end -0.1778 0.2794)
						)
						(arc
							(start 0.1778 0.2794)
							(mid 0.249642 0.249642)
							(end 0.2794 0.1778)
						)
						(arc
							(start 0.2794 -0.1778)
							(mid 0.249642 -0.249642)
							(end 0.1778 -0.2794)
						)
					)
					(width 0)
					(fill yes)
				)
			)
		)
	)
	(footprint ""
		(layer "F.Cu")
		(at 197.4088 -126.619)
		(property "Reference" "R565"
			(at 0 0 0)
			(layer "F.SilkS")
			(hide yes)
			(effects
				(font
					(size 1.27 1.27)
				)
			)
		)
		(property "Value" "221R2F-2-GP"
			(at 0.064008 -3.993896 0)
			(unlocked yes)
			(layer "F.Fab")
			(hide yes)
			(effects
				(font
					(size 1.016 1.016)
					(thickness 0.1524)
				)
			)
		)
		(property "Device Type" "R402H16"
			(at 0.064008 -5.517896 0)
			(unlocked yes)
			(layer "F.Fab")
			(hide yes)
			(effects
				(font
					(size 1.016 1.016)
					(thickness 0.1524)
				)
			)
		)
		(duplicate_pad_numbers_are_jumpers no)
		(fp_line
			(start -0.508 -0.9398)
			(end -0.508 0.9398)
			(stroke
				(width 0.1524)
				(type default)
			)
			(layer "F.SilkS")
		)
		(fp_line
			(start 0.508 -0.9398)
			(end -0.508 -0.9398)
			(stroke
				(width 0.1524)
				(type default)
			)
			(layer "F.SilkS")
		)
		(fp_rect
			(start -0.508 0.9398)
			(end 0.508 -0.9398)
			(stroke
				(width 0)
				(type default)
			)
			(fill no)
			(layer "F.CrtYd")
		)
		(fp_rect
			(start -0.508 0.9398)
			(end 0.508 -0.9398)
			(stroke
				(width 0)
				(type default)
			)
			(fill no)
			(layer "F.Fab")
		)
		(pad "1" smd custom
			(at 0 -0.4445)
			(size 0.1397 0.1397)
			(layers "F.Cu" "F.Mask" "F.Paste")
			(net "VT235_VDES_RCC")
			(options
				(clearance outline)
				(anchor circle)
			)
			(primitives
				(gr_poly
					(pts
						(arc
							(start -0.1778 -0.2794)
							(mid -0.249642 -0.249642)
							(end -0.2794 -0.1778)
						)
						(arc
							(start -0.2794 0.1778)
							(mid -0.249642 0.249642)
							(end -0.1778 0.2794)
						)
						(arc
							(start 0.1778 0.2794)
							(mid 0.249642 0.249642)
							(end 0.2794 0.1778)
						)
						(arc
							(start 0.2794 -0.1778)
							(mid 0.249642 -0.249642)
							(end 0.1778 -0.2794)
						)
					)
					(width 0)
					(fill yes)
				)
			)
		)
		(pad "2" smd custom
			(at 0 0.4445)
			(size 0.1397 0.1397)
			(layers "F.Cu" "F.Mask" "F.Paste")
			(net "GND_SEN")
			(options
				(clearance outline)
				(anchor circle)
			)
			(primitives
				(gr_poly
					(pts
						(arc
							(start -0.1778 -0.2794)
							(mid -0.249642 -0.249642)
							(end -0.2794 -0.1778)
						)
						(arc
							(start -0.2794 0.1778)
							(mid -0.249642 0.249642)
							(end -0.1778 0.2794)
						)
						(arc
							(start 0.1778 0.2794)
							(mid 0.249642 0.249642)
							(end 0.2794 0.1778)
						)
						(arc
							(start 0.2794 -0.1778)
							(mid 0.249642 -0.249642)
							(end 0.1778 -0.2794)
						)
					)
					(width 0)
					(fill yes)
				)
			)
		)
	)
	(footprint ""
		(layer "F.Cu")
		(at 45.99559 -158.1912)
		(property "Reference" "R172"
			(at 0 0 0)
			(layer "F.SilkS")
			(hide yes)
			(effects
				(font
					(size 1.27 1.27)
				)
			)
		)
		(property "Value" "0R2J-2-GP"
			(at 0.064008 -3.993896 0)
			(unlocked yes)
			(layer "F.Fab")
			(hide yes)
			(effects
				(font
					(size 1.016 1.016)
					(thickness 0.1524)
				)
			)
		)
		(property "Device Type" "R402H16"
			(at 0.064008 -5.517896 0)
			(unlocked yes)
			(layer "F.Fab")
			(hide yes)
			(effects
				(font
					(size 1.016 1.016)
					(thickness 0.1524)
				)
			)
		)
		(duplicate_pad_numbers_are_jumpers no)
		(fp_line
			(start -0.508 -0.9398)
			(end -0.508 0.9398)
			(stroke
				(width 0.1524)
				(type default)
			)
			(layer "F.SilkS")
		)
		(fp_line
			(start 0.508 -0.9398)
			(end -0.508 -0.9398)
			(stroke
				(width 0.1524)
				(type default)
			)
			(layer "F.SilkS")
		)
		(fp_rect
			(start -0.508 0.9398)
			(end 0.508 -0.9398)
			(stroke
				(width 0)
				(type default)
			)
			(fill no)
			(layer "F.CrtYd")
		)
		(fp_rect
			(start -0.508 0.9398)
			(end 0.508 -0.9398)
			(stroke
				(width 0)
				(type default)
			)
			(fill no)
			(layer "F.Fab")
		)
		(pad "1" smd custom
			(at 0 -0.4445)
			(size 0.1397 0.1397)
			(layers "F.Cu" "F.Mask" "F.Paste")
			(net "I2C_DPB_SDA_OUT")
			(options
				(clearance outline)
				(anchor circle)
			)
			(primitives
				(gr_poly
					(pts
						(arc
							(start -0.1778 -0.2794)
							(mid -0.249642 -0.249642)
							(end -0.2794 -0.1778)
						)
						(arc
							(start -0.2794 0.1778)
							(mid -0.249642 0.249642)
							(end -0.1778 0.2794)
						)
						(arc
							(start 0.1778 0.2794)
							(mid 0.249642 0.249642)
							(end 0.2794 0.1778)
						)
						(arc
							(start 0.2794 -0.1778)
							(mid 0.249642 -0.249642)
							(end 0.1778 -0.2794)
						)
					)
					(width 0)
					(fill yes)
				)
			)
		)
		(pad "2" smd custom
			(at 0 0.4445)
			(size 0.1397 0.1397)
			(layers "F.Cu" "F.Mask" "F.Paste")
			(net "BMC_SMB7_DAT")
			(options
				(clearance outline)
				(anchor circle)
			)
			(primitives
				(gr_poly
					(pts
						(arc
							(start -0.1778 -0.2794)
							(mid -0.249642 -0.249642)
							(end -0.2794 -0.1778)
						)
						(arc
							(start -0.2794 0.1778)
							(mid -0.249642 0.249642)
							(end -0.1778 0.2794)
						)
						(arc
							(start 0.1778 0.2794)
							(mid 0.249642 0.249642)
							(end 0.2794 0.1778)
						)
						(arc
							(start 0.2794 -0.1778)
							(mid 0.249642 -0.249642)
							(end 0.1778 -0.2794)
						)
					)
					(width 0)
					(fill yes)
				)
			)
		)
	)
	(footprint ""
		(layer "F.Cu")
		(at 191.242188 -49.984406)
		(property "Reference" "TP152"
			(at 0 0 0)
			(layer "F.SilkS")
			(hide yes)
			(effects
				(font
					(size 1.27 1.27)
				)
			)
		)
		(property "Value" "TPAD28-2-GP"
			(at -0.0127 -1.6637 0)
			(unlocked yes)
			(layer "F.Fab")
			(hide yes)
			(effects
				(font
					(size 1.016 1.016)
					(thickness 0.1524)
				)
			)
		)
		(property "Device Type" "TPAD28"
			(at -0.0127 -3.1877 0)
			(unlocked yes)
			(layer "F.Fab")
			(hide yes)
			(effects
				(font
					(size 1.016 1.016)
					(thickness 0.1524)
				)
			)
		)
		(duplicate_pad_numbers_are_jumpers no)
		(fp_poly
			(pts
				(arc
					(start 0.3556 0)
					(mid -0.3556 0)
					(end 0.3556 0)
				)
			)
			(stroke
				(width 0)
				(type default)
			)
			(fill no)
			(layer "F.CrtYd")
		)
		(fp_poly
			(pts
				(arc
					(start 0.6096 0)
					(mid -0.6096 0)
					(end 0.6096 0)
				)
			)
			(stroke
				(width 0)
				(type default)
			)
			(fill no)
			(layer "F.Fab")
		)
		(pad "1" smd circle
			(at 0 0)
			(size 0.7112 0.7112)
			(layers "F.Cu" "F.Mask" "F.Paste")
			(net "JTAG_IOC_TDI")
		)
	)
	(footprint ""
		(layer "F.Cu")
		(at 207.408018 -101.337872 -90)
		(property "Reference" "R606"
			(at 0 0 270)
			(layer "F.SilkS")
			(hide yes)
			(effects
				(font
					(size 1.27 1.27)
				)
			)
		)
		(property "Value" "0R2J-2-GP"
			(at 0.064008 -3.993896 270)
			(unlocked yes)
			(layer "F.Fab")
			(hide yes)
			(effects
				(font
					(size 1.016 1.016)
					(thickness 0.1524)
				)
			)
		)
		(property "Device Type" "R402H16"
			(at 0.064008 -5.517896 270)
			(unlocked yes)
			(layer "F.Fab")
			(hide yes)
			(effects
				(font
					(size 1.016 1.016)
					(thickness 0.1524)
				)
			)
		)
		(duplicate_pad_numbers_are_jumpers no)
		(fp_line
			(start -0.508 -0.9398)
			(end -0.508 0.9398)
			(stroke
				(width 0.1524)
				(type default)
			)
			(layer "F.SilkS")
		)
		(fp_line
			(start 0.508 -0.9398)
			(end -0.508 -0.9398)
			(stroke
				(width 0.1524)
				(type default)
			)
			(layer "F.SilkS")
		)
		(fp_rect
			(start -0.508 0.9398)
			(end 0.508 -0.9398)
			(stroke
				(width 0)
				(type default)
			)
			(fill no)
			(layer "F.CrtYd")
		)
		(fp_rect
			(start -0.508 0.9398)
			(end 0.508 -0.9398)
			(stroke
				(width 0)
				(type default)
			)
			(fill no)
			(layer "F.Fab")
		)
		(pad "1" smd custom
			(at 0 -0.4445 270)
			(size 0.1397 0.1397)
			(layers "F.Cu" "F.Mask" "F.Paste")
			(net "IOC_EEPROM_SCL")
			(options
				(clearance outline)
				(anchor circle)
			)
			(primitives
				(gr_poly
					(pts
						(arc
							(start -0.1778 -0.2794)
							(mid -0.249642 -0.249642)
							(end -0.2794 -0.1778)
						)
						(arc
							(start -0.2794 0.1778)
							(mid -0.249642 0.249642)
							(end -0.1778 0.2794)
						)
						(arc
							(start 0.1778 0.2794)
							(mid 0.249642 0.249642)
							(end 0.2794 0.1778)
						)
						(arc
							(start 0.2794 -0.1778)
							(mid 0.249642 -0.249642)
							(end 0.1778 -0.2794)
						)
					)
					(width 0)
					(fill yes)
				)
			)
		)
		(pad "2" smd custom
			(at 0 0.4445 270)
			(size 0.1397 0.1397)
			(layers "F.Cu" "F.Mask" "F.Paste")
			(net "SBL_SCL")
			(options
				(clearance outline)
				(anchor circle)
			)
			(primitives
				(gr_poly
					(pts
						(arc
							(start -0.1778 -0.2794)
							(mid -0.249642 -0.249642)
							(end -0.2794 -0.1778)
						)
						(arc
							(start -0.2794 0.1778)
							(mid -0.249642 0.249642)
							(end -0.1778 0.2794)
						)
						(arc
							(start 0.1778 0.2794)
							(mid 0.249642 0.249642)
							(end 0.2794 0.1778)
						)
						(arc
							(start 0.2794 -0.1778)
							(mid 0.249642 -0.249642)
							(end 0.1778 -0.2794)
						)
					)
					(width 0)
					(fill yes)
				)
			)
		)
	)
	(footprint ""
		(layer "F.Cu")
		(at 124.0282 -12.4714 90)
		(property "Reference" "R439"
			(at 0 0 90)
			(layer "F.SilkS")
			(hide yes)
			(effects
				(font
					(size 1.27 1.27)
				)
			)
		)
		(property "Value" "11KR2F-L-GP"
			(at 0.064008 -3.993896 90)
			(unlocked yes)
			(layer "F.Fab")
			(hide yes)
			(effects
				(font
					(size 1.016 1.016)
					(thickness 0.1524)
				)
			)
		)
		(property "Device Type" "R402H16"
			(at 0.064008 -5.517896 90)
			(unlocked yes)
			(layer "F.Fab")
			(hide yes)
			(effects
				(font
					(size 1.016 1.016)
					(thickness 0.1524)
				)
			)
		)
		(duplicate_pad_numbers_are_jumpers no)
		(fp_line
			(start 0.508 -0.9398)
			(end -0.508 -0.9398)
			(stroke
				(width 0.1524)
				(type default)
			)
			(layer "F.SilkS")
		)
		(fp_line
			(start -0.508 -0.9398)
			(end -0.508 0.9398)
			(stroke
				(width 0.1524)
				(type default)
			)
			(layer "F.SilkS")
		)
		(fp_rect
			(start -0.508 0.9398)
			(end 0.508 -0.9398)
			(stroke
				(width 0)
				(type default)
			)
			(fill no)
			(layer "F.CrtYd")
		)
		(fp_rect
			(start -0.508 0.9398)
			(end 0.508 -0.9398)
			(stroke
				(width 0)
				(type default)
			)
			(fill no)
			(layer "F.Fab")
		)
		(pad "1" smd custom
			(at 0 -0.4445 90)
			(size 0.1397 0.1397)
			(layers "F.Cu" "F.Mask" "F.Paste")
			(net "MB0_P12V_PWGIN_R")
			(options
				(clearance outline)
				(anchor circle)
			)
			(primitives
				(gr_poly
					(pts
						(arc
							(start -0.1778 -0.2794)
							(mid -0.249642 -0.249642)
							(end -0.2794 -0.1778)
						)
						(arc
							(start -0.2794 0.1778)
							(mid -0.249642 0.249642)
							(end -0.1778 0.2794)
						)
						(arc
							(start 0.1778 0.2794)
							(mid 0.249642 0.249642)
							(end 0.2794 0.1778)
						)
						(arc
							(start 0.2794 -0.1778)
							(mid 0.249642 -0.249642)
							(end 0.1778 -0.2794)
						)
					)
					(width 0)
					(fill yes)
				)
			)
		)
		(pad "2" smd custom
			(at 0 0.4445 90)
			(size 0.1397 0.1397)
			(layers "F.Cu" "F.Mask" "F.Paste")
			(net "GND")
			(options
				(clearance outline)
				(anchor circle)
			)
			(primitives
				(gr_poly
					(pts
						(arc
							(start -0.1778 -0.2794)
							(mid -0.249642 -0.249642)
							(end -0.2794 -0.1778)
						)
						(arc
							(start -0.2794 0.1778)
							(mid -0.249642 0.249642)
							(end -0.1778 0.2794)
						)
						(arc
							(start 0.1778 0.2794)
							(mid 0.249642 0.249642)
							(end 0.2794 0.1778)
						)
						(arc
							(start 0.2794 -0.1778)
							(mid 0.249642 -0.249642)
							(end 0.1778 -0.2794)
						)
					)
					(width 0)
					(fill yes)
				)
			)
		)
	)
	(footprint ""
		(layer "F.Cu")
		(at 172.6692 -156.7688 180)
		(property "Reference" "L7"
			(at 0 0 180)
			(layer "F.SilkS")
			(hide yes)
			(effects
				(font
					(size 1.27 1.27)
				)
			)
		)
		(property "Value" "IND-4D7UH-291-GP"
			(at -6.34492 -3.502152 180)
			(unlocked yes)
			(layer "F.Fab")
			(hide yes)
			(effects
				(font
					(size 1.016 1.016)
					(thickness 0.1524)
				)
			)
		)
		(property "Device Type" "L11102530H158"
			(at -6.3246 -5.08 180)
			(unlocked yes)
			(layer "F.Fab")
			(hide yes)
			(effects
				(font
					(size 1.016 1.016)
					(thickness 0.1524)
				)
			)
		)
		(duplicate_pad_numbers_are_jumpers no)
		(fp_line
			(start 5.2578 6.3754)
			(end 5.2578 -6.3754)
			(stroke
				(width 0.1524)
				(type default)
			)
			(layer "F.SilkS")
		)
		(fp_line
			(start 5.2578 -6.3754)
			(end -5.2578 -6.3754)
			(stroke
				(width 0.1524)
				(type default)
			)
			(layer "F.SilkS")
		)
		(fp_line
			(start -5.2578 6.3754)
			(end 5.2578 6.3754)
			(stroke
				(width 0.1524)
				(type default)
			)
			(layer "F.SilkS")
		)
		(fp_line
			(start -5.2578 -6.3754)
			(end -5.2578 6.3754)
			(stroke
				(width 0.1524)
				(type default)
			)
			(layer "F.SilkS")
		)
		(fp_rect
			(start -5.0038 5.4991)
			(end 5.0038 -5.4991)
			(stroke
				(width 0)
				(type default)
			)
			(fill no)
			(layer "F.CrtYd")
		)
		(fp_poly
			(pts
				(xy -5.5118 6.4516) (xy -5.5118 -6.4516) (xy 5.5118 -6.4516) (xy 5.5118 -0.8509) (xy 5.0038 -0.8509)
				(xy 5.0038 -5.4991) (xy -5.0038 -5.4991) (xy -5.0038 5.4991) (xy 5.0038 5.4991) (xy 5.0038 -0.8382)
				(xy 5.5118 -0.8382) (xy 5.5118 6.4516)
			)
			(stroke
				(width 0)
				(type default)
			)
			(fill no)
			(layer "F.CrtYd")
		)
		(fp_rect
			(start -5.5118 6.4516)
			(end 5.5118 -6.4516)
			(stroke
				(width 0)
				(type default)
			)
			(fill no)
			(layer "F.Fab")
		)
		(pad "1" smd rect
			(at 0 -4.435094 180)
			(size 3.2512 3.3782)
			(layers "F.Cu" "F.Mask" "F.Paste")
			(net "P5V_LL")
		)
		(pad "2" smd rect
			(at 0 4.435094 180)
			(size 3.2512 3.3782)
			(layers "F.Cu" "F.Mask" "F.Paste")
			(net "P5V_STBY")
		)
	)
	(footprint ""
		(layer "F.Cu")
		(at 68.3006 -183.769 -90)
		(property "Reference" "R510"
			(at 0 0 270)
			(layer "F.SilkS")
			(hide yes)
			(effects
				(font
					(size 1.27 1.27)
				)
			)
		)
		(property "Value" "0R2J-2-GP"
			(at 0.064008 -3.993896 270)
			(unlocked yes)
			(layer "F.Fab")
			(hide yes)
			(effects
				(font
					(size 1.016 1.016)
					(thickness 0.1524)
				)
			)
		)
		(property "Device Type" "R402H16"
			(at 0.064008 -5.517896 270)
			(unlocked yes)
			(layer "F.Fab")
			(hide yes)
			(effects
				(font
					(size 1.016 1.016)
					(thickness 0.1524)
				)
			)
		)
		(duplicate_pad_numbers_are_jumpers no)
		(fp_line
			(start -0.508 -0.9398)
			(end -0.508 0.9398)
			(stroke
				(width 0.1524)
				(type default)
			)
			(layer "F.SilkS")
		)
		(fp_line
			(start 0.508 -0.9398)
			(end -0.508 -0.9398)
			(stroke
				(width 0.1524)
				(type default)
			)
			(layer "F.SilkS")
		)
		(fp_rect
			(start -0.508 0.9398)
			(end 0.508 -0.9398)
			(stroke
				(width 0)
				(type default)
			)
			(fill no)
			(layer "F.CrtYd")
		)
		(fp_rect
			(start -0.508 0.9398)
			(end 0.508 -0.9398)
			(stroke
				(width 0)
				(type default)
			)
			(fill no)
			(layer "F.Fab")
		)
		(pad "1" smd custom
			(at 0 -0.4445 270)
			(size 0.1397 0.1397)
			(layers "F.Cu" "F.Mask" "F.Paste")
			(net "TPS74801_P2V5_STBY_EN")
			(options
				(clearance outline)
				(anchor circle)
			)
			(primitives
				(gr_poly
					(pts
						(arc
							(start -0.1778 -0.2794)
							(mid -0.249642 -0.249642)
							(end -0.2794 -0.1778)
						)
						(arc
							(start -0.2794 0.1778)
							(mid -0.249642 0.249642)
							(end -0.1778 0.2794)
						)
						(arc
							(start 0.1778 0.2794)
							(mid 0.249642 0.249642)
							(end 0.2794 0.1778)
						)
						(arc
							(start 0.2794 -0.1778)
							(mid 0.249642 -0.249642)
							(end 0.1778 -0.2794)
						)
					)
					(width 0)
					(fill yes)
				)
			)
		)
		(pad "2" smd custom
			(at 0 0.4445 270)
			(size 0.1397 0.1397)
			(layers "F.Cu" "F.Mask" "F.Paste")
			(net "PWRGD_P3V3_STBY")
			(options
				(clearance outline)
				(anchor circle)
			)
			(primitives
				(gr_poly
					(pts
						(arc
							(start -0.1778 -0.2794)
							(mid -0.249642 -0.249642)
							(end -0.2794 -0.1778)
						)
						(arc
							(start -0.2794 0.1778)
							(mid -0.249642 0.249642)
							(end -0.1778 0.2794)
						)
						(arc
							(start 0.1778 0.2794)
							(mid 0.249642 0.249642)
							(end 0.2794 0.1778)
						)
						(arc
							(start 0.2794 -0.1778)
							(mid 0.249642 -0.249642)
							(end 0.1778 -0.2794)
						)
					)
					(width 0)
					(fill yes)
				)
			)
		)
	)
	(footprint ""
		(layer "F.Cu")
		(at 68.6054 -118.2116 90)
		(property "Reference" "C74"
			(at 0 0 90)
			(layer "F.SilkS")
			(hide yes)
			(effects
				(font
					(size 1.27 1.27)
				)
			)
		)
		(property "Value" "SCD1U16V2KX-3GP"
			(at 1.1811 -2.7051 90)
			(unlocked yes)
			(layer "F.Fab")
			(hide yes)
			(effects
				(font
					(size 1.016 1.016)
					(thickness 0.1524)
				)
			)
		)
		(property "Device Type" "C402H22"
			(at 1.1811 -4.2291 90)
			(unlocked yes)
			(layer "F.Fab")
			(hide yes)
			(effects
				(font
					(size 1.016 1.016)
					(thickness 0.1524)
				)
			)
		)
		(duplicate_pad_numbers_are_jumpers no)
		(fp_rect
			(start -0.4318 0.9525)
			(end 0.4318 -0.9525)
			(stroke
				(width 0)
				(type default)
			)
			(fill no)
			(layer "F.CrtYd")
		)
		(fp_rect
			(start -0.4318 0.9525)
			(end 0.4318 -0.9525)
			(stroke
				(width 0)
				(type default)
			)
			(fill no)
			(layer "F.Fab")
		)
		(pad "1" smd custom
			(at 0 -0.4445 90)
			(size 0.1524 0.1524)
			(layers "F.Cu" "F.Mask" "F.Paste")
			(net "P3V3_STBY")
			(options
				(clearance outline)
				(anchor circle)
			)
			(primitives
				(gr_poly
					(pts
						(arc
							(start 0.3048 -0.2032)
							(mid 0.275042 -0.275042)
							(end 0.2032 -0.3048)
						)
						(arc
							(start -0.2032 -0.3048)
							(mid -0.275042 -0.275042)
							(end -0.3048 -0.2032)
						)
						(arc
							(start -0.3048 0.2032)
							(mid -0.275042 0.275042)
							(end -0.2032 0.3048)
						)
						(arc
							(start 0.2032 0.3048)
							(mid 0.275042 0.275042)
							(end 0.3048 0.2032)
						)
					)
					(width 0)
					(fill yes)
				)
			)
		)
		(pad "2" smd custom
			(at 0 0.4445 90)
			(size 0.1524 0.1524)
			(layers "F.Cu" "F.Mask" "F.Paste")
			(net "GND")
			(options
				(clearance outline)
				(anchor circle)
			)
			(primitives
				(gr_poly
					(pts
						(arc
							(start 0.3048 -0.2032)
							(mid 0.275042 -0.275042)
							(end 0.2032 -0.3048)
						)
						(arc
							(start -0.2032 -0.3048)
							(mid -0.275042 -0.275042)
							(end -0.3048 -0.2032)
						)
						(arc
							(start -0.3048 0.2032)
							(mid -0.275042 0.275042)
							(end -0.2032 0.3048)
						)
						(arc
							(start 0.2032 0.3048)
							(mid 0.275042 0.275042)
							(end 0.3048 0.2032)
						)
					)
					(width 0)
					(fill yes)
				)
			)
		)
	)
	(footprint ""
		(layer "B.Cu")
		(at 189.1919 -63.4746 90)
		(property "Reference" "C426"
			(at 0 0 90)
			(layer "B.SilkS")
			(hide yes)
			(effects
				(font
					(size 1.27 1.27)
				)
				(justify mirror)
			)
		)
		(property "Value" "SC1KP50V2KX-1GP"
			(at -1.1811 -2.7051 90)
			(unlocked yes)
			(layer "B.Fab")
			(hide yes)
			(effects
				(font
					(size 1.016 1.016)
					(thickness 0.1524)
				)
				(justify mirror)
			)
		)
		(property "Device Type" "C402H22"
			(at -1.1811 -4.2291 90)
			(unlocked yes)
			(layer "B.Fab")
			(hide yes)
			(effects
				(font
					(size 1.016 1.016)
					(thickness 0.1524)
				)
				(justify mirror)
			)
		)
		(duplicate_pad_numbers_are_jumpers no)
		(fp_rect
			(start 0.4318 0.9525)
			(end -0.4318 -0.9525)
			(stroke
				(width 0)
				(type default)
			)
			(fill no)
			(layer "B.CrtYd")
		)
		(fp_rect
			(start 0.4318 0.9525)
			(end -0.4318 -0.9525)
			(stroke
				(width 0)
				(type default)
			)
			(fill no)
			(layer "B.Fab")
		)
		(pad "1" smd custom
			(at 0 -0.4445 270)
			(size 0.1524 0.1524)
			(layers "B.Cu" "B.Mask" "B.Paste")
			(net "P0V975")
			(options
				(clearance outline)
				(anchor circle)
			)
			(primitives
				(gr_poly
					(pts
						(arc
							(start 0.3048 0.2032)
							(mid 0.275042 0.275042)
							(end 0.2032 0.3048)
						)
						(arc
							(start -0.2032 0.3048)
							(mid -0.275042 0.275042)
							(end -0.3048 0.2032)
						)
						(arc
							(start -0.3048 -0.2032)
							(mid -0.275042 -0.275042)
							(end -0.2032 -0.3048)
						)
						(arc
							(start 0.2032 -0.3048)
							(mid 0.275042 -0.275042)
							(end 0.3048 -0.2032)
						)
					)
					(width 0)
					(fill yes)
				)
			)
		)
		(pad "2" smd custom
			(at 0 0.4445 270)
			(size 0.1524 0.1524)
			(layers "B.Cu" "B.Mask" "B.Paste")
			(net "GND")
			(options
				(clearance outline)
				(anchor circle)
			)
			(primitives
				(gr_poly
					(pts
						(arc
							(start 0.3048 0.2032)
							(mid 0.275042 0.275042)
							(end 0.2032 0.3048)
						)
						(arc
							(start -0.2032 0.3048)
							(mid -0.275042 0.275042)
							(end -0.3048 0.2032)
						)
						(arc
							(start -0.3048 -0.2032)
							(mid -0.275042 -0.275042)
							(end -0.2032 -0.3048)
						)
						(arc
							(start 0.2032 -0.3048)
							(mid 0.275042 -0.275042)
							(end 0.3048 -0.2032)
						)
					)
					(width 0)
					(fill yes)
				)
			)
		)
	)
	(footprint ""
		(layer "B.Cu")
		(at 184.0611 -65.1637 90)
		(property "Reference" "C475"
			(at 0 0 90)
			(layer "B.SilkS")
			(hide yes)
			(effects
				(font
					(size 1.27 1.27)
				)
				(justify mirror)
			)
		)
		(property "Value" "SC1KP50V2KX-1GP"
			(at -1.1811 -2.7051 90)
			(unlocked yes)
			(layer "B.Fab")
			(hide yes)
			(effects
				(font
					(size 1.016 1.016)
					(thickness 0.1524)
				)
				(justify mirror)
			)
		)
		(property "Device Type" "C402H22"
			(at -1.1811 -4.2291 90)
			(unlocked yes)
			(layer "B.Fab")
			(hide yes)
			(effects
				(font
					(size 1.016 1.016)
					(thickness 0.1524)
				)
				(justify mirror)
			)
		)
		(duplicate_pad_numbers_are_jumpers no)
		(fp_rect
			(start 0.4318 0.9525)
			(end -0.4318 -0.9525)
			(stroke
				(width 0)
				(type default)
			)
			(fill no)
			(layer "B.CrtYd")
		)
		(fp_rect
			(start 0.4318 0.9525)
			(end -0.4318 -0.9525)
			(stroke
				(width 0)
				(type default)
			)
			(fill no)
			(layer "B.Fab")
		)
		(pad "1" smd custom
			(at 0 -0.4445 270)
			(size 0.1524 0.1524)
			(layers "B.Cu" "B.Mask" "B.Paste")
			(net "P1V8")
			(options
				(clearance outline)
				(anchor circle)
			)
			(primitives
				(gr_poly
					(pts
						(arc
							(start 0.3048 0.2032)
							(mid 0.275042 0.275042)
							(end 0.2032 0.3048)
						)
						(arc
							(start -0.2032 0.3048)
							(mid -0.275042 0.275042)
							(end -0.3048 0.2032)
						)
						(arc
							(start -0.3048 -0.2032)
							(mid -0.275042 -0.275042)
							(end -0.2032 -0.3048)
						)
						(arc
							(start 0.2032 -0.3048)
							(mid 0.275042 -0.275042)
							(end 0.3048 -0.2032)
						)
					)
					(width 0)
					(fill yes)
				)
			)
		)
		(pad "2" smd custom
			(at 0 0.4445 270)
			(size 0.1524 0.1524)
			(layers "B.Cu" "B.Mask" "B.Paste")
			(net "GND")
			(options
				(clearance outline)
				(anchor circle)
			)
			(primitives
				(gr_poly
					(pts
						(arc
							(start 0.3048 0.2032)
							(mid 0.275042 0.275042)
							(end 0.2032 0.3048)
						)
						(arc
							(start -0.2032 0.3048)
							(mid -0.275042 0.275042)
							(end -0.3048 0.2032)
						)
						(arc
							(start -0.3048 -0.2032)
							(mid -0.275042 -0.275042)
							(end -0.2032 -0.3048)
						)
						(arc
							(start 0.2032 -0.3048)
							(mid 0.275042 -0.275042)
							(end 0.3048 -0.2032)
						)
					)
					(width 0)
					(fill yes)
				)
			)
		)
	)
	(footprint ""
		(layer "B.Cu")
		(at 54.2036 -163.1188 -90)
		(property "Reference" "R401"
			(at 0 0 90)
			(layer "B.SilkS")
			(hide yes)
			(effects
				(font
					(size 1.27 1.27)
				)
				(justify mirror)
			)
		)
		(property "Value" "7K87R2F-GP"
			(at -0.064008 -3.993896 270)
			(unlocked yes)
			(layer "B.Fab")
			(hide yes)
			(effects
				(font
					(size 1.016 1.016)
					(thickness 0.1524)
				)
				(justify mirror)
			)
		)
		(property "Device Type" "R402H16"
			(at -0.064008 -5.517896 270)
			(unlocked yes)
			(layer "B.Fab")
			(hide yes)
			(effects
				(font
					(size 1.016 1.016)
					(thickness 0.1524)
				)
				(justify mirror)
			)
		)
		(duplicate_pad_numbers_are_jumpers no)
		(fp_line
			(start -0.508 -0.9398)
			(end 0.508 -0.9398)
			(stroke
				(width 0.1524)
				(type default)
			)
			(layer "B.SilkS")
		)
		(fp_line
			(start 0.508 -0.9398)
			(end 0.508 0.9398)
			(stroke
				(width 0.1524)
				(type default)
			)
			(layer "B.SilkS")
		)
		(fp_rect
			(start 0.508 0.9398)
			(end -0.508 -0.9398)
			(stroke
				(width 0)
				(type default)
			)
			(fill no)
			(layer "B.CrtYd")
		)
		(fp_rect
			(start 0.508 0.9398)
			(end -0.508 -0.9398)
			(stroke
				(width 0)
				(type default)
			)
			(fill no)
			(layer "B.Fab")
		)
		(pad "1" smd custom
			(at 0 -0.4445 90)
			(size 0.1397 0.1397)
			(layers "B.Cu" "B.Mask" "B.Paste")
			(net "P12V_STBY")
			(options
				(clearance outline)
				(anchor circle)
			)
			(primitives
				(gr_poly
					(pts
						(arc
							(start -0.1778 0.2794)
							(mid -0.249642 0.249642)
							(end -0.2794 0.1778)
						)
						(arc
							(start -0.2794 -0.1778)
							(mid -0.249642 -0.249642)
							(end -0.1778 -0.2794)
						)
						(arc
							(start 0.1778 -0.2794)
							(mid 0.249642 -0.249642)
							(end 0.2794 -0.1778)
						)
						(arc
							(start 0.2794 0.1778)
							(mid 0.249642 0.249642)
							(end 0.1778 0.2794)
						)
					)
					(width 0)
					(fill yes)
				)
			)
		)
		(pad "2" smd custom
			(at 0 0.4445 90)
			(size 0.1397 0.1397)
			(layers "B.Cu" "B.Mask" "B.Paste")
			(net "ADC_12V")
			(options
				(clearance outline)
				(anchor circle)
			)
			(primitives
				(gr_poly
					(pts
						(arc
							(start -0.1778 0.2794)
							(mid -0.249642 0.249642)
							(end -0.2794 0.1778)
						)
						(arc
							(start -0.2794 -0.1778)
							(mid -0.249642 -0.249642)
							(end -0.1778 -0.2794)
						)
						(arc
							(start 0.1778 -0.2794)
							(mid 0.249642 -0.249642)
							(end 0.2794 -0.1778)
						)
						(arc
							(start 0.2794 0.1778)
							(mid 0.249642 0.249642)
							(end 0.1778 0.2794)
						)
					)
					(width 0)
					(fill yes)
				)
			)
		)
	)
	(footprint ""
		(layer "B.Cu")
		(at 211.836 -88.138 90)
		(property "Reference" "L18"
			(at 0 0 90)
			(layer "B.SilkS")
			(hide yes)
			(effects
				(font
					(size 1.27 1.27)
				)
				(justify mirror)
			)
		)
		(property "Value" "MPZ2012S601AT-GP"
			(at 0 -4.2418 90)
			(unlocked yes)
			(layer "B.Fab")
			(hide yes)
			(effects
				(font
					(size 1.016 1.016)
					(thickness 0.1524)
				)
				(justify mirror)
			)
		)
		(property "Device Type" "L805H42"
			(at 0 -5.7912 90)
			(unlocked yes)
			(layer "B.Fab")
			(hide yes)
			(effects
				(font
					(size 1.016 1.016)
					(thickness 0.1524)
				)
				(justify mirror)
			)
		)
		(duplicate_pad_numbers_are_jumpers no)
		(fp_line
			(start 0.889 -1.7018)
			(end -0.889 -1.7018)
			(stroke
				(width 0.1524)
				(type default)
			)
			(layer "B.SilkS")
		)
		(fp_line
			(start -0.889 -1.7018)
			(end -0.889 1.7018)
			(stroke
				(width 0.1524)
				(type default)
			)
			(layer "B.SilkS")
		)
		(fp_line
			(start 0.889 1.7018)
			(end 0.889 -1.7018)
			(stroke
				(width 0.1524)
				(type default)
			)
			(layer "B.SilkS")
		)
		(fp_line
			(start -0.889 1.7018)
			(end 0.889 1.7018)
			(stroke
				(width 0.1524)
				(type default)
			)
			(layer "B.SilkS")
		)
		(fp_rect
			(start 0.9652 1.778)
			(end -0.9652 -1.778)
			(stroke
				(width 0)
				(type default)
			)
			(fill no)
			(layer "B.CrtYd")
		)
		(fp_rect
			(start 0.9652 1.778)
			(end -0.9652 -1.778)
			(stroke
				(width 0)
				(type default)
			)
			(fill no)
			(layer "B.Fab")
		)
		(pad "1" smd rect
			(at 0 -0.9652 270)
			(size 1.397 1.143)
			(layers "B.Cu" "B.Mask" "B.Paste")
			(net "SAS0_VDDH")
		)
		(pad "2" smd rect
			(at 0 0.9652 270)
			(size 1.397 1.143)
			(layers "B.Cu" "B.Mask" "B.Paste")
			(net "P1V8")
		)
	)
	(footprint ""
		(layer "B.Cu")
		(at 122.3264 -14.9606 -90)
		(property "Reference" "R743"
			(at 0 0 90)
			(layer "B.SilkS")
			(hide yes)
			(effects
				(font
					(size 1.27 1.27)
				)
				(justify mirror)
			)
		)
		(property "Value" "100KR2F-L1-GP"
			(at -0.064008 -3.993896 270)
			(unlocked yes)
			(layer "B.Fab")
			(hide yes)
			(effects
				(font
					(size 1.016 1.016)
					(thickness 0.1524)
				)
				(justify mirror)
			)
		)
		(property "Device Type" "R402H16"
			(at -0.064008 -5.517896 270)
			(unlocked yes)
			(layer "B.Fab")
			(hide yes)
			(effects
				(font
					(size 1.016 1.016)
					(thickness 0.1524)
				)
				(justify mirror)
			)
		)
		(duplicate_pad_numbers_are_jumpers no)
		(fp_line
			(start -0.508 -0.9398)
			(end 0.508 -0.9398)
			(stroke
				(width 0.1524)
				(type default)
			)
			(layer "B.SilkS")
		)
		(fp_line
			(start 0.508 -0.9398)
			(end 0.508 0.9398)
			(stroke
				(width 0.1524)
				(type default)
			)
			(layer "B.SilkS")
		)
		(fp_rect
			(start 0.508 0.9398)
			(end -0.508 -0.9398)
			(stroke
				(width 0)
				(type default)
			)
			(fill no)
			(layer "B.CrtYd")
		)
		(fp_rect
			(start 0.508 0.9398)
			(end -0.508 -0.9398)
			(stroke
				(width 0)
				(type default)
			)
			(fill no)
			(layer "B.Fab")
		)
		(pad "1" smd custom
			(at 0 -0.4445 90)
			(size 0.1397 0.1397)
			(layers "B.Cu" "B.Mask" "B.Paste")
			(net "P12V_IOM")
			(options
				(clearance outline)
				(anchor circle)
			)
			(primitives
				(gr_poly
					(pts
						(arc
							(start -0.1778 0.2794)
							(mid -0.249642 0.249642)
							(end -0.2794 0.1778)
						)
						(arc
							(start -0.2794 -0.1778)
							(mid -0.249642 -0.249642)
							(end -0.1778 -0.2794)
						)
						(arc
							(start 0.1778 -0.2794)
							(mid 0.249642 -0.249642)
							(end 0.2794 -0.1778)
						)
						(arc
							(start 0.2794 0.1778)
							(mid 0.249642 0.249642)
							(end 0.1778 0.2794)
						)
					)
					(width 0)
					(fill yes)
				)
			)
		)
		(pad "2" smd custom
			(at 0 0.4445 90)
			(size 0.1397 0.1397)
			(layers "B.Cu" "B.Mask" "B.Paste")
			(net "IOM_ADM1278_EN")
			(options
				(clearance outline)
				(anchor circle)
			)
			(primitives
				(gr_poly
					(pts
						(arc
							(start -0.1778 0.2794)
							(mid -0.249642 0.249642)
							(end -0.2794 0.1778)
						)
						(arc
							(start -0.2794 -0.1778)
							(mid -0.249642 -0.249642)
							(end -0.1778 -0.2794)
						)
						(arc
							(start 0.1778 -0.2794)
							(mid 0.249642 -0.249642)
							(end 0.2794 -0.1778)
						)
						(arc
							(start 0.2794 0.1778)
							(mid 0.249642 0.249642)
							(end 0.1778 0.2794)
						)
					)
					(width 0)
					(fill yes)
				)
			)
		)
	)
	(footprint ""
		(layer "B.Cu")
		(at 55.0164 -127.24892)
		(property "Reference" "U37"
			(at 0 0 0)
			(layer "B.SilkS")
			(hide yes)
			(effects
				(font
					(size 1.27 1.27)
				)
				(justify mirror)
			)
		)
		(property "Value" "SN74LVC1G08DCKR-GP"
			(at 2.3368 -8.6868 0)
			(unlocked yes)
			(layer "B.Fab")
			(hide yes)
			(effects
				(font
					(size 1.016 1.016)
					(thickness 0.1524)
				)
				(justify mirror)
			)
		)
		(property "Device Type" "SC70-5H44"
			(at 2.3114 -10.414 0)
			(unlocked yes)
			(layer "B.Fab")
			(hide yes)
			(effects
				(font
					(size 1.016 1.016)
					(thickness 0.1524)
				)
				(justify mirror)
			)
		)
		(duplicate_pad_numbers_are_jumpers no)
		(fp_line
			(start -1.3843 -1.8034)
			(end -1.3843 -1.1176)
			(stroke
				(width 0.3302)
				(type default)
			)
			(layer "B.SilkS")
		)
		(fp_line
			(start -1.27 -1.7018)
			(end -1.27 1.7018)
			(stroke
				(width 0.1524)
				(type default)
			)
			(layer "B.SilkS")
		)
		(fp_line
			(start -1.27 1.7018)
			(end 1.27 1.7018)
			(stroke
				(width 0.1524)
				(type default)
			)
			(layer "B.SilkS")
		)
		(fp_line
			(start -0.6604 -1.8034)
			(end -1.3843 -1.8034)
			(stroke
				(width 0.3302)
				(type default)
			)
			(layer "B.SilkS")
		)
		(fp_line
			(start 1.27 -1.7018)
			(end -1.27 -1.7018)
			(stroke
				(width 0.1524)
				(type default)
			)
			(layer "B.SilkS")
		)
		(fp_line
			(start 1.27 1.7018)
			(end 1.27 -1.7018)
			(stroke
				(width 0.1524)
				(type default)
			)
			(layer "B.SilkS")
		)
		(fp_rect
			(start 1.524 1.9558)
			(end -1.524 -1.9558)
			(stroke
				(width 0)
				(type default)
			)
			(fill no)
			(layer "B.CrtYd")
		)
		(fp_poly
			(pts
				(xy 1.524 -1.9558) (xy -1.524 -1.9558) (xy -1.524 1.9558) (xy 1.524 1.9558)
			)
			(stroke
				(width 0)
				(type default)
			)
			(fill no)
			(layer "B.Fab")
		)
		(pad "1" smd rect
			(at -0.65024 -0.8255 180)
			(size 0.4064 1.2192)
			(layers "B.Cu" "B.Mask" "B.Paste")
			(net "RST_BMC_EXTRST_N_1")
		)
		(pad "2" smd rect
			(at 0 -0.8255 180)
			(size 0.4064 1.2192)
			(layers "B.Cu" "B.Mask" "B.Paste")
			(net "DEBUG_RST_BTN_N_R")
		)
		(pad "3" smd rect
			(at 0.65024 -0.8255 180)
			(size 0.4064 1.2192)
			(layers "B.Cu" "B.Mask" "B.Paste")
			(net "GND")
		)
		(pad "4" smd rect
			(at 0.65024 0.8255 180)
			(size 0.4064 1.2192)
			(layers "B.Cu" "B.Mask" "B.Paste")
			(net "RST_BMC_EXTRST_N")
		)
		(pad "5" smd rect
			(at -0.65024 0.8255 180)
			(size 0.4064 1.2192)
			(layers "B.Cu" "B.Mask" "B.Paste")
			(net "P3V3_STBY")
		)
	)
	(footprint ""
		(layer "B.Cu")
		(at 61.0362 -146.0754 90)
		(property "Reference" "R163"
			(at 0 0 90)
			(layer "B.SilkS")
			(hide yes)
			(effects
				(font
					(size 1.27 1.27)
				)
				(justify mirror)
			)
		)
		(property "Value" "0R2J-2-GP"
			(at -0.064008 -3.993896 90)
			(unlocked yes)
			(layer "B.Fab")
			(hide yes)
			(effects
				(font
					(size 1.016 1.016)
					(thickness 0.1524)
				)
				(justify mirror)
			)
		)
		(property "Device Type" "R402H16"
			(at -0.064008 -5.517896 90)
			(unlocked yes)
			(layer "B.Fab")
			(hide yes)
			(effects
				(font
					(size 1.016 1.016)
					(thickness 0.1524)
				)
				(justify mirror)
			)
		)
		(duplicate_pad_numbers_are_jumpers no)
		(fp_line
			(start 0.508 -0.9398)
			(end 0.508 0.9398)
			(stroke
				(width 0.1524)
				(type default)
			)
			(layer "B.SilkS")
		)
		(fp_line
			(start -0.508 -0.9398)
			(end 0.508 -0.9398)
			(stroke
				(width 0.1524)
				(type default)
			)
			(layer "B.SilkS")
		)
		(fp_rect
			(start 0.508 0.9398)
			(end -0.508 -0.9398)
			(stroke
				(width 0)
				(type default)
			)
			(fill no)
			(layer "B.CrtYd")
		)
		(fp_rect
			(start 0.508 0.9398)
			(end -0.508 -0.9398)
			(stroke
				(width 0)
				(type default)
			)
			(fill no)
			(layer "B.Fab")
		)
		(pad "1" smd custom
			(at 0 -0.4445 270)
			(size 0.1397 0.1397)
			(layers "B.Cu" "B.Mask" "B.Paste")
			(net "BMC_SMB13_CLK")
			(options
				(clearance outline)
				(anchor circle)
			)
			(primitives
				(gr_poly
					(pts
						(arc
							(start -0.1778 0.2794)
							(mid -0.249642 0.249642)
							(end -0.2794 0.1778)
						)
						(arc
							(start -0.2794 -0.1778)
							(mid -0.249642 -0.249642)
							(end -0.1778 -0.2794)
						)
						(arc
							(start 0.1778 -0.2794)
							(mid 0.249642 -0.249642)
							(end 0.2794 -0.1778)
						)
						(arc
							(start 0.2794 0.1778)
							(mid 0.249642 0.249642)
							(end 0.1778 0.2794)
						)
					)
					(width 0)
					(fill yes)
				)
			)
		)
		(pad "2" smd custom
			(at 0 0.4445 270)
			(size 0.1397 0.1397)
			(layers "B.Cu" "B.Mask" "B.Paste")
			(net "I2C_MEZZ_FRU_SENSOR_SCL")
			(options
				(clearance outline)
				(anchor circle)
			)
			(primitives
				(gr_poly
					(pts
						(arc
							(start -0.1778 0.2794)
							(mid -0.249642 0.249642)
							(end -0.2794 0.1778)
						)
						(arc
							(start -0.2794 -0.1778)
							(mid -0.249642 -0.249642)
							(end -0.1778 -0.2794)
						)
						(arc
							(start 0.1778 -0.2794)
							(mid 0.249642 -0.249642)
							(end 0.2794 -0.1778)
						)
						(arc
							(start 0.2794 0.1778)
							(mid 0.249642 0.249642)
							(end 0.1778 0.2794)
						)
					)
					(width 0)
					(fill yes)
				)
			)
		)
	)
	(footprint ""
		(layer "B.Cu")
		(at 61.0108 -141.859 90)
		(property "Reference" "R185"
			(at 0 0 90)
			(layer "B.SilkS")
			(hide yes)
			(effects
				(font
					(size 1.27 1.27)
				)
				(justify mirror)
			)
		)
		(property "Value" "2K2R2F-GP"
			(at -0.064008 -3.993896 90)
			(unlocked yes)
			(layer "B.Fab")
			(hide yes)
			(effects
				(font
					(size 1.016 1.016)
					(thickness 0.1524)
				)
				(justify mirror)
			)
		)
		(property "Device Type" "R402H16"
			(at -0.064008 -5.517896 90)
			(unlocked yes)
			(layer "B.Fab")
			(hide yes)
			(effects
				(font
					(size 1.016 1.016)
					(thickness 0.1524)
				)
				(justify mirror)
			)
		)
		(duplicate_pad_numbers_are_jumpers no)
		(fp_line
			(start 0.508 -0.9398)
			(end 0.508 0.9398)
			(stroke
				(width 0.1524)
				(type default)
			)
			(layer "B.SilkS")
		)
		(fp_line
			(start -0.508 -0.9398)
			(end 0.508 -0.9398)
			(stroke
				(width 0.1524)
				(type default)
			)
			(layer "B.SilkS")
		)
		(fp_rect
			(start 0.508 0.9398)
			(end -0.508 -0.9398)
			(stroke
				(width 0)
				(type default)
			)
			(fill no)
			(layer "B.CrtYd")
		)
		(fp_rect
			(start 0.508 0.9398)
			(end -0.508 -0.9398)
			(stroke
				(width 0)
				(type default)
			)
			(fill no)
			(layer "B.Fab")
		)
		(pad "1" smd custom
			(at 0 -0.4445 270)
			(size 0.1397 0.1397)
			(layers "B.Cu" "B.Mask" "B.Paste")
			(net "I2C_M2_2_SCL")
			(options
				(clearance outline)
				(anchor circle)
			)
			(primitives
				(gr_poly
					(pts
						(arc
							(start -0.1778 0.2794)
							(mid -0.249642 0.249642)
							(end -0.2794 0.1778)
						)
						(arc
							(start -0.2794 -0.1778)
							(mid -0.249642 -0.249642)
							(end -0.1778 -0.2794)
						)
						(arc
							(start 0.1778 -0.2794)
							(mid 0.249642 -0.249642)
							(end 0.2794 -0.1778)
						)
						(arc
							(start 0.2794 0.1778)
							(mid 0.249642 0.249642)
							(end 0.1778 0.2794)
						)
					)
					(width 0)
					(fill yes)
				)
			)
		)
		(pad "2" smd custom
			(at 0 0.4445 270)
			(size 0.1397 0.1397)
			(layers "B.Cu" "B.Mask" "B.Paste")
			(net "P3V3_STBY")
			(options
				(clearance outline)
				(anchor circle)
			)
			(primitives
				(gr_poly
					(pts
						(arc
							(start -0.1778 0.2794)
							(mid -0.249642 0.249642)
							(end -0.2794 0.1778)
						)
						(arc
							(start -0.2794 -0.1778)
							(mid -0.249642 -0.249642)
							(end -0.1778 -0.2794)
						)
						(arc
							(start 0.1778 -0.2794)
							(mid 0.249642 -0.249642)
							(end 0.2794 -0.1778)
						)
						(arc
							(start 0.2794 0.1778)
							(mid 0.249642 0.249642)
							(end 0.1778 0.2794)
						)
					)
					(width 0)
					(fill yes)
				)
			)
		)
	)
	(footprint ""
		(layer "B.Cu")
		(at 91.86672 -135.2296 -90)
		(property "Reference" "U101"
			(at 0 0 90)
			(layer "B.SilkS")
			(hide yes)
			(effects
				(font
					(size 1.27 1.27)
				)
				(justify mirror)
			)
		)
		(property "Value" "SNLVC1G126DCKR-GP"
			(at 2.3368 -8.6868 270)
			(unlocked yes)
			(layer "B.Fab")
			(hide yes)
			(effects
				(font
					(size 1.016 1.016)
					(thickness 0.1524)
				)
				(justify mirror)
			)
		)
		(property "Device Type" "SC70-5H44"
			(at 2.3114 -10.414 270)
			(unlocked yes)
			(layer "B.Fab")
			(hide yes)
			(effects
				(font
					(size 1.016 1.016)
					(thickness 0.1524)
				)
				(justify mirror)
			)
		)
		(duplicate_pad_numbers_are_jumpers no)
		(fp_line
			(start -1.27 1.7018)
			(end 1.27 1.7018)
			(stroke
				(width 0.1524)
				(type default)
			)
			(layer "B.SilkS")
		)
		(fp_line
			(start 1.27 1.7018)
			(end 1.27 -1.7018)
			(stroke
				(width 0.1524)
				(type default)
			)
			(layer "B.SilkS")
		)
		(fp_line
			(start -1.27 -1.7018)
			(end -1.27 1.7018)
			(stroke
				(width 0.1524)
				(type default)
			)
			(layer "B.SilkS")
		)
		(fp_line
			(start 1.27 -1.7018)
			(end -1.27 -1.7018)
			(stroke
				(width 0.1524)
				(type default)
			)
			(layer "B.SilkS")
		)
		(fp_line
			(start -1.3843 -1.8034)
			(end -1.3843 -1.1176)
			(stroke
				(width 0.3302)
				(type default)
			)
			(layer "B.SilkS")
		)
		(fp_line
			(start -0.6604 -1.8034)
			(end -1.3843 -1.8034)
			(stroke
				(width 0.3302)
				(type default)
			)
			(layer "B.SilkS")
		)
		(fp_rect
			(start 1.524 1.9558)
			(end -1.524 -1.9558)
			(stroke
				(width 0)
				(type default)
			)
			(fill no)
			(layer "B.CrtYd")
		)
		(fp_poly
			(pts
				(xy 1.524 -1.9558) (xy -1.524 -1.9558) (xy -1.524 1.9558) (xy 1.524 1.9558)
			)
			(stroke
				(width 0)
				(type default)
			)
			(fill no)
			(layer "B.Fab")
		)
		(pad "1" smd rect
			(at -0.65024 -0.8255 90)
			(size 0.4064 1.2192)
			(layers "B.Cu" "B.Mask" "B.Paste")
			(net "DEBUG_CARD_PRSNT")
		)
		(pad "2" smd rect
			(at 0 -0.8255 90)
			(size 0.4064 1.2192)
			(layers "B.Cu" "B.Mask" "B.Paste")
			(net "UART_IOM_RX")
		)
		(pad "3" smd rect
			(at 0.65024 -0.8255 90)
			(size 0.4064 1.2192)
			(layers "B.Cu" "B.Mask" "B.Paste")
			(net "GND")
		)
		(pad "4" smd rect
			(at 0.65024 0.8255 90)
			(size 0.4064 1.2192)
			(layers "B.Cu" "B.Mask" "B.Paste")
			(net "DEBUG_UART_IOM_RX")
		)
		(pad "5" smd rect
			(at -0.65024 0.8255 90)
			(size 0.4064 1.2192)
			(layers "B.Cu" "B.Mask" "B.Paste")
			(net "P3V3_STBY")
		)
	)
	(footprint ""
		(layer "B.Cu")
		(at 10.200132 -138.145774 90)
		(property "Reference" "R246"
			(at 0 0 90)
			(layer "B.SilkS")
			(hide yes)
			(effects
				(font
					(size 1.27 1.27)
				)
				(justify mirror)
			)
		)
		(property "Value" "120R2F-GP"
			(at -0.064008 -3.993896 90)
			(unlocked yes)
			(layer "B.Fab")
			(hide yes)
			(effects
				(font
					(size 1.016 1.016)
					(thickness 0.1524)
				)
				(justify mirror)
			)
		)
		(property "Device Type" "R402H16"
			(at -0.064008 -5.517896 90)
			(unlocked yes)
			(layer "B.Fab")
			(hide yes)
			(effects
				(font
					(size 1.016 1.016)
					(thickness 0.1524)
				)
				(justify mirror)
			)
		)
		(duplicate_pad_numbers_are_jumpers no)
		(fp_line
			(start 0.508 -0.9398)
			(end 0.508 0.9398)
			(stroke
				(width 0.1524)
				(type default)
			)
			(layer "B.SilkS")
		)
		(fp_line
			(start -0.508 -0.9398)
			(end 0.508 -0.9398)
			(stroke
				(width 0.1524)
				(type default)
			)
			(layer "B.SilkS")
		)
		(fp_rect
			(start 0.508 0.9398)
			(end -0.508 -0.9398)
			(stroke
				(width 0)
				(type default)
			)
			(fill no)
			(layer "B.CrtYd")
		)
		(fp_rect
			(start 0.508 0.9398)
			(end -0.508 -0.9398)
			(stroke
				(width 0)
				(type default)
			)
			(fill no)
			(layer "B.Fab")
		)
		(pad "1" smd custom
			(at 0 -0.4445 270)
			(size 0.1397 0.1397)
			(layers "B.Cu" "B.Mask" "B.Paste")
			(net "GND")
			(options
				(clearance outline)
				(anchor circle)
			)
			(primitives
				(gr_poly
					(pts
						(arc
							(start -0.1778 0.2794)
							(mid -0.249642 0.249642)
							(end -0.2794 0.1778)
						)
						(arc
							(start -0.2794 -0.1778)
							(mid -0.249642 -0.249642)
							(end -0.1778 -0.2794)
						)
						(arc
							(start 0.1778 -0.2794)
							(mid 0.249642 -0.249642)
							(end 0.2794 -0.1778)
						)
						(arc
							(start 0.2794 0.1778)
							(mid 0.249642 0.249642)
							(end 0.1778 0.2794)
						)
					)
					(width 0)
					(fill yes)
				)
			)
		)
		(pad "2" smd custom
			(at 0 0.4445 270)
			(size 0.1397 0.1397)
			(layers "B.Cu" "B.Mask" "B.Paste")
			(net "MEMA_6")
			(options
				(clearance outline)
				(anchor circle)
			)
			(primitives
				(gr_poly
					(pts
						(arc
							(start -0.1778 0.2794)
							(mid -0.249642 0.249642)
							(end -0.2794 0.1778)
						)
						(arc
							(start -0.2794 -0.1778)
							(mid -0.249642 -0.249642)
							(end -0.1778 -0.2794)
						)
						(arc
							(start 0.1778 -0.2794)
							(mid 0.249642 -0.249642)
							(end 0.2794 -0.1778)
						)
						(arc
							(start 0.2794 0.1778)
							(mid 0.249642 0.249642)
							(end 0.1778 0.2794)
						)
					)
					(width 0)
					(fill yes)
				)
			)
		)
	)
	(footprint ""
		(layer "B.Cu")
		(at 60.7568 -133.858)
		(property "Reference" "TP192"
			(at 0 0 0)
			(layer "B.SilkS")
			(hide yes)
			(effects
				(font
					(size 1.27 1.27)
				)
				(justify mirror)
			)
		)
		(property "Value" "TPAD28-2-GP"
			(at 0.0127 -1.6637 0)
			(unlocked yes)
			(layer "B.Fab")
			(hide yes)
			(effects
				(font
					(size 1.016 1.016)
					(thickness 0.1524)
				)
				(justify mirror)
			)
		)
		(property "Device Type" "TPAD28"
			(at 0.0127 -3.1877 0)
			(unlocked yes)
			(layer "B.Fab")
			(hide yes)
			(effects
				(font
					(size 1.016 1.016)
					(thickness 0.1524)
				)
				(justify mirror)
			)
		)
		(duplicate_pad_numbers_are_jumpers no)
		(fp_poly
			(pts
				(arc
					(start 0.3556 0)
					(mid -0.3556 0)
					(end 0.3556 0)
				)
			)
			(stroke
				(width 0)
				(type default)
			)
			(fill no)
			(layer "B.CrtYd")
		)
		(fp_poly
			(pts
				(arc
					(start 0.6096 0)
					(mid -0.6096 0)
					(end 0.6096 0)
				)
			)
			(stroke
				(width 0)
				(type default)
			)
			(fill no)
			(layer "B.Fab")
		)
		(pad "1" smd circle
			(at 0 0 180)
			(size 0.7112 0.7112)
			(layers "B.Cu" "B.Mask" "B.Paste")
			(net "TP_BMC_EXT1_LED_B")
		)
	)
	(footprint ""
		(layer "B.Cu")
		(at 190.0174 -71.4502)
		(property "Reference" "TP159"
			(at 0 0 0)
			(layer "B.SilkS")
			(hide yes)
			(effects
				(font
					(size 1.27 1.27)
				)
				(justify mirror)
			)
		)
		(property "Value" "TPAD28-2-GP"
			(at 0.0127 -1.6637 0)
			(unlocked yes)
			(layer "B.Fab")
			(hide yes)
			(effects
				(font
					(size 1.016 1.016)
					(thickness 0.1524)
				)
				(justify mirror)
			)
		)
		(property "Device Type" "TPAD28"
			(at 0.0127 -3.1877 0)
			(unlocked yes)
			(layer "B.Fab")
			(hide yes)
			(effects
				(font
					(size 1.016 1.016)
					(thickness 0.1524)
				)
				(justify mirror)
			)
		)
		(duplicate_pad_numbers_are_jumpers no)
		(fp_poly
			(pts
				(arc
					(start 0.3556 0)
					(mid -0.3556 0)
					(end 0.3556 0)
				)
			)
			(stroke
				(width 0)
				(type default)
			)
			(fill no)
			(layer "B.CrtYd")
		)
		(fp_poly
			(pts
				(arc
					(start 0.6096 0)
					(mid -0.6096 0)
					(end 0.6096 0)
				)
			)
			(stroke
				(width 0)
				(type default)
			)
			(fill no)
			(layer "B.Fab")
		)
		(pad "1" smd circle
			(at 0 0 180)
			(size 0.7112 0.7112)
			(layers "B.Cu" "B.Mask" "B.Paste")
			(net "SPARE3")
		)
	)
	(footprint ""
		(layer "B.Cu")
		(at 51.9938 -132.6388)
		(property "Reference" "C109"
			(at 0 0 0)
			(layer "B.SilkS")
			(hide yes)
			(effects
				(font
					(size 1.27 1.27)
				)
				(justify mirror)
			)
		)
		(property "Value" "SC1U16V3KX-5GP"
			(at 0 -2.8194 0)
			(unlocked yes)
			(layer "B.Fab")
			(hide yes)
			(effects
				(font
					(size 1.016 1.016)
					(thickness 0.1524)
				)
				(justify mirror)
			)
		)
		(property "Device Type" "C603H36"
			(at 0 -4.3434 0)
			(unlocked yes)
			(layer "B.Fab")
			(hide yes)
			(effects
				(font
					(size 1.016 1.016)
					(thickness 0.1524)
				)
				(justify mirror)
			)
		)
		(duplicate_pad_numbers_are_jumpers no)
		(fp_line
			(start -0.508 0)
			(end 0.508 0)
			(stroke
				(width 0.2032)
				(type default)
			)
			(layer "B.SilkS")
		)
		(fp_rect
			(start 0.5842 1.3335)
			(end -0.5842 -1.3335)
			(stroke
				(width 0)
				(type default)
			)
			(fill no)
			(layer "B.CrtYd")
		)
		(fp_rect
			(start 0.5842 1.3335)
			(end -0.5842 -1.3335)
			(stroke
				(width 0)
				(type default)
			)
			(fill no)
			(layer "B.Fab")
		)
		(pad "1" smd custom
			(at 0 -0.762 180)
			(size 0.2159 0.2159)
			(layers "B.Cu" "B.Mask" "B.Paste")
			(net "P1V15_STBY")
			(options
				(clearance outline)
				(anchor circle)
			)
			(primitives
				(gr_poly
					(pts
						(arc
							(start -0.3302 0.4318)
							(mid -0.402042 0.402042)
							(end -0.4318 0.3302)
						)
						(arc
							(start -0.4318 -0.3302)
							(mid -0.402042 -0.402042)
							(end -0.3302 -0.4318)
						)
						(arc
							(start 0.3302 -0.4318)
							(mid 0.402042 -0.402042)
							(end 0.4318 -0.3302)
						)
						(arc
							(start 0.4318 0.3302)
							(mid 0.402042 0.402042)
							(end 0.3302 0.4318)
						)
					)
					(width 0)
					(fill yes)
				)
			)
		)
		(pad "2" smd custom
			(at 0 0.762 180)
			(size 0.2159 0.2159)
			(layers "B.Cu" "B.Mask" "B.Paste")
			(net "GND")
			(options
				(clearance outline)
				(anchor circle)
			)
			(primitives
				(gr_poly
					(pts
						(arc
							(start -0.3302 0.4318)
							(mid -0.402042 0.402042)
							(end -0.4318 0.3302)
						)
						(arc
							(start -0.4318 -0.3302)
							(mid -0.402042 -0.402042)
							(end -0.3302 -0.4318)
						)
						(arc
							(start 0.3302 -0.4318)
							(mid 0.402042 -0.402042)
							(end 0.4318 -0.3302)
						)
						(arc
							(start 0.4318 0.3302)
							(mid 0.402042 0.402042)
							(end 0.3302 0.4318)
						)
					)
					(width 0)
					(fill yes)
				)
			)
		)
	)
	(footprint ""
		(layer "B.Cu")
		(at 195.6562 -69.5452 180)
		(property "Reference" "C384"
			(at 0 0 0)
			(layer "B.SilkS")
			(hide yes)
			(effects
				(font
					(size 1.27 1.27)
				)
				(justify mirror)
			)
		)
		(property "Value" "SC10U6D3V5KX-4GP"
			(at 0.0762 -6.1214 180)
			(unlocked yes)
			(layer "B.Fab")
			(hide yes)
			(effects
				(font
					(size 1.016 1.016)
					(thickness 0.1524)
				)
				(justify mirror)
			)
		)
		(property "Device Type" "C805H58"
			(at 0.0762 -8.1534 180)
			(unlocked yes)
			(layer "B.Fab")
			(hide yes)
			(effects
				(font
					(size 1.016 1.016)
					(thickness 0.1524)
				)
				(justify mirror)
			)
		)
		(duplicate_pad_numbers_are_jumpers no)
		(fp_line
			(start -0.635 0)
			(end 0.635 0)
			(stroke
				(width 0.508)
				(type default)
			)
			(layer "B.SilkS")
		)
		(fp_rect
			(start 0.9652 1.778)
			(end -0.9652 -1.778)
			(stroke
				(width 0)
				(type default)
			)
			(fill no)
			(layer "B.CrtYd")
		)
		(fp_poly
			(pts
				(xy 0.9652 -1.778) (xy -0.9652 -1.778) (xy -0.9652 1.778) (xy 0.9652 1.778)
			)
			(stroke
				(width 0)
				(type default)
			)
			(fill no)
			(layer "B.Fab")
		)
		(pad "1" smd rect
			(at 0 -0.9652)
			(size 1.397 1.143)
			(layers "B.Cu" "B.Mask" "B.Paste")
			(net "P0V975")
		)
		(pad "2" smd rect
			(at 0 0.9652)
			(size 1.397 1.143)
			(layers "B.Cu" "B.Mask" "B.Paste")
			(net "GND")
		)
	)
	(footprint ""
		(layer "B.Cu")
		(at 85.334348 -178.789584)
		(property "Reference" "R96"
			(at 0 0 0)
			(layer "B.SilkS")
			(hide yes)
			(effects
				(font
					(size 1.27 1.27)
				)
				(justify mirror)
			)
		)
		(property "Value" "0R2J-2-GP"
			(at -0.064008 -3.993896 0)
			(unlocked yes)
			(layer "B.Fab")
			(hide yes)
			(effects
				(font
					(size 1.016 1.016)
					(thickness 0.1524)
				)
				(justify mirror)
			)
		)
		(property "Device Type" "R402H16"
			(at -0.064008 -5.517896 0)
			(unlocked yes)
			(layer "B.Fab")
			(hide yes)
			(effects
				(font
					(size 1.016 1.016)
					(thickness 0.1524)
				)
				(justify mirror)
			)
		)
		(duplicate_pad_numbers_are_jumpers no)
		(fp_line
			(start -0.508 -0.9398)
			(end 0.508 -0.9398)
			(stroke
				(width 0.1524)
				(type default)
			)
			(layer "B.SilkS")
		)
		(fp_line
			(start 0.508 -0.9398)
			(end 0.508 0.9398)
			(stroke
				(width 0.1524)
				(type default)
			)
			(layer "B.SilkS")
		)
		(fp_rect
			(start 0.508 0.9398)
			(end -0.508 -0.9398)
			(stroke
				(width 0)
				(type default)
			)
			(fill no)
			(layer "B.CrtYd")
		)
		(fp_rect
			(start 0.508 0.9398)
			(end -0.508 -0.9398)
			(stroke
				(width 0)
				(type default)
			)
			(fill no)
			(layer "B.Fab")
		)
		(pad "1" smd custom
			(at 0 -0.4445 180)
			(size 0.1397 0.1397)
			(layers "B.Cu" "B.Mask" "B.Paste")
			(net "I2C_BMC_COMP_SDA_R")
			(options
				(clearance outline)
				(anchor circle)
			)
			(primitives
				(gr_poly
					(pts
						(arc
							(start -0.1778 0.2794)
							(mid -0.249642 0.249642)
							(end -0.2794 0.1778)
						)
						(arc
							(start -0.2794 -0.1778)
							(mid -0.249642 -0.249642)
							(end -0.1778 -0.2794)
						)
						(arc
							(start 0.1778 -0.2794)
							(mid 0.249642 -0.249642)
							(end 0.2794 -0.1778)
						)
						(arc
							(start 0.2794 0.1778)
							(mid 0.249642 0.249642)
							(end 0.1778 0.2794)
						)
					)
					(width 0)
					(fill yes)
				)
			)
		)
		(pad "2" smd custom
			(at 0 0.4445 180)
			(size 0.1397 0.1397)
			(layers "B.Cu" "B.Mask" "B.Paste")
			(net "I2C_BMC_COMP_SDA")
			(options
				(clearance outline)
				(anchor circle)
			)
			(primitives
				(gr_poly
					(pts
						(arc
							(start -0.1778 0.2794)
							(mid -0.249642 0.249642)
							(end -0.2794 0.1778)
						)
						(arc
							(start -0.2794 -0.1778)
							(mid -0.249642 -0.249642)
							(end -0.1778 -0.2794)
						)
						(arc
							(start 0.1778 -0.2794)
							(mid 0.249642 -0.249642)
							(end 0.2794 -0.1778)
						)
						(arc
							(start 0.2794 0.1778)
							(mid 0.249642 0.249642)
							(end 0.1778 0.2794)
						)
					)
					(width 0)
					(fill yes)
				)
			)
		)
	)
	(footprint ""
		(layer "B.Cu")
		(at 54.229 -162.1536 90)
		(property "Reference" "C117"
			(at 0 0 90)
			(layer "B.SilkS")
			(hide yes)
			(effects
				(font
					(size 1.27 1.27)
				)
				(justify mirror)
			)
		)
		(property "Value" "SCD1U25V2KX-2-GP"
			(at -1.1811 -2.7051 90)
			(unlocked yes)
			(layer "B.Fab")
			(hide yes)
			(effects
				(font
					(size 1.016 1.016)
					(thickness 0.1524)
				)
				(justify mirror)
			)
		)
		(property "Device Type" "C402H22"
			(at -1.1811 -4.2291 90)
			(unlocked yes)
			(layer "B.Fab")
			(hide yes)
			(effects
				(font
					(size 1.016 1.016)
					(thickness 0.1524)
				)
				(justify mirror)
			)
		)
		(duplicate_pad_numbers_are_jumpers no)
		(fp_rect
			(start 0.4318 0.9525)
			(end -0.4318 -0.9525)
			(stroke
				(width 0)
				(type default)
			)
			(fill no)
			(layer "B.CrtYd")
		)
		(fp_rect
			(start 0.4318 0.9525)
			(end -0.4318 -0.9525)
			(stroke
				(width 0)
				(type default)
			)
			(fill no)
			(layer "B.Fab")
		)
		(pad "1" smd custom
			(at 0 -0.4445 270)
			(size 0.1524 0.1524)
			(layers "B.Cu" "B.Mask" "B.Paste")
			(net "ADC_12V")
			(options
				(clearance outline)
				(anchor circle)
			)
			(primitives
				(gr_poly
					(pts
						(arc
							(start 0.3048 0.2032)
							(mid 0.275042 0.275042)
							(end 0.2032 0.3048)
						)
						(arc
							(start -0.2032 0.3048)
							(mid -0.275042 0.275042)
							(end -0.3048 0.2032)
						)
						(arc
							(start -0.3048 -0.2032)
							(mid -0.275042 -0.275042)
							(end -0.2032 -0.3048)
						)
						(arc
							(start 0.2032 -0.3048)
							(mid 0.275042 -0.275042)
							(end 0.3048 -0.2032)
						)
					)
					(width 0)
					(fill yes)
				)
			)
		)
		(pad "2" smd custom
			(at 0 0.4445 270)
			(size 0.1524 0.1524)
			(layers "B.Cu" "B.Mask" "B.Paste")
			(net "GND")
			(options
				(clearance outline)
				(anchor circle)
			)
			(primitives
				(gr_poly
					(pts
						(arc
							(start 0.3048 0.2032)
							(mid 0.275042 0.275042)
							(end 0.2032 0.3048)
						)
						(arc
							(start -0.2032 0.3048)
							(mid -0.275042 0.275042)
							(end -0.3048 0.2032)
						)
						(arc
							(start -0.3048 -0.2032)
							(mid -0.275042 -0.275042)
							(end -0.2032 -0.3048)
						)
						(arc
							(start 0.2032 -0.3048)
							(mid 0.275042 -0.275042)
							(end 0.3048 -0.2032)
						)
					)
					(width 0)
					(fill yes)
				)
			)
		)
	)
	(footprint ""
		(layer "B.Cu")
		(at 44.221908 -145.810732 -90)
		(property "Reference" "R141"
			(at 0 0 90)
			(layer "B.SilkS")
			(hide yes)
			(effects
				(font
					(size 1.27 1.27)
				)
				(justify mirror)
			)
		)
		(property "Value" "1KR2D-1-GP"
			(at -0.064008 -3.993896 270)
			(unlocked yes)
			(layer "B.Fab")
			(hide yes)
			(effects
				(font
					(size 1.016 1.016)
					(thickness 0.1524)
				)
				(justify mirror)
			)
		)
		(property "Device Type" "R402H16"
			(at -0.064008 -5.517896 270)
			(unlocked yes)
			(layer "B.Fab")
			(hide yes)
			(effects
				(font
					(size 1.016 1.016)
					(thickness 0.1524)
				)
				(justify mirror)
			)
		)
		(duplicate_pad_numbers_are_jumpers no)
		(fp_line
			(start -0.508 -0.9398)
			(end 0.508 -0.9398)
			(stroke
				(width 0.1524)
				(type default)
			)
			(layer "B.SilkS")
		)
		(fp_line
			(start 0.508 -0.9398)
			(end 0.508 0.9398)
			(stroke
				(width 0.1524)
				(type default)
			)
			(layer "B.SilkS")
		)
		(fp_rect
			(start 0.508 0.9398)
			(end -0.508 -0.9398)
			(stroke
				(width 0)
				(type default)
			)
			(fill no)
			(layer "B.CrtYd")
		)
		(fp_rect
			(start 0.508 0.9398)
			(end -0.508 -0.9398)
			(stroke
				(width 0)
				(type default)
			)
			(fill no)
			(layer "B.Fab")
		)
		(pad "1" smd custom
			(at 0 -0.4445 90)
			(size 0.1397 0.1397)
			(layers "B.Cu" "B.Mask" "B.Paste")
			(net "P1V2_STBY")
			(options
				(clearance outline)
				(anchor circle)
			)
			(primitives
				(gr_poly
					(pts
						(arc
							(start -0.1778 0.2794)
							(mid -0.249642 0.249642)
							(end -0.2794 0.1778)
						)
						(arc
							(start -0.2794 -0.1778)
							(mid -0.249642 -0.249642)
							(end -0.1778 -0.2794)
						)
						(arc
							(start 0.1778 -0.2794)
							(mid 0.249642 -0.249642)
							(end 0.2794 -0.1778)
						)
						(arc
							(start 0.2794 0.1778)
							(mid 0.249642 0.249642)
							(end 0.1778 0.2794)
						)
					)
					(width 0)
					(fill yes)
				)
			)
		)
		(pad "2" smd custom
			(at 0 0.4445 90)
			(size 0.1397 0.1397)
			(layers "B.Cu" "B.Mask" "B.Paste")
			(net "DDR_VREF")
			(options
				(clearance outline)
				(anchor circle)
			)
			(primitives
				(gr_poly
					(pts
						(arc
							(start -0.1778 0.2794)
							(mid -0.249642 0.249642)
							(end -0.2794 0.1778)
						)
						(arc
							(start -0.2794 -0.1778)
							(mid -0.249642 -0.249642)
							(end -0.1778 -0.2794)
						)
						(arc
							(start 0.1778 -0.2794)
							(mid 0.249642 -0.249642)
							(end 0.2794 -0.1778)
						)
						(arc
							(start 0.2794 0.1778)
							(mid 0.249642 0.249642)
							(end 0.1778 0.2794)
						)
					)
					(width 0)
					(fill yes)
				)
			)
		)
	)
	(footprint ""
		(layer "B.Cu")
		(at 206.737712 -64.430656 90)
		(property "Reference" "R598"
			(at 0 0 90)
			(layer "B.SilkS")
			(hide yes)
			(effects
				(font
					(size 1.27 1.27)
				)
				(justify mirror)
			)
		)
		(property "Value" "10KR2F-2-GP"
			(at -0.064008 -3.993896 90)
			(unlocked yes)
			(layer "B.Fab")
			(hide yes)
			(effects
				(font
					(size 1.016 1.016)
					(thickness 0.1524)
				)
				(justify mirror)
			)
		)
		(property "Device Type" "R402H16"
			(at -0.064008 -5.517896 90)
			(unlocked yes)
			(layer "B.Fab")
			(hide yes)
			(effects
				(font
					(size 1.016 1.016)
					(thickness 0.1524)
				)
				(justify mirror)
			)
		)
		(duplicate_pad_numbers_are_jumpers no)
		(fp_line
			(start 0.508 -0.9398)
			(end 0.508 0.9398)
			(stroke
				(width 0.1524)
				(type default)
			)
			(layer "B.SilkS")
		)
		(fp_line
			(start -0.508 -0.9398)
			(end 0.508 -0.9398)
			(stroke
				(width 0.1524)
				(type default)
			)
			(layer "B.SilkS")
		)
		(fp_rect
			(start 0.508 0.9398)
			(end -0.508 -0.9398)
			(stroke
				(width 0)
				(type default)
			)
			(fill no)
			(layer "B.CrtYd")
		)
		(fp_rect
			(start 0.508 0.9398)
			(end -0.508 -0.9398)
			(stroke
				(width 0)
				(type default)
			)
			(fill no)
			(layer "B.Fab")
		)
		(pad "1" smd custom
			(at 0 -0.4445 270)
			(size 0.1397 0.1397)
			(layers "B.Cu" "B.Mask" "B.Paste")
			(net "IOC_SIO_BLINK")
			(options
				(clearance outline)
				(anchor circle)
			)
			(primitives
				(gr_poly
					(pts
						(arc
							(start -0.1778 0.2794)
							(mid -0.249642 0.249642)
							(end -0.2794 0.1778)
						)
						(arc
							(start -0.2794 -0.1778)
							(mid -0.249642 -0.249642)
							(end -0.1778 -0.2794)
						)
						(arc
							(start 0.1778 -0.2794)
							(mid 0.249642 -0.249642)
							(end 0.2794 -0.1778)
						)
						(arc
							(start 0.2794 0.1778)
							(mid 0.249642 0.249642)
							(end 0.1778 0.2794)
						)
					)
					(width 0)
					(fill yes)
				)
			)
		)
		(pad "2" smd custom
			(at 0 0.4445 270)
			(size 0.1397 0.1397)
			(layers "B.Cu" "B.Mask" "B.Paste")
			(net "GND")
			(options
				(clearance outline)
				(anchor circle)
			)
			(primitives
				(gr_poly
					(pts
						(arc
							(start -0.1778 0.2794)
							(mid -0.249642 0.249642)
							(end -0.2794 0.1778)
						)
						(arc
							(start -0.2794 -0.1778)
							(mid -0.249642 -0.249642)
							(end -0.1778 -0.2794)
						)
						(arc
							(start 0.1778 -0.2794)
							(mid 0.249642 -0.249642)
							(end 0.2794 -0.1778)
						)
						(arc
							(start 0.2794 0.1778)
							(mid 0.249642 0.249642)
							(end 0.1778 0.2794)
						)
					)
					(width 0)
					(fill yes)
				)
			)
		)
	)
	(footprint ""
		(layer "B.Cu")
		(at 189.2554 -64.8208 90)
		(property "Reference" "C412"
			(at 0 0 90)
			(layer "B.SilkS")
			(hide yes)
			(effects
				(font
					(size 1.27 1.27)
				)
				(justify mirror)
			)
		)
		(property "Value" "SCD1U6D3V1KX-GP"
			(at 2.8321 -1.7399 90)
			(unlocked yes)
			(layer "B.Fab")
			(hide yes)
			(effects
				(font
					(size 1.016 1.016)
					(thickness 0.1524)
				)
				(justify mirror)
			)
		)
		(property "Device Type" "C0201H13"
			(at 2.8321 -3.2639 90)
			(unlocked yes)
			(layer "B.Fab")
			(hide yes)
			(effects
				(font
					(size 1.016 1.016)
					(thickness 0.1524)
				)
				(justify mirror)
			)
		)
		(duplicate_pad_numbers_are_jumpers no)
		(fp_rect
			(start 0.2794 0.6477)
			(end -0.2794 -0.6477)
			(stroke
				(width 0)
				(type default)
			)
			(fill no)
			(layer "B.CrtYd")
		)
		(fp_rect
			(start 0.2794 0.6477)
			(end -0.2794 -0.6477)
			(stroke
				(width 0)
				(type default)
			)
			(fill no)
			(layer "B.Fab")
		)
		(pad "1" smd custom
			(at 0 -0.2794 270)
			(size 0.0762 0.0762)
			(layers "B.Cu" "B.Mask" "B.Paste")
			(net "P0V975")
			(options
				(clearance outline)
				(anchor circle)
			)
			(primitives
				(gr_poly
					(pts
						(arc
							(start 0.1524 0.127)
							(mid 0.137521 0.162921)
							(end 0.1016 0.1778)
						)
						(arc
							(start -0.1016 0.1778)
							(mid -0.137521 0.162921)
							(end -0.1524 0.127)
						)
						(arc
							(start -0.1524 -0.127)
							(mid -0.137521 -0.162921)
							(end -0.1016 -0.1778)
						)
						(arc
							(start 0.1016 -0.1778)
							(mid 0.137521 -0.162921)
							(end 0.1524 -0.127)
						)
					)
					(width 0)
					(fill yes)
				)
			)
		)
		(pad "2" smd custom
			(at 0 0.2794 270)
			(size 0.0762 0.0762)
			(layers "B.Cu" "B.Mask" "B.Paste")
			(net "GND")
			(options
				(clearance outline)
				(anchor circle)
			)
			(primitives
				(gr_poly
					(pts
						(arc
							(start 0.1524 0.127)
							(mid 0.137521 0.162921)
							(end 0.1016 0.1778)
						)
						(arc
							(start -0.1016 0.1778)
							(mid -0.137521 0.162921)
							(end -0.1524 0.127)
						)
						(arc
							(start -0.1524 -0.127)
							(mid -0.137521 -0.162921)
							(end -0.1016 -0.1778)
						)
						(arc
							(start 0.1016 -0.1778)
							(mid 0.137521 -0.162921)
							(end 0.1524 -0.127)
						)
					)
					(width 0)
					(fill yes)
				)
			)
		)
	)
	(footprint ""
		(layer "B.Cu")
		(at 189.5983 -68.3006 -90)
		(property "Reference" "C429"
			(at 0 0 90)
			(layer "B.SilkS")
			(hide yes)
			(effects
				(font
					(size 1.27 1.27)
				)
				(justify mirror)
			)
		)
		(property "Value" "SC1KP50V2KX-1GP"
			(at -1.1811 -2.7051 270)
			(unlocked yes)
			(layer "B.Fab")
			(hide yes)
			(effects
				(font
					(size 1.016 1.016)
					(thickness 0.1524)
				)
				(justify mirror)
			)
		)
		(property "Device Type" "C402H22"
			(at -1.1811 -4.2291 270)
			(unlocked yes)
			(layer "B.Fab")
			(hide yes)
			(effects
				(font
					(size 1.016 1.016)
					(thickness 0.1524)
				)
				(justify mirror)
			)
		)
		(duplicate_pad_numbers_are_jumpers no)
		(fp_rect
			(start 0.4318 0.9525)
			(end -0.4318 -0.9525)
			(stroke
				(width 0)
				(type default)
			)
			(fill no)
			(layer "B.CrtYd")
		)
		(fp_rect
			(start 0.4318 0.9525)
			(end -0.4318 -0.9525)
			(stroke
				(width 0)
				(type default)
			)
			(fill no)
			(layer "B.Fab")
		)
		(pad "1" smd custom
			(at 0 -0.4445 90)
			(size 0.1524 0.1524)
			(layers "B.Cu" "B.Mask" "B.Paste")
			(net "P0V975")
			(options
				(clearance outline)
				(anchor circle)
			)
			(primitives
				(gr_poly
					(pts
						(arc
							(start 0.3048 0.2032)
							(mid 0.275042 0.275042)
							(end 0.2032 0.3048)
						)
						(arc
							(start -0.2032 0.3048)
							(mid -0.275042 0.275042)
							(end -0.3048 0.2032)
						)
						(arc
							(start -0.3048 -0.2032)
							(mid -0.275042 -0.275042)
							(end -0.2032 -0.3048)
						)
						(arc
							(start 0.2032 -0.3048)
							(mid 0.275042 -0.275042)
							(end 0.3048 -0.2032)
						)
					)
					(width 0)
					(fill yes)
				)
			)
		)
		(pad "2" smd custom
			(at 0 0.4445 90)
			(size 0.1524 0.1524)
			(layers "B.Cu" "B.Mask" "B.Paste")
			(net "GND")
			(options
				(clearance outline)
				(anchor circle)
			)
			(primitives
				(gr_poly
					(pts
						(arc
							(start 0.3048 0.2032)
							(mid 0.275042 0.275042)
							(end 0.2032 0.3048)
						)
						(arc
							(start -0.2032 0.3048)
							(mid -0.275042 0.275042)
							(end -0.3048 0.2032)
						)
						(arc
							(start -0.3048 -0.2032)
							(mid -0.275042 -0.275042)
							(end -0.2032 -0.3048)
						)
						(arc
							(start 0.2032 -0.3048)
							(mid 0.275042 -0.275042)
							(end 0.3048 -0.2032)
						)
					)
					(width 0)
					(fill yes)
				)
			)
		)
	)
	(footprint ""
		(layer "B.Cu")
		(at 79.317088 -49.922176 180)
		(property "Reference" "C28"
			(at 0 0 0)
			(layer "B.SilkS")
			(hide yes)
			(effects
				(font
					(size 1.27 1.27)
				)
				(justify mirror)
			)
		)
		(property "Value" "SC2D2U25V5KX-2-GP"
			(at 0.0762 -6.1214 180)
			(unlocked yes)
			(layer "B.Fab")
			(hide yes)
			(effects
				(font
					(size 1.016 1.016)
					(thickness 0.1524)
				)
				(justify mirror)
			)
		)
		(property "Device Type" "C805H54"
			(at 0.0762 -8.1534 180)
			(unlocked yes)
			(layer "B.Fab")
			(hide yes)
			(effects
				(font
					(size 1.016 1.016)
					(thickness 0.1524)
				)
				(justify mirror)
			)
		)
		(duplicate_pad_numbers_are_jumpers no)
		(fp_line
			(start -0.635 0)
			(end 0.635 0)
			(stroke
				(width 0.508)
				(type default)
			)
			(layer "B.SilkS")
		)
		(fp_rect
			(start 0.9652 1.778)
			(end -0.9652 -1.778)
			(stroke
				(width 0)
				(type default)
			)
			(fill no)
			(layer "B.CrtYd")
		)
		(fp_poly
			(pts
				(xy 0.9652 -1.778) (xy -0.9652 -1.778) (xy -0.9652 1.778) (xy 0.9652 1.778)
			)
			(stroke
				(width 0)
				(type default)
			)
			(fill no)
			(layer "B.Fab")
		)
		(pad "1" smd rect
			(at 0 -0.9652)
			(size 1.397 1.143)
			(layers "B.Cu" "B.Mask" "B.Paste")
			(net "P12V_STBY")
		)
		(pad "2" smd rect
			(at 0 0.9652)
			(size 1.397 1.143)
			(layers "B.Cu" "B.Mask" "B.Paste")
			(net "GND")
		)
	)
	(footprint ""
		(layer "B.Cu")
		(at 180.601366 -70.894956)
		(property "Reference" "TP116"
			(at 0 0 0)
			(layer "B.SilkS")
			(hide yes)
			(effects
				(font
					(size 1.27 1.27)
				)
				(justify mirror)
			)
		)
		(property "Value" "TPAD28-2-GP"
			(at 0.0127 -1.6637 0)
			(unlocked yes)
			(layer "B.Fab")
			(hide yes)
			(effects
				(font
					(size 1.016 1.016)
					(thickness 0.1524)
				)
				(justify mirror)
			)
		)
		(property "Device Type" "TPAD28"
			(at 0.0127 -3.1877 0)
			(unlocked yes)
			(layer "B.Fab")
			(hide yes)
			(effects
				(font
					(size 1.016 1.016)
					(thickness 0.1524)
				)
				(justify mirror)
			)
		)
		(duplicate_pad_numbers_are_jumpers no)
		(fp_poly
			(pts
				(arc
					(start 0.3556 0)
					(mid -0.3556 0)
					(end 0.3556 0)
				)
			)
			(stroke
				(width 0)
				(type default)
			)
			(fill no)
			(layer "B.CrtYd")
		)
		(fp_poly
			(pts
				(arc
					(start 0.6096 0)
					(mid -0.6096 0)
					(end 0.6096 0)
				)
			)
			(stroke
				(width 0)
				(type default)
			)
			(fill no)
			(layer "B.Fab")
		)
		(pad "1" smd circle
			(at 0 0 180)
			(size 0.7112 0.7112)
			(layers "B.Cu" "B.Mask" "B.Paste")
			(net "IOC_GPIO_28")
		)
	)
	(footprint ""
		(layer "B.Cu")
		(at 90.8812 -137.5156 -90)
		(property "Reference" "C504"
			(at 0 0 90)
			(layer "B.SilkS")
			(hide yes)
			(effects
				(font
					(size 1.27 1.27)
				)
				(justify mirror)
			)
		)
		(property "Value" "SCD1U16V2KX-3GP"
			(at -1.1811 -2.7051 270)
			(unlocked yes)
			(layer "B.Fab")
			(hide yes)
			(effects
				(font
					(size 1.016 1.016)
					(thickness 0.1524)
				)
				(justify mirror)
			)
		)
		(property "Device Type" "C402H22"
			(at -1.1811 -4.2291 270)
			(unlocked yes)
			(layer "B.Fab")
			(hide yes)
			(effects
				(font
					(size 1.016 1.016)
					(thickness 0.1524)
				)
				(justify mirror)
			)
		)
		(duplicate_pad_numbers_are_jumpers no)
		(fp_rect
			(start 0.4318 0.9525)
			(end -0.4318 -0.9525)
			(stroke
				(width 0)
				(type default)
			)
			(fill no)
			(layer "B.CrtYd")
		)
		(fp_rect
			(start 0.4318 0.9525)
			(end -0.4318 -0.9525)
			(stroke
				(width 0)
				(type default)
			)
			(fill no)
			(layer "B.Fab")
		)
		(pad "1" smd custom
			(at 0 -0.4445 90)
			(size 0.1524 0.1524)
			(layers "B.Cu" "B.Mask" "B.Paste")
			(net "P3V3_STBY")
			(options
				(clearance outline)
				(anchor circle)
			)
			(primitives
				(gr_poly
					(pts
						(arc
							(start 0.3048 0.2032)
							(mid 0.275042 0.275042)
							(end 0.2032 0.3048)
						)
						(arc
							(start -0.2032 0.3048)
							(mid -0.275042 0.275042)
							(end -0.3048 0.2032)
						)
						(arc
							(start -0.3048 -0.2032)
							(mid -0.275042 -0.275042)
							(end -0.2032 -0.3048)
						)
						(arc
							(start 0.2032 -0.3048)
							(mid 0.275042 -0.275042)
							(end 0.3048 -0.2032)
						)
					)
					(width 0)
					(fill yes)
				)
			)
		)
		(pad "2" smd custom
			(at 0 0.4445 90)
			(size 0.1524 0.1524)
			(layers "B.Cu" "B.Mask" "B.Paste")
			(net "GND")
			(options
				(clearance outline)
				(anchor circle)
			)
			(primitives
				(gr_poly
					(pts
						(arc
							(start 0.3048 0.2032)
							(mid 0.275042 0.275042)
							(end 0.2032 0.3048)
						)
						(arc
							(start -0.2032 0.3048)
							(mid -0.275042 0.275042)
							(end -0.3048 0.2032)
						)
						(arc
							(start -0.3048 -0.2032)
							(mid -0.275042 -0.275042)
							(end -0.2032 -0.3048)
						)
						(arc
							(start 0.2032 -0.3048)
							(mid 0.275042 -0.275042)
							(end 0.3048 -0.2032)
						)
					)
					(width 0)
					(fill yes)
				)
			)
		)
	)
	(footprint ""
		(layer "B.Cu")
		(at 170.6118 -78.0796 90)
		(property "Reference" "R682"
			(at 0 0 90)
			(layer "B.SilkS")
			(hide yes)
			(effects
				(font
					(size 1.27 1.27)
				)
				(justify mirror)
			)
		)
		(property "Value" "10R2F-L-GP"
			(at -0.064008 -3.993896 90)
			(unlocked yes)
			(layer "B.Fab")
			(hide yes)
			(effects
				(font
					(size 1.016 1.016)
					(thickness 0.1524)
				)
				(justify mirror)
			)
		)
		(property "Device Type" "R402H14"
			(at -0.064008 -5.517896 90)
			(unlocked yes)
			(layer "B.Fab")
			(hide yes)
			(effects
				(font
					(size 1.016 1.016)
					(thickness 0.1524)
				)
				(justify mirror)
			)
		)
		(duplicate_pad_numbers_are_jumpers no)
		(fp_line
			(start 0.508 -0.9398)
			(end 0.508 0.9398)
			(stroke
				(width 0.1524)
				(type default)
			)
			(layer "B.SilkS")
		)
		(fp_line
			(start -0.508 -0.9398)
			(end 0.508 -0.9398)
			(stroke
				(width 0.1524)
				(type default)
			)
			(layer "B.SilkS")
		)
		(fp_rect
			(start 0.508 0.9398)
			(end -0.508 -0.9398)
			(stroke
				(width 0)
				(type default)
			)
			(fill no)
			(layer "B.CrtYd")
		)
		(fp_rect
			(start 0.508 0.9398)
			(end -0.508 -0.9398)
			(stroke
				(width 0)
				(type default)
			)
			(fill no)
			(layer "B.Fab")
		)
		(pad "1" smd custom
			(at 0 -0.4445 270)
			(size 0.1397 0.1397)
			(layers "B.Cu" "B.Mask" "B.Paste")
			(net "P1V8")
			(options
				(clearance outline)
				(anchor circle)
			)
			(primitives
				(gr_poly
					(pts
						(arc
							(start -0.1778 0.2794)
							(mid -0.249642 0.249642)
							(end -0.2794 0.1778)
						)
						(arc
							(start -0.2794 -0.1778)
							(mid -0.249642 -0.249642)
							(end -0.1778 -0.2794)
						)
						(arc
							(start 0.1778 -0.2794)
							(mid 0.249642 -0.249642)
							(end 0.2794 -0.1778)
						)
						(arc
							(start 0.2794 0.1778)
							(mid 0.249642 0.249642)
							(end 0.1778 0.2794)
						)
					)
					(width 0)
					(fill yes)
				)
			)
		)
		(pad "2" smd custom
			(at 0 0.4445 270)
			(size 0.1397 0.1397)
			(layers "B.Cu" "B.Mask" "B.Paste")
			(net "PLL_VDD")
			(options
				(clearance outline)
				(anchor circle)
			)
			(primitives
				(gr_poly
					(pts
						(arc
							(start -0.1778 0.2794)
							(mid -0.249642 0.249642)
							(end -0.2794 0.1778)
						)
						(arc
							(start -0.2794 -0.1778)
							(mid -0.249642 -0.249642)
							(end -0.1778 -0.2794)
						)
						(arc
							(start 0.1778 -0.2794)
							(mid 0.249642 -0.249642)
							(end 0.2794 -0.1778)
						)
						(arc
							(start 0.2794 0.1778)
							(mid 0.249642 0.249642)
							(end 0.1778 0.2794)
						)
					)
					(width 0)
					(fill yes)
				)
			)
		)
	)
	(footprint ""
		(layer "B.Cu")
		(at 64.17818 -158.048198 180)
		(property "Reference" "C80"
			(at 0 0 0)
			(layer "B.SilkS")
			(hide yes)
			(effects
				(font
					(size 1.27 1.27)
				)
				(justify mirror)
			)
		)
		(property "Value" "SCD1U16V2KX-3GP"
			(at -1.1811 -2.7051 180)
			(unlocked yes)
			(layer "B.Fab")
			(hide yes)
			(effects
				(font
					(size 1.016 1.016)
					(thickness 0.1524)
				)
				(justify mirror)
			)
		)
		(property "Device Type" "C402H22"
			(at -1.1811 -4.2291 180)
			(unlocked yes)
			(layer "B.Fab")
			(hide yes)
			(effects
				(font
					(size 1.016 1.016)
					(thickness 0.1524)
				)
				(justify mirror)
			)
		)
		(duplicate_pad_numbers_are_jumpers no)
		(fp_rect
			(start 0.4318 0.9525)
			(end -0.4318 -0.9525)
			(stroke
				(width 0)
				(type default)
			)
			(fill no)
			(layer "B.CrtYd")
		)
		(fp_rect
			(start 0.4318 0.9525)
			(end -0.4318 -0.9525)
			(stroke
				(width 0)
				(type default)
			)
			(fill no)
			(layer "B.Fab")
		)
		(pad "1" smd custom
			(at 0 -0.4445)
			(size 0.1524 0.1524)
			(layers "B.Cu" "B.Mask" "B.Paste")
			(net "P3V3_STBY")
			(options
				(clearance outline)
				(anchor circle)
			)
			(primitives
				(gr_poly
					(pts
						(arc
							(start 0.3048 0.2032)
							(mid 0.275042 0.275042)
							(end 0.2032 0.3048)
						)
						(arc
							(start -0.2032 0.3048)
							(mid -0.275042 0.275042)
							(end -0.3048 0.2032)
						)
						(arc
							(start -0.3048 -0.2032)
							(mid -0.275042 -0.275042)
							(end -0.2032 -0.3048)
						)
						(arc
							(start 0.2032 -0.3048)
							(mid 0.275042 -0.275042)
							(end 0.3048 -0.2032)
						)
					)
					(width 0)
					(fill yes)
				)
			)
		)
		(pad "2" smd custom
			(at 0 0.4445)
			(size 0.1524 0.1524)
			(layers "B.Cu" "B.Mask" "B.Paste")
			(net "GND")
			(options
				(clearance outline)
				(anchor circle)
			)
			(primitives
				(gr_poly
					(pts
						(arc
							(start 0.3048 0.2032)
							(mid 0.275042 0.275042)
							(end 0.2032 0.3048)
						)
						(arc
							(start -0.2032 0.3048)
							(mid -0.275042 0.275042)
							(end -0.3048 0.2032)
						)
						(arc
							(start -0.3048 -0.2032)
							(mid -0.275042 -0.275042)
							(end -0.2032 -0.3048)
						)
						(arc
							(start 0.2032 -0.3048)
							(mid 0.275042 -0.275042)
							(end 0.3048 -0.2032)
						)
					)
					(width 0)
					(fill yes)
				)
			)
		)
	)
	(footprint ""
		(layer "B.Cu")
		(at 52.07508 -155.05176)
		(property "Reference" "R315"
			(at 0 0 0)
			(layer "B.SilkS")
			(hide yes)
			(effects
				(font
					(size 1.27 1.27)
				)
				(justify mirror)
			)
		)
		(property "Value" "10KR2F-2-GP"
			(at -0.064008 -3.993896 0)
			(unlocked yes)
			(layer "B.Fab")
			(hide yes)
			(effects
				(font
					(size 1.016 1.016)
					(thickness 0.1524)
				)
				(justify mirror)
			)
		)
		(property "Device Type" "R402H16"
			(at -0.064008 -5.517896 0)
			(unlocked yes)
			(layer "B.Fab")
			(hide yes)
			(effects
				(font
					(size 1.016 1.016)
					(thickness 0.1524)
				)
				(justify mirror)
			)
		)
		(duplicate_pad_numbers_are_jumpers no)
		(fp_line
			(start -0.508 -0.9398)
			(end 0.508 -0.9398)
			(stroke
				(width 0.1524)
				(type default)
			)
			(layer "B.SilkS")
		)
		(fp_line
			(start 0.508 -0.9398)
			(end 0.508 0.9398)
			(stroke
				(width 0.1524)
				(type default)
			)
			(layer "B.SilkS")
		)
		(fp_rect
			(start 0.508 0.9398)
			(end -0.508 -0.9398)
			(stroke
				(width 0)
				(type default)
			)
			(fill no)
			(layer "B.CrtYd")
		)
		(fp_rect
			(start 0.508 0.9398)
			(end -0.508 -0.9398)
			(stroke
				(width 0)
				(type default)
			)
			(fill no)
			(layer "B.Fab")
		)
		(pad "1" smd custom
			(at 0 -0.4445 180)
			(size 0.1397 0.1397)
			(layers "B.Cu" "B.Mask" "B.Paste")
			(net "BMC_ENTEST")
			(options
				(clearance outline)
				(anchor circle)
			)
			(primitives
				(gr_poly
					(pts
						(arc
							(start -0.1778 0.2794)
							(mid -0.249642 0.249642)
							(end -0.2794 0.1778)
						)
						(arc
							(start -0.2794 -0.1778)
							(mid -0.249642 -0.249642)
							(end -0.1778 -0.2794)
						)
						(arc
							(start 0.1778 -0.2794)
							(mid 0.249642 -0.249642)
							(end 0.2794 -0.1778)
						)
						(arc
							(start 0.2794 0.1778)
							(mid 0.249642 0.249642)
							(end 0.1778 0.2794)
						)
					)
					(width 0)
					(fill yes)
				)
			)
		)
		(pad "2" smd custom
			(at 0 0.4445 180)
			(size 0.1397 0.1397)
			(layers "B.Cu" "B.Mask" "B.Paste")
			(net "GND")
			(options
				(clearance outline)
				(anchor circle)
			)
			(primitives
				(gr_poly
					(pts
						(arc
							(start -0.1778 0.2794)
							(mid -0.249642 0.249642)
							(end -0.2794 0.1778)
						)
						(arc
							(start -0.2794 -0.1778)
							(mid -0.249642 -0.249642)
							(end -0.1778 -0.2794)
						)
						(arc
							(start 0.1778 -0.2794)
							(mid 0.249642 -0.249642)
							(end 0.2794 -0.1778)
						)
						(arc
							(start 0.2794 0.1778)
							(mid 0.249642 0.249642)
							(end 0.1778 0.2794)
						)
					)
					(width 0)
					(fill yes)
				)
			)
		)
	)
	(footprint ""
		(layer "B.Cu")
		(at 50.81397 -132.626354)
		(property "Reference" "C113"
			(at 0 0 0)
			(layer "B.SilkS")
			(hide yes)
			(effects
				(font
					(size 1.27 1.27)
				)
				(justify mirror)
			)
		)
		(property "Value" "SC1U16V3KX-5GP"
			(at 0 -2.8194 0)
			(unlocked yes)
			(layer "B.Fab")
			(hide yes)
			(effects
				(font
					(size 1.016 1.016)
					(thickness 0.1524)
				)
				(justify mirror)
			)
		)
		(property "Device Type" "C603H36"
			(at 0 -4.3434 0)
			(unlocked yes)
			(layer "B.Fab")
			(hide yes)
			(effects
				(font
					(size 1.016 1.016)
					(thickness 0.1524)
				)
				(justify mirror)
			)
		)
		(duplicate_pad_numbers_are_jumpers no)
		(fp_line
			(start -0.508 0)
			(end 0.508 0)
			(stroke
				(width 0.2032)
				(type default)
			)
			(layer "B.SilkS")
		)
		(fp_rect
			(start 0.5842 1.3335)
			(end -0.5842 -1.3335)
			(stroke
				(width 0)
				(type default)
			)
			(fill no)
			(layer "B.CrtYd")
		)
		(fp_rect
			(start 0.5842 1.3335)
			(end -0.5842 -1.3335)
			(stroke
				(width 0)
				(type default)
			)
			(fill no)
			(layer "B.Fab")
		)
		(pad "1" smd custom
			(at 0 -0.762 180)
			(size 0.2159 0.2159)
			(layers "B.Cu" "B.Mask" "B.Paste")
			(net "P1V15_STBY")
			(options
				(clearance outline)
				(anchor circle)
			)
			(primitives
				(gr_poly
					(pts
						(arc
							(start -0.3302 0.4318)
							(mid -0.402042 0.402042)
							(end -0.4318 0.3302)
						)
						(arc
							(start -0.4318 -0.3302)
							(mid -0.402042 -0.402042)
							(end -0.3302 -0.4318)
						)
						(arc
							(start 0.3302 -0.4318)
							(mid 0.402042 -0.402042)
							(end 0.4318 -0.3302)
						)
						(arc
							(start 0.4318 0.3302)
							(mid 0.402042 0.402042)
							(end 0.3302 0.4318)
						)
					)
					(width 0)
					(fill yes)
				)
			)
		)
		(pad "2" smd custom
			(at 0 0.762 180)
			(size 0.2159 0.2159)
			(layers "B.Cu" "B.Mask" "B.Paste")
			(net "GND")
			(options
				(clearance outline)
				(anchor circle)
			)
			(primitives
				(gr_poly
					(pts
						(arc
							(start -0.3302 0.4318)
							(mid -0.402042 0.402042)
							(end -0.4318 0.3302)
						)
						(arc
							(start -0.4318 -0.3302)
							(mid -0.402042 -0.402042)
							(end -0.3302 -0.4318)
						)
						(arc
							(start 0.3302 -0.4318)
							(mid 0.402042 -0.402042)
							(end 0.4318 -0.3302)
						)
						(arc
							(start 0.4318 0.3302)
							(mid 0.402042 0.402042)
							(end 0.3302 0.4318)
						)
					)
					(width 0)
					(fill yes)
				)
			)
		)
	)
	(footprint ""
		(layer "B.Cu")
		(at 168.601136 -38.442138)
		(property "Reference" "C496"
			(at 0 0 0)
			(layer "B.SilkS")
			(hide yes)
			(effects
				(font
					(size 1.27 1.27)
				)
				(justify mirror)
			)
		)
		(property "Value" "SCD01U16V1KX-GP"
			(at 2.8321 -1.7399 0)
			(unlocked yes)
			(layer "B.Fab")
			(hide yes)
			(effects
				(font
					(size 1.016 1.016)
					(thickness 0.1524)
				)
				(justify mirror)
			)
		)
		(property "Device Type" "C0201H13"
			(at 2.8321 -3.2639 0)
			(unlocked yes)
			(layer "B.Fab")
			(hide yes)
			(effects
				(font
					(size 1.016 1.016)
					(thickness 0.1524)
				)
				(justify mirror)
			)
		)
		(duplicate_pad_numbers_are_jumpers no)
		(fp_rect
			(start 0.2794 0.6477)
			(end -0.2794 -0.6477)
			(stroke
				(width 0)
				(type default)
			)
			(fill no)
			(layer "B.CrtYd")
		)
		(fp_rect
			(start 0.2794 0.6477)
			(end -0.2794 -0.6477)
			(stroke
				(width 0)
				(type default)
			)
			(fill no)
			(layer "B.Fab")
		)
		(pad "1" smd custom
			(at 0 -0.2794 180)
			(size 0.0762 0.0762)
			(layers "B.Cu" "B.Mask" "B.Paste")
			(net "PHY_CON_B_TO_IOC_1_DN")
			(options
				(clearance outline)
				(anchor circle)
			)
			(primitives
				(gr_poly
					(pts
						(arc
							(start 0.1524 0.127)
							(mid 0.137521 0.162921)
							(end 0.1016 0.1778)
						)
						(arc
							(start -0.1016 0.1778)
							(mid -0.137521 0.162921)
							(end -0.1524 0.127)
						)
						(arc
							(start -0.1524 -0.127)
							(mid -0.137521 -0.162921)
							(end -0.1016 -0.1778)
						)
						(arc
							(start 0.1016 -0.1778)
							(mid 0.137521 -0.162921)
							(end 0.1524 -0.127)
						)
					)
					(width 0)
					(fill yes)
				)
			)
		)
		(pad "2" smd custom
			(at 0 0.2794 180)
			(size 0.0762 0.0762)
			(layers "B.Cu" "B.Mask" "B.Paste")
			(net "PHY_CON_B_TO_IOC_1_DN_C")
			(options
				(clearance outline)
				(anchor circle)
			)
			(primitives
				(gr_poly
					(pts
						(arc
							(start 0.1524 0.127)
							(mid 0.137521 0.162921)
							(end 0.1016 0.1778)
						)
						(arc
							(start -0.1016 0.1778)
							(mid -0.137521 0.162921)
							(end -0.1524 0.127)
						)
						(arc
							(start -0.1524 -0.127)
							(mid -0.137521 -0.162921)
							(end -0.1016 -0.1778)
						)
						(arc
							(start 0.1016 -0.1778)
							(mid 0.137521 -0.162921)
							(end 0.1524 -0.127)
						)
					)
					(width 0)
					(fill yes)
				)
			)
		)
	)
	(footprint ""
		(layer "B.Cu")
		(at 193.7258 -68.326 90)
		(property "Reference" "C427"
			(at 0 0 90)
			(layer "B.SilkS")
			(hide yes)
			(effects
				(font
					(size 1.27 1.27)
				)
				(justify mirror)
			)
		)
		(property "Value" "SC1KP50V2KX-1GP"
			(at -1.1811 -2.7051 90)
			(unlocked yes)
			(layer "B.Fab")
			(hide yes)
			(effects
				(font
					(size 1.016 1.016)
					(thickness 0.1524)
				)
				(justify mirror)
			)
		)
		(property "Device Type" "C402H22"
			(at -1.1811 -4.2291 90)
			(unlocked yes)
			(layer "B.Fab")
			(hide yes)
			(effects
				(font
					(size 1.016 1.016)
					(thickness 0.1524)
				)
				(justify mirror)
			)
		)
		(duplicate_pad_numbers_are_jumpers no)
		(fp_rect
			(start 0.4318 0.9525)
			(end -0.4318 -0.9525)
			(stroke
				(width 0)
				(type default)
			)
			(fill no)
			(layer "B.CrtYd")
		)
		(fp_rect
			(start 0.4318 0.9525)
			(end -0.4318 -0.9525)
			(stroke
				(width 0)
				(type default)
			)
			(fill no)
			(layer "B.Fab")
		)
		(pad "1" smd custom
			(at 0 -0.4445 270)
			(size 0.1524 0.1524)
			(layers "B.Cu" "B.Mask" "B.Paste")
			(net "P0V975")
			(options
				(clearance outline)
				(anchor circle)
			)
			(primitives
				(gr_poly
					(pts
						(arc
							(start 0.3048 0.2032)
							(mid 0.275042 0.275042)
							(end 0.2032 0.3048)
						)
						(arc
							(start -0.2032 0.3048)
							(mid -0.275042 0.275042)
							(end -0.3048 0.2032)
						)
						(arc
							(start -0.3048 -0.2032)
							(mid -0.275042 -0.275042)
							(end -0.2032 -0.3048)
						)
						(arc
							(start 0.2032 -0.3048)
							(mid 0.275042 -0.275042)
							(end 0.3048 -0.2032)
						)
					)
					(width 0)
					(fill yes)
				)
			)
		)
		(pad "2" smd custom
			(at 0 0.4445 270)
			(size 0.1524 0.1524)
			(layers "B.Cu" "B.Mask" "B.Paste")
			(net "GND")
			(options
				(clearance outline)
				(anchor circle)
			)
			(primitives
				(gr_poly
					(pts
						(arc
							(start 0.3048 0.2032)
							(mid 0.275042 0.275042)
							(end 0.2032 0.3048)
						)
						(arc
							(start -0.2032 0.3048)
							(mid -0.275042 0.275042)
							(end -0.3048 0.2032)
						)
						(arc
							(start -0.3048 -0.2032)
							(mid -0.275042 -0.275042)
							(end -0.2032 -0.3048)
						)
						(arc
							(start 0.2032 -0.3048)
							(mid 0.275042 -0.275042)
							(end 0.3048 -0.2032)
						)
					)
					(width 0)
					(fill yes)
				)
			)
		)
	)
	(footprint ""
		(layer "B.Cu")
		(at 179.47132 -80.98536)
		(property "Reference" "R686"
			(at 0 0 0)
			(layer "B.SilkS")
			(hide yes)
			(effects
				(font
					(size 1.27 1.27)
				)
				(justify mirror)
			)
		)
		(property "Value" "D51R3F-2-GP"
			(at 0.0254 -2.5146 0)
			(unlocked yes)
			(layer "B.Fab")
			(hide yes)
			(effects
				(font
					(size 1.016 1.016)
					(thickness 0.1524)
				)
				(justify mirror)
			)
		)
		(property "Device Type" "R603H22"
			(at 0.0254 -4.0386 0)
			(unlocked yes)
			(layer "B.Fab")
			(hide yes)
			(effects
				(font
					(size 1.016 1.016)
					(thickness 0.1524)
				)
				(justify mirror)
			)
		)
		(duplicate_pad_numbers_are_jumpers no)
		(fp_line
			(start -0.2032 0)
			(end -0.4826 0)
			(stroke
				(width 0.2032)
				(type default)
			)
			(layer "B.SilkS")
		)
		(fp_line
			(start 0.4826 0)
			(end 0.2032 0)
			(stroke
				(width 0.2032)
				(type default)
			)
			(layer "B.SilkS")
		)
		(fp_rect
			(start 0.5842 1.3335)
			(end -0.5842 -1.3335)
			(stroke
				(width 0)
				(type default)
			)
			(fill no)
			(layer "B.CrtYd")
		)
		(fp_rect
			(start 0.5842 1.3335)
			(end -0.5842 -1.3335)
			(stroke
				(width 0)
				(type default)
			)
			(fill no)
			(layer "B.Fab")
		)
		(pad "1" smd custom
			(at 0 -0.762 180)
			(size 0.2159 0.2159)
			(layers "B.Cu" "B.Mask" "B.Paste")
			(net "P0V975")
			(options
				(clearance outline)
				(anchor circle)
			)
			(primitives
				(gr_poly
					(pts
						(arc
							(start -0.3302 0.4318)
							(mid -0.402042 0.402042)
							(end -0.4318 0.3302)
						)
						(arc
							(start -0.4318 -0.3302)
							(mid -0.402042 -0.402042)
							(end -0.3302 -0.4318)
						)
						(arc
							(start 0.3302 -0.4318)
							(mid 0.402042 -0.402042)
							(end 0.4318 -0.3302)
						)
						(arc
							(start 0.4318 0.3302)
							(mid 0.402042 0.402042)
							(end 0.3302 0.4318)
						)
					)
					(width 0)
					(fill yes)
				)
			)
		)
		(pad "2" smd custom
			(at 0 0.762 180)
			(size 0.2159 0.2159)
			(layers "B.Cu" "B.Mask" "B.Paste")
			(net "PCE_AVDD")
			(options
				(clearance outline)
				(anchor circle)
			)
			(primitives
				(gr_poly
					(pts
						(arc
							(start -0.3302 0.4318)
							(mid -0.402042 0.402042)
							(end -0.4318 0.3302)
						)
						(arc
							(start -0.4318 -0.3302)
							(mid -0.402042 -0.402042)
							(end -0.3302 -0.4318)
						)
						(arc
							(start 0.3302 -0.4318)
							(mid 0.402042 -0.402042)
							(end 0.4318 -0.3302)
						)
						(arc
							(start 0.4318 0.3302)
							(mid 0.402042 0.402042)
							(end 0.3302 0.4318)
						)
					)
					(width 0)
					(fill yes)
				)
			)
		)
	)
	(footprint ""
		(layer "B.Cu")
		(at 38.4556 -116.8908 -90)
		(property "Reference" "R341"
			(at 0 0 90)
			(layer "B.SilkS")
			(hide yes)
			(effects
				(font
					(size 1.27 1.27)
				)
				(justify mirror)
			)
		)
		(property "Value" "4K7R2F-GP"
			(at -0.064008 -3.993896 270)
			(unlocked yes)
			(layer "B.Fab")
			(hide yes)
			(effects
				(font
					(size 1.016 1.016)
					(thickness 0.1524)
				)
				(justify mirror)
			)
		)
		(property "Device Type" "R402H16"
			(at -0.064008 -5.517896 270)
			(unlocked yes)
			(layer "B.Fab")
			(hide yes)
			(effects
				(font
					(size 1.016 1.016)
					(thickness 0.1524)
				)
				(justify mirror)
			)
		)
		(duplicate_pad_numbers_are_jumpers no)
		(fp_line
			(start -0.508 -0.9398)
			(end 0.508 -0.9398)
			(stroke
				(width 0.1524)
				(type default)
			)
			(layer "B.SilkS")
		)
		(fp_line
			(start 0.508 -0.9398)
			(end 0.508 0.9398)
			(stroke
				(width 0.1524)
				(type default)
			)
			(layer "B.SilkS")
		)
		(fp_rect
			(start 0.508 0.9398)
			(end -0.508 -0.9398)
			(stroke
				(width 0)
				(type default)
			)
			(fill no)
			(layer "B.CrtYd")
		)
		(fp_rect
			(start 0.508 0.9398)
			(end -0.508 -0.9398)
			(stroke
				(width 0)
				(type default)
			)
			(fill no)
			(layer "B.Fab")
		)
		(pad "1" smd custom
			(at 0 -0.4445 90)
			(size 0.1397 0.1397)
			(layers "B.Cu" "B.Mask" "B.Paste")
			(net "TEMP_3_A2")
			(options
				(clearance outline)
				(anchor circle)
			)
			(primitives
				(gr_poly
					(pts
						(arc
							(start -0.1778 0.2794)
							(mid -0.249642 0.249642)
							(end -0.2794 0.1778)
						)
						(arc
							(start -0.2794 -0.1778)
							(mid -0.249642 -0.249642)
							(end -0.1778 -0.2794)
						)
						(arc
							(start 0.1778 -0.2794)
							(mid 0.249642 -0.249642)
							(end 0.2794 -0.1778)
						)
						(arc
							(start 0.2794 0.1778)
							(mid 0.249642 0.249642)
							(end 0.1778 0.2794)
						)
					)
					(width 0)
					(fill yes)
				)
			)
		)
		(pad "2" smd custom
			(at 0 0.4445 90)
			(size 0.1397 0.1397)
			(layers "B.Cu" "B.Mask" "B.Paste")
			(net "GND")
			(options
				(clearance outline)
				(anchor circle)
			)
			(primitives
				(gr_poly
					(pts
						(arc
							(start -0.1778 0.2794)
							(mid -0.249642 0.249642)
							(end -0.2794 0.1778)
						)
						(arc
							(start -0.2794 -0.1778)
							(mid -0.249642 -0.249642)
							(end -0.1778 -0.2794)
						)
						(arc
							(start 0.1778 -0.2794)
							(mid 0.249642 -0.249642)
							(end 0.2794 -0.1778)
						)
						(arc
							(start 0.2794 0.1778)
							(mid 0.249642 0.249642)
							(end 0.1778 0.2794)
						)
					)
					(width 0)
					(fill yes)
				)
			)
		)
	)
	(footprint ""
		(layer "B.Cu")
		(at 190.8302 -61.6204 90)
		(property "Reference" "C415"
			(at 0 0 90)
			(layer "B.SilkS")
			(hide yes)
			(effects
				(font
					(size 1.27 1.27)
				)
				(justify mirror)
			)
		)
		(property "Value" "SCD1U6D3V1KX-GP"
			(at 2.8321 -1.7399 90)
			(unlocked yes)
			(layer "B.Fab")
			(hide yes)
			(effects
				(font
					(size 1.016 1.016)
					(thickness 0.1524)
				)
				(justify mirror)
			)
		)
		(property "Device Type" "C0201H13"
			(at 2.8321 -3.2639 90)
			(unlocked yes)
			(layer "B.Fab")
			(hide yes)
			(effects
				(font
					(size 1.016 1.016)
					(thickness 0.1524)
				)
				(justify mirror)
			)
		)
		(duplicate_pad_numbers_are_jumpers no)
		(fp_rect
			(start 0.2794 0.6477)
			(end -0.2794 -0.6477)
			(stroke
				(width 0)
				(type default)
			)
			(fill no)
			(layer "B.CrtYd")
		)
		(fp_rect
			(start 0.2794 0.6477)
			(end -0.2794 -0.6477)
			(stroke
				(width 0)
				(type default)
			)
			(fill no)
			(layer "B.Fab")
		)
		(pad "1" smd custom
			(at 0 -0.2794 270)
			(size 0.0762 0.0762)
			(layers "B.Cu" "B.Mask" "B.Paste")
			(net "P0V975")
			(options
				(clearance outline)
				(anchor circle)
			)
			(primitives
				(gr_poly
					(pts
						(arc
							(start 0.1524 0.127)
							(mid 0.137521 0.162921)
							(end 0.1016 0.1778)
						)
						(arc
							(start -0.1016 0.1778)
							(mid -0.137521 0.162921)
							(end -0.1524 0.127)
						)
						(arc
							(start -0.1524 -0.127)
							(mid -0.137521 -0.162921)
							(end -0.1016 -0.1778)
						)
						(arc
							(start 0.1016 -0.1778)
							(mid 0.137521 -0.162921)
							(end 0.1524 -0.127)
						)
					)
					(width 0)
					(fill yes)
				)
			)
		)
		(pad "2" smd custom
			(at 0 0.2794 270)
			(size 0.0762 0.0762)
			(layers "B.Cu" "B.Mask" "B.Paste")
			(net "GND")
			(options
				(clearance outline)
				(anchor circle)
			)
			(primitives
				(gr_poly
					(pts
						(arc
							(start 0.1524 0.127)
							(mid 0.137521 0.162921)
							(end 0.1016 0.1778)
						)
						(arc
							(start -0.1016 0.1778)
							(mid -0.137521 0.162921)
							(end -0.1524 0.127)
						)
						(arc
							(start -0.1524 -0.127)
							(mid -0.137521 -0.162921)
							(end -0.1016 -0.1778)
						)
						(arc
							(start 0.1016 -0.1778)
							(mid 0.137521 -0.162921)
							(end 0.1524 -0.127)
						)
					)
					(width 0)
					(fill yes)
				)
			)
		)
	)
	(footprint ""
		(layer "B.Cu")
		(at 198.28256 -68.33362 -90)
		(property "Reference" "C383"
			(at 0 0 90)
			(layer "B.SilkS")
			(hide yes)
			(effects
				(font
					(size 1.27 1.27)
				)
				(justify mirror)
			)
		)
		(property "Value" "SCD1U6D3V1KX-GP"
			(at 2.8321 -1.7399 270)
			(unlocked yes)
			(layer "B.Fab")
			(hide yes)
			(effects
				(font
					(size 1.016 1.016)
					(thickness 0.1524)
				)
				(justify mirror)
			)
		)
		(property "Device Type" "C0201H13"
			(at 2.8321 -3.2639 270)
			(unlocked yes)
			(layer "B.Fab")
			(hide yes)
			(effects
				(font
					(size 1.016 1.016)
					(thickness 0.1524)
				)
				(justify mirror)
			)
		)
		(duplicate_pad_numbers_are_jumpers no)
		(fp_rect
			(start 0.2794 0.6477)
			(end -0.2794 -0.6477)
			(stroke
				(width 0)
				(type default)
			)
			(fill no)
			(layer "B.CrtYd")
		)
		(fp_rect
			(start 0.2794 0.6477)
			(end -0.2794 -0.6477)
			(stroke
				(width 0)
				(type default)
			)
			(fill no)
			(layer "B.Fab")
		)
		(pad "1" smd custom
			(at 0 -0.2794 90)
			(size 0.0762 0.0762)
			(layers "B.Cu" "B.Mask" "B.Paste")
			(net "SAS0_AVDD")
			(options
				(clearance outline)
				(anchor circle)
			)
			(primitives
				(gr_poly
					(pts
						(arc
							(start 0.1524 0.127)
							(mid 0.137521 0.162921)
							(end 0.1016 0.1778)
						)
						(arc
							(start -0.1016 0.1778)
							(mid -0.137521 0.162921)
							(end -0.1524 0.127)
						)
						(arc
							(start -0.1524 -0.127)
							(mid -0.137521 -0.162921)
							(end -0.1016 -0.1778)
						)
						(arc
							(start 0.1016 -0.1778)
							(mid 0.137521 -0.162921)
							(end 0.1524 -0.127)
						)
					)
					(width 0)
					(fill yes)
				)
			)
		)
		(pad "2" smd custom
			(at 0 0.2794 90)
			(size 0.0762 0.0762)
			(layers "B.Cu" "B.Mask" "B.Paste")
			(net "GND")
			(options
				(clearance outline)
				(anchor circle)
			)
			(primitives
				(gr_poly
					(pts
						(arc
							(start 0.1524 0.127)
							(mid 0.137521 0.162921)
							(end 0.1016 0.1778)
						)
						(arc
							(start -0.1016 0.1778)
							(mid -0.137521 0.162921)
							(end -0.1524 0.127)
						)
						(arc
							(start -0.1524 -0.127)
							(mid -0.137521 -0.162921)
							(end -0.1016 -0.1778)
						)
						(arc
							(start 0.1016 -0.1778)
							(mid 0.137521 -0.162921)
							(end 0.1524 -0.127)
						)
					)
					(width 0)
					(fill yes)
				)
			)
		)
	)
	(footprint ""
		(layer "B.Cu")
		(at 25.89022 -146.418808 90)
		(property "Reference" "C73"
			(at 0 0 90)
			(layer "B.SilkS")
			(hide yes)
			(effects
				(font
					(size 1.27 1.27)
				)
				(justify mirror)
			)
		)
		(property "Value" "SCD1U16V2KX-3GP"
			(at -1.1811 -2.7051 90)
			(unlocked yes)
			(layer "B.Fab")
			(hide yes)
			(effects
				(font
					(size 1.016 1.016)
					(thickness 0.1524)
				)
				(justify mirror)
			)
		)
		(property "Device Type" "C402H22"
			(at -1.1811 -4.2291 90)
			(unlocked yes)
			(layer "B.Fab")
			(hide yes)
			(effects
				(font
					(size 1.016 1.016)
					(thickness 0.1524)
				)
				(justify mirror)
			)
		)
		(duplicate_pad_numbers_are_jumpers no)
		(fp_rect
			(start 0.4318 0.9525)
			(end -0.4318 -0.9525)
			(stroke
				(width 0)
				(type default)
			)
			(fill no)
			(layer "B.CrtYd")
		)
		(fp_rect
			(start 0.4318 0.9525)
			(end -0.4318 -0.9525)
			(stroke
				(width 0)
				(type default)
			)
			(fill no)
			(layer "B.Fab")
		)
		(pad "1" smd custom
			(at 0 -0.4445 270)
			(size 0.1524 0.1524)
			(layers "B.Cu" "B.Mask" "B.Paste")
			(net "GND")
			(options
				(clearance outline)
				(anchor circle)
			)
			(primitives
				(gr_poly
					(pts
						(arc
							(start 0.3048 0.2032)
							(mid 0.275042 0.275042)
							(end 0.2032 0.3048)
						)
						(arc
							(start -0.2032 0.3048)
							(mid -0.275042 0.275042)
							(end -0.3048 0.2032)
						)
						(arc
							(start -0.3048 -0.2032)
							(mid -0.275042 -0.275042)
							(end -0.2032 -0.3048)
						)
						(arc
							(start 0.2032 -0.3048)
							(mid 0.275042 -0.275042)
							(end 0.3048 -0.2032)
						)
					)
					(width 0)
					(fill yes)
				)
			)
		)
		(pad "2" smd custom
			(at 0 0.4445 270)
			(size 0.1524 0.1524)
			(layers "B.Cu" "B.Mask" "B.Paste")
			(net "P1V2_STBY")
			(options
				(clearance outline)
				(anchor circle)
			)
			(primitives
				(gr_poly
					(pts
						(arc
							(start 0.3048 0.2032)
							(mid 0.275042 0.275042)
							(end 0.2032 0.3048)
						)
						(arc
							(start -0.2032 0.3048)
							(mid -0.275042 0.275042)
							(end -0.3048 0.2032)
						)
						(arc
							(start -0.3048 -0.2032)
							(mid -0.275042 -0.275042)
							(end -0.2032 -0.3048)
						)
						(arc
							(start 0.2032 -0.3048)
							(mid 0.275042 -0.275042)
							(end 0.3048 -0.2032)
						)
					)
					(width 0)
					(fill yes)
				)
			)
		)
	)
	(footprint ""
		(layer "B.Cu")
		(at 12.091924 -132.402326 90)
		(property "Reference" "R238"
			(at 0 0 90)
			(layer "B.SilkS")
			(hide yes)
			(effects
				(font
					(size 1.27 1.27)
				)
				(justify mirror)
			)
		)
		(property "Value" "120R2F-GP"
			(at -0.064008 -3.993896 90)
			(unlocked yes)
			(layer "B.Fab")
			(hide yes)
			(effects
				(font
					(size 1.016 1.016)
					(thickness 0.1524)
				)
				(justify mirror)
			)
		)
		(property "Device Type" "R402H16"
			(at -0.064008 -5.517896 90)
			(unlocked yes)
			(layer "B.Fab")
			(hide yes)
			(effects
				(font
					(size 1.016 1.016)
					(thickness 0.1524)
				)
				(justify mirror)
			)
		)
		(duplicate_pad_numbers_are_jumpers no)
		(fp_line
			(start 0.508 -0.9398)
			(end 0.508 0.9398)
			(stroke
				(width 0.1524)
				(type default)
			)
			(layer "B.SilkS")
		)
		(fp_line
			(start -0.508 -0.9398)
			(end 0.508 -0.9398)
			(stroke
				(width 0.1524)
				(type default)
			)
			(layer "B.SilkS")
		)
		(fp_rect
			(start 0.508 0.9398)
			(end -0.508 -0.9398)
			(stroke
				(width 0)
				(type default)
			)
			(fill no)
			(layer "B.CrtYd")
		)
		(fp_rect
			(start 0.508 0.9398)
			(end -0.508 -0.9398)
			(stroke
				(width 0)
				(type default)
			)
			(fill no)
			(layer "B.Fab")
		)
		(pad "1" smd custom
			(at 0 -0.4445 270)
			(size 0.1397 0.1397)
			(layers "B.Cu" "B.Mask" "B.Paste")
			(net "MEMA_2")
			(options
				(clearance outline)
				(anchor circle)
			)
			(primitives
				(gr_poly
					(pts
						(arc
							(start -0.1778 0.2794)
							(mid -0.249642 0.249642)
							(end -0.2794 0.1778)
						)
						(arc
							(start -0.2794 -0.1778)
							(mid -0.249642 -0.249642)
							(end -0.1778 -0.2794)
						)
						(arc
							(start 0.1778 -0.2794)
							(mid 0.249642 -0.249642)
							(end 0.2794 -0.1778)
						)
						(arc
							(start 0.2794 0.1778)
							(mid 0.249642 0.249642)
							(end 0.1778 0.2794)
						)
					)
					(width 0)
					(fill yes)
				)
			)
		)
		(pad "2" smd custom
			(at 0 0.4445 270)
			(size 0.1397 0.1397)
			(layers "B.Cu" "B.Mask" "B.Paste")
			(net "P1V2_STBY")
			(options
				(clearance outline)
				(anchor circle)
			)
			(primitives
				(gr_poly
					(pts
						(arc
							(start -0.1778 0.2794)
							(mid -0.249642 0.249642)
							(end -0.2794 0.1778)
						)
						(arc
							(start -0.2794 -0.1778)
							(mid -0.249642 -0.249642)
							(end -0.1778 -0.2794)
						)
						(arc
							(start 0.1778 -0.2794)
							(mid 0.249642 -0.249642)
							(end 0.2794 -0.1778)
						)
						(arc
							(start 0.2794 0.1778)
							(mid 0.249642 0.249642)
							(end 0.1778 0.2794)
						)
					)
					(width 0)
					(fill yes)
				)
			)
		)
	)
	(footprint ""
		(layer "B.Cu")
		(at 192.231518 -81.153 180)
		(property "Reference" "C299"
			(at 0 0 0)
			(layer "B.SilkS")
			(hide yes)
			(effects
				(font
					(size 1.27 1.27)
				)
				(justify mirror)
			)
		)
		(property "Value" "SCD22U10V1KX-GP"
			(at 2.8321 -1.7399 180)
			(unlocked yes)
			(layer "B.Fab")
			(hide yes)
			(effects
				(font
					(size 1.016 1.016)
					(thickness 0.1524)
				)
				(justify mirror)
			)
		)
		(property "Device Type" "C0201H13"
			(at 2.8321 -3.2639 180)
			(unlocked yes)
			(layer "B.Fab")
			(hide yes)
			(effects
				(font
					(size 1.016 1.016)
					(thickness 0.1524)
				)
				(justify mirror)
			)
		)
		(duplicate_pad_numbers_are_jumpers no)
		(fp_rect
			(start 0.2794 0.6477)
			(end -0.2794 -0.6477)
			(stroke
				(width 0)
				(type default)
			)
			(fill no)
			(layer "B.CrtYd")
		)
		(fp_rect
			(start 0.2794 0.6477)
			(end -0.2794 -0.6477)
			(stroke
				(width 0)
				(type default)
			)
			(fill no)
			(layer "B.Fab")
		)
		(pad "1" smd custom
			(at 0 -0.2794)
			(size 0.0762 0.0762)
			(layers "B.Cu" "B.Mask" "B.Paste")
			(net "PCIE_IOM_TO_COMP_13_DP_C")
			(options
				(clearance outline)
				(anchor circle)
			)
			(primitives
				(gr_poly
					(pts
						(arc
							(start 0.1524 0.127)
							(mid 0.137521 0.162921)
							(end 0.1016 0.1778)
						)
						(arc
							(start -0.1016 0.1778)
							(mid -0.137521 0.162921)
							(end -0.1524 0.127)
						)
						(arc
							(start -0.1524 -0.127)
							(mid -0.137521 -0.162921)
							(end -0.1016 -0.1778)
						)
						(arc
							(start 0.1016 -0.1778)
							(mid 0.137521 -0.162921)
							(end 0.1524 -0.127)
						)
					)
					(width 0)
					(fill yes)
				)
			)
		)
		(pad "2" smd custom
			(at 0 0.2794)
			(size 0.0762 0.0762)
			(layers "B.Cu" "B.Mask" "B.Paste")
			(net "PCIE_IOM_TO_COMP_13_DP")
			(options
				(clearance outline)
				(anchor circle)
			)
			(primitives
				(gr_poly
					(pts
						(arc
							(start 0.1524 0.127)
							(mid 0.137521 0.162921)
							(end 0.1016 0.1778)
						)
						(arc
							(start -0.1016 0.1778)
							(mid -0.137521 0.162921)
							(end -0.1524 0.127)
						)
						(arc
							(start -0.1524 -0.127)
							(mid -0.137521 -0.162921)
							(end -0.1016 -0.1778)
						)
						(arc
							(start 0.1016 -0.1778)
							(mid 0.137521 -0.162921)
							(end 0.1524 -0.127)
						)
					)
					(width 0)
					(fill yes)
				)
			)
		)
	)
	(footprint ""
		(layer "B.Cu")
		(at 213.2076 -122.301 90)
		(property "Reference" "C247"
			(at 0 0 90)
			(layer "B.SilkS")
			(hide yes)
			(effects
				(font
					(size 1.27 1.27)
				)
				(justify mirror)
			)
		)
		(property "Value" "SC10U6D3V5KX-4GP"
			(at 0.0762 -6.1214 90)
			(unlocked yes)
			(layer "B.Fab")
			(hide yes)
			(effects
				(font
					(size 1.016 1.016)
					(thickness 0.1524)
				)
				(justify mirror)
			)
		)
		(property "Device Type" "C805H58"
			(at 0.0762 -8.1534 90)
			(unlocked yes)
			(layer "B.Fab")
			(hide yes)
			(effects
				(font
					(size 1.016 1.016)
					(thickness 0.1524)
				)
				(justify mirror)
			)
		)
		(duplicate_pad_numbers_are_jumpers no)
		(fp_line
			(start -0.635 0)
			(end 0.635 0)
			(stroke
				(width 0.508)
				(type default)
			)
			(layer "B.SilkS")
		)
		(fp_rect
			(start 0.9652 1.778)
			(end -0.9652 -1.778)
			(stroke
				(width 0)
				(type default)
			)
			(fill no)
			(layer "B.CrtYd")
		)
		(fp_poly
			(pts
				(xy 0.9652 -1.778) (xy -0.9652 -1.778) (xy -0.9652 1.778) (xy 0.9652 1.778)
			)
			(stroke
				(width 0)
				(type default)
			)
			(fill no)
			(layer "B.Fab")
		)
		(pad "1" smd rect
			(at 0 -0.9652 270)
			(size 1.397 1.143)
			(layers "B.Cu" "B.Mask" "B.Paste")
			(net "P1V5_OUT")
		)
		(pad "2" smd rect
			(at 0 0.9652 270)
			(size 1.397 1.143)
			(layers "B.Cu" "B.Mask" "B.Paste")
			(net "GND")
		)
	)
	(footprint ""
		(layer "B.Cu")
		(at 127.104394 -13.60551)
		(property "Reference" "R447"
			(at 0 0 0)
			(layer "B.SilkS")
			(hide yes)
			(effects
				(font
					(size 1.27 1.27)
				)
				(justify mirror)
			)
		)
		(property "Value" "4K12R2F-3-GP"
			(at -0.064008 -3.993896 0)
			(unlocked yes)
			(layer "B.Fab")
			(hide yes)
			(effects
				(font
					(size 1.016 1.016)
					(thickness 0.1524)
				)
				(justify mirror)
			)
		)
		(property "Device Type" "R402H16"
			(at -0.064008 -5.517896 0)
			(unlocked yes)
			(layer "B.Fab")
			(hide yes)
			(effects
				(font
					(size 1.016 1.016)
					(thickness 0.1524)
				)
				(justify mirror)
			)
		)
		(duplicate_pad_numbers_are_jumpers no)
		(fp_line
			(start -0.508 -0.9398)
			(end 0.508 -0.9398)
			(stroke
				(width 0.1524)
				(type default)
			)
			(layer "B.SilkS")
		)
		(fp_line
			(start 0.508 -0.9398)
			(end 0.508 0.9398)
			(stroke
				(width 0.1524)
				(type default)
			)
			(layer "B.SilkS")
		)
		(fp_rect
			(start 0.508 0.9398)
			(end -0.508 -0.9398)
			(stroke
				(width 0)
				(type default)
			)
			(fill no)
			(layer "B.CrtYd")
		)
		(fp_rect
			(start 0.508 0.9398)
			(end -0.508 -0.9398)
			(stroke
				(width 0)
				(type default)
			)
			(fill no)
			(layer "B.Fab")
		)
		(pad "1" smd custom
			(at 0 -0.4445 180)
			(size 0.1397 0.1397)
			(layers "B.Cu" "B.Mask" "B.Paste")
			(net "MB0_CM_OV_R")
			(options
				(clearance outline)
				(anchor circle)
			)
			(primitives
				(gr_poly
					(pts
						(arc
							(start -0.1778 0.2794)
							(mid -0.249642 0.249642)
							(end -0.2794 0.1778)
						)
						(arc
							(start -0.2794 -0.1778)
							(mid -0.249642 -0.249642)
							(end -0.1778 -0.2794)
						)
						(arc
							(start 0.1778 -0.2794)
							(mid 0.249642 -0.249642)
							(end 0.2794 -0.1778)
						)
						(arc
							(start 0.2794 0.1778)
							(mid 0.249642 0.249642)
							(end 0.1778 0.2794)
						)
					)
					(width 0)
					(fill yes)
				)
			)
		)
		(pad "2" smd custom
			(at 0 0.4445 180)
			(size 0.1397 0.1397)
			(layers "B.Cu" "B.Mask" "B.Paste")
			(net "AGND_CURRENT_MON")
			(options
				(clearance outline)
				(anchor circle)
			)
			(primitives
				(gr_poly
					(pts
						(arc
							(start -0.1778 0.2794)
							(mid -0.249642 0.249642)
							(end -0.2794 0.1778)
						)
						(arc
							(start -0.2794 -0.1778)
							(mid -0.249642 -0.249642)
							(end -0.1778 -0.2794)
						)
						(arc
							(start 0.1778 -0.2794)
							(mid 0.249642 -0.249642)
							(end 0.2794 -0.1778)
						)
						(arc
							(start 0.2794 0.1778)
							(mid 0.249642 0.249642)
							(end 0.1778 0.2794)
						)
					)
					(width 0)
					(fill yes)
				)
			)
		)
	)
	(footprint ""
		(layer "B.Cu")
		(at 14.4272 -146.2659 90)
		(property "Reference" "R210"
			(at 0 0 90)
			(layer "B.SilkS")
			(hide yes)
			(effects
				(font
					(size 1.27 1.27)
				)
				(justify mirror)
			)
		)
		(property "Value" "120R2F-GP"
			(at -0.064008 -3.993896 90)
			(unlocked yes)
			(layer "B.Fab")
			(hide yes)
			(effects
				(font
					(size 1.016 1.016)
					(thickness 0.1524)
				)
				(justify mirror)
			)
		)
		(property "Device Type" "R402H16"
			(at -0.064008 -5.517896 90)
			(unlocked yes)
			(layer "B.Fab")
			(hide yes)
			(effects
				(font
					(size 1.016 1.016)
					(thickness 0.1524)
				)
				(justify mirror)
			)
		)
		(duplicate_pad_numbers_are_jumpers no)
		(fp_line
			(start 0.508 -0.9398)
			(end 0.508 0.9398)
			(stroke
				(width 0.1524)
				(type default)
			)
			(layer "B.SilkS")
		)
		(fp_line
			(start -0.508 -0.9398)
			(end 0.508 -0.9398)
			(stroke
				(width 0.1524)
				(type default)
			)
			(layer "B.SilkS")
		)
		(fp_rect
			(start 0.508 0.9398)
			(end -0.508 -0.9398)
			(stroke
				(width 0)
				(type default)
			)
			(fill no)
			(layer "B.CrtYd")
		)
		(fp_rect
			(start 0.508 0.9398)
			(end -0.508 -0.9398)
			(stroke
				(width 0)
				(type default)
			)
			(fill no)
			(layer "B.Fab")
		)
		(pad "1" smd custom
			(at 0 -0.4445 270)
			(size 0.1397 0.1397)
			(layers "B.Cu" "B.Mask" "B.Paste")
			(net "MEMCKE")
			(options
				(clearance outline)
				(anchor circle)
			)
			(primitives
				(gr_poly
					(pts
						(arc
							(start -0.1778 0.2794)
							(mid -0.249642 0.249642)
							(end -0.2794 0.1778)
						)
						(arc
							(start -0.2794 -0.1778)
							(mid -0.249642 -0.249642)
							(end -0.1778 -0.2794)
						)
						(arc
							(start 0.1778 -0.2794)
							(mid 0.249642 -0.249642)
							(end 0.2794 -0.1778)
						)
						(arc
							(start 0.2794 0.1778)
							(mid 0.249642 0.249642)
							(end 0.1778 0.2794)
						)
					)
					(width 0)
					(fill yes)
				)
			)
		)
		(pad "2" smd custom
			(at 0 0.4445 270)
			(size 0.1397 0.1397)
			(layers "B.Cu" "B.Mask" "B.Paste")
			(net "P1V2_STBY")
			(options
				(clearance outline)
				(anchor circle)
			)
			(primitives
				(gr_poly
					(pts
						(arc
							(start -0.1778 0.2794)
							(mid -0.249642 0.249642)
							(end -0.2794 0.1778)
						)
						(arc
							(start -0.2794 -0.1778)
							(mid -0.249642 -0.249642)
							(end -0.1778 -0.2794)
						)
						(arc
							(start 0.1778 -0.2794)
							(mid 0.249642 -0.249642)
							(end 0.2794 -0.1778)
						)
						(arc
							(start 0.2794 0.1778)
							(mid 0.249642 0.249642)
							(end 0.1778 0.2794)
						)
					)
					(width 0)
					(fill yes)
				)
			)
		)
	)
	(footprint ""
		(layer "B.Cu")
		(at 93.98 -175.133 90)
		(property "Reference" "C37"
			(at 0 0 90)
			(layer "B.SilkS")
			(hide yes)
			(effects
				(font
					(size 1.27 1.27)
				)
				(justify mirror)
			)
		)
		(property "Value" "SCD1U16V2KX-3GP"
			(at -1.1811 -2.7051 90)
			(unlocked yes)
			(layer "B.Fab")
			(hide yes)
			(effects
				(font
					(size 1.016 1.016)
					(thickness 0.1524)
				)
				(justify mirror)
			)
		)
		(property "Device Type" "C402H22"
			(at -1.1811 -4.2291 90)
			(unlocked yes)
			(layer "B.Fab")
			(hide yes)
			(effects
				(font
					(size 1.016 1.016)
					(thickness 0.1524)
				)
				(justify mirror)
			)
		)
		(duplicate_pad_numbers_are_jumpers no)
		(fp_rect
			(start 0.4318 0.9525)
			(end -0.4318 -0.9525)
			(stroke
				(width 0)
				(type default)
			)
			(fill no)
			(layer "B.CrtYd")
		)
		(fp_rect
			(start 0.4318 0.9525)
			(end -0.4318 -0.9525)
			(stroke
				(width 0)
				(type default)
			)
			(fill no)
			(layer "B.Fab")
		)
		(pad "1" smd custom
			(at 0 -0.4445 270)
			(size 0.1524 0.1524)
			(layers "B.Cu" "B.Mask" "B.Paste")
			(net "P3V3_STBY")
			(options
				(clearance outline)
				(anchor circle)
			)
			(primitives
				(gr_poly
					(pts
						(arc
							(start 0.3048 0.2032)
							(mid 0.275042 0.275042)
							(end 0.2032 0.3048)
						)
						(arc
							(start -0.2032 0.3048)
							(mid -0.275042 0.275042)
							(end -0.3048 0.2032)
						)
						(arc
							(start -0.3048 -0.2032)
							(mid -0.275042 -0.275042)
							(end -0.2032 -0.3048)
						)
						(arc
							(start 0.2032 -0.3048)
							(mid 0.275042 -0.275042)
							(end 0.3048 -0.2032)
						)
					)
					(width 0)
					(fill yes)
				)
			)
		)
		(pad "2" smd custom
			(at 0 0.4445 270)
			(size 0.1524 0.1524)
			(layers "B.Cu" "B.Mask" "B.Paste")
			(net "GND")
			(options
				(clearance outline)
				(anchor circle)
			)
			(primitives
				(gr_poly
					(pts
						(arc
							(start 0.3048 0.2032)
							(mid 0.275042 0.275042)
							(end 0.2032 0.3048)
						)
						(arc
							(start -0.2032 0.3048)
							(mid -0.275042 0.275042)
							(end -0.3048 0.2032)
						)
						(arc
							(start -0.3048 -0.2032)
							(mid -0.275042 -0.275042)
							(end -0.2032 -0.3048)
						)
						(arc
							(start 0.2032 -0.3048)
							(mid 0.275042 -0.275042)
							(end 0.3048 -0.2032)
						)
					)
					(width 0)
					(fill yes)
				)
			)
		)
	)
	(footprint ""
		(layer "B.Cu")
		(at 12.091924 -133.85673 90)
		(property "Reference" "R243"
			(at 0 0 90)
			(layer "B.SilkS")
			(hide yes)
			(effects
				(font
					(size 1.27 1.27)
				)
				(justify mirror)
			)
		)
		(property "Value" "120R2F-GP"
			(at -0.064008 -3.993896 90)
			(unlocked yes)
			(layer "B.Fab")
			(hide yes)
			(effects
				(font
					(size 1.016 1.016)
					(thickness 0.1524)
				)
				(justify mirror)
			)
		)
		(property "Device Type" "R402H16"
			(at -0.064008 -5.517896 90)
			(unlocked yes)
			(layer "B.Fab")
			(hide yes)
			(effects
				(font
					(size 1.016 1.016)
					(thickness 0.1524)
				)
				(justify mirror)
			)
		)
		(duplicate_pad_numbers_are_jumpers no)
		(fp_line
			(start 0.508 -0.9398)
			(end 0.508 0.9398)
			(stroke
				(width 0.1524)
				(type default)
			)
			(layer "B.SilkS")
		)
		(fp_line
			(start -0.508 -0.9398)
			(end 0.508 -0.9398)
			(stroke
				(width 0.1524)
				(type default)
			)
			(layer "B.SilkS")
		)
		(fp_rect
			(start 0.508 0.9398)
			(end -0.508 -0.9398)
			(stroke
				(width 0)
				(type default)
			)
			(fill no)
			(layer "B.CrtYd")
		)
		(fp_rect
			(start 0.508 0.9398)
			(end -0.508 -0.9398)
			(stroke
				(width 0)
				(type default)
			)
			(fill no)
			(layer "B.Fab")
		)
		(pad "1" smd custom
			(at 0 -0.4445 270)
			(size 0.1397 0.1397)
			(layers "B.Cu" "B.Mask" "B.Paste")
			(net "MEMA_4")
			(options
				(clearance outline)
				(anchor circle)
			)
			(primitives
				(gr_poly
					(pts
						(arc
							(start -0.1778 0.2794)
							(mid -0.249642 0.249642)
							(end -0.2794 0.1778)
						)
						(arc
							(start -0.2794 -0.1778)
							(mid -0.249642 -0.249642)
							(end -0.1778 -0.2794)
						)
						(arc
							(start 0.1778 -0.2794)
							(mid 0.249642 -0.249642)
							(end 0.2794 -0.1778)
						)
						(arc
							(start 0.2794 0.1778)
							(mid 0.249642 0.249642)
							(end 0.1778 0.2794)
						)
					)
					(width 0)
					(fill yes)
				)
			)
		)
		(pad "2" smd custom
			(at 0 0.4445 270)
			(size 0.1397 0.1397)
			(layers "B.Cu" "B.Mask" "B.Paste")
			(net "P1V2_STBY")
			(options
				(clearance outline)
				(anchor circle)
			)
			(primitives
				(gr_poly
					(pts
						(arc
							(start -0.1778 0.2794)
							(mid -0.249642 0.249642)
							(end -0.2794 0.1778)
						)
						(arc
							(start -0.2794 -0.1778)
							(mid -0.249642 -0.249642)
							(end -0.1778 -0.2794)
						)
						(arc
							(start 0.1778 -0.2794)
							(mid 0.249642 -0.249642)
							(end 0.2794 -0.1778)
						)
						(arc
							(start 0.2794 0.1778)
							(mid 0.249642 0.249642)
							(end 0.1778 0.2794)
						)
					)
					(width 0)
					(fill yes)
				)
			)
		)
	)
	(footprint ""
		(layer "B.Cu")
		(at 115.7478 -8.5344 90)
		(property "Reference" "R436"
			(at 0 0 90)
			(layer "B.SilkS")
			(hide yes)
			(effects
				(font
					(size 1.27 1.27)
				)
				(justify mirror)
			)
		)
		(property "Value" "0R2J-2-GP"
			(at -0.064008 -3.993896 90)
			(unlocked yes)
			(layer "B.Fab")
			(hide yes)
			(effects
				(font
					(size 1.016 1.016)
					(thickness 0.1524)
				)
				(justify mirror)
			)
		)
		(property "Device Type" "R402H16"
			(at -0.064008 -5.517896 90)
			(unlocked yes)
			(layer "B.Fab")
			(hide yes)
			(effects
				(font
					(size 1.016 1.016)
					(thickness 0.1524)
				)
				(justify mirror)
			)
		)
		(duplicate_pad_numbers_are_jumpers no)
		(fp_line
			(start 0.508 -0.9398)
			(end 0.508 0.9398)
			(stroke
				(width 0.1524)
				(type default)
			)
			(layer "B.SilkS")
		)
		(fp_line
			(start -0.508 -0.9398)
			(end 0.508 -0.9398)
			(stroke
				(width 0.1524)
				(type default)
			)
			(layer "B.SilkS")
		)
		(fp_rect
			(start 0.508 0.9398)
			(end -0.508 -0.9398)
			(stroke
				(width 0)
				(type default)
			)
			(fill no)
			(layer "B.CrtYd")
		)
		(fp_rect
			(start 0.508 0.9398)
			(end -0.508 -0.9398)
			(stroke
				(width 0)
				(type default)
			)
			(fill no)
			(layer "B.Fab")
		)
		(pad "1" smd custom
			(at 0 -0.4445 270)
			(size 0.1397 0.1397)
			(layers "B.Cu" "B.Mask" "B.Paste")
			(net "P12V_A_PGOOD")
			(options
				(clearance outline)
				(anchor circle)
			)
			(primitives
				(gr_poly
					(pts
						(arc
							(start -0.1778 0.2794)
							(mid -0.249642 0.249642)
							(end -0.2794 0.1778)
						)
						(arc
							(start -0.2794 -0.1778)
							(mid -0.249642 -0.249642)
							(end -0.1778 -0.2794)
						)
						(arc
							(start 0.1778 -0.2794)
							(mid 0.249642 -0.249642)
							(end 0.2794 -0.1778)
						)
						(arc
							(start 0.2794 0.1778)
							(mid 0.249642 0.249642)
							(end 0.1778 0.2794)
						)
					)
					(width 0)
					(fill yes)
				)
			)
		)
		(pad "2" smd custom
			(at 0 0.4445 270)
			(size 0.1397 0.1397)
			(layers "B.Cu" "B.Mask" "B.Paste")
			(net "MB0_HS_ENABLE")
			(options
				(clearance outline)
				(anchor circle)
			)
			(primitives
				(gr_poly
					(pts
						(arc
							(start -0.1778 0.2794)
							(mid -0.249642 0.249642)
							(end -0.2794 0.1778)
						)
						(arc
							(start -0.2794 -0.1778)
							(mid -0.249642 -0.249642)
							(end -0.1778 -0.2794)
						)
						(arc
							(start 0.1778 -0.2794)
							(mid 0.249642 -0.249642)
							(end 0.2794 -0.1778)
						)
						(arc
							(start 0.2794 0.1778)
							(mid 0.249642 0.249642)
							(end 0.1778 0.2794)
						)
					)
					(width 0)
					(fill yes)
				)
			)
		)
	)
	(footprint ""
		(layer "B.Cu")
		(at 46.3296 -142.0368 90)
		(property "Reference" "C100"
			(at 0 0 90)
			(layer "B.SilkS")
			(hide yes)
			(effects
				(font
					(size 1.27 1.27)
				)
				(justify mirror)
			)
		)
		(property "Value" "SC1U16V3KX-5GP"
			(at 0 -2.8194 90)
			(unlocked yes)
			(layer "B.Fab")
			(hide yes)
			(effects
				(font
					(size 1.016 1.016)
					(thickness 0.1524)
				)
				(justify mirror)
			)
		)
		(property "Device Type" "C603H36"
			(at 0 -4.3434 90)
			(unlocked yes)
			(layer "B.Fab")
			(hide yes)
			(effects
				(font
					(size 1.016 1.016)
					(thickness 0.1524)
				)
				(justify mirror)
			)
		)
		(duplicate_pad_numbers_are_jumpers no)
		(fp_line
			(start -0.508 0)
			(end 0.508 0)
			(stroke
				(width 0.2032)
				(type default)
			)
			(layer "B.SilkS")
		)
		(fp_rect
			(start 0.5842 1.3335)
			(end -0.5842 -1.3335)
			(stroke
				(width 0)
				(type default)
			)
			(fill no)
			(layer "B.CrtYd")
		)
		(fp_rect
			(start 0.5842 1.3335)
			(end -0.5842 -1.3335)
			(stroke
				(width 0)
				(type default)
			)
			(fill no)
			(layer "B.Fab")
		)
		(pad "1" smd custom
			(at 0 -0.762 270)
			(size 0.2159 0.2159)
			(layers "B.Cu" "B.Mask" "B.Paste")
			(net "P3V3_STBY")
			(options
				(clearance outline)
				(anchor circle)
			)
			(primitives
				(gr_poly
					(pts
						(arc
							(start -0.3302 0.4318)
							(mid -0.402042 0.402042)
							(end -0.4318 0.3302)
						)
						(arc
							(start -0.4318 -0.3302)
							(mid -0.402042 -0.402042)
							(end -0.3302 -0.4318)
						)
						(arc
							(start 0.3302 -0.4318)
							(mid 0.402042 -0.402042)
							(end 0.4318 -0.3302)
						)
						(arc
							(start 0.4318 0.3302)
							(mid 0.402042 0.402042)
							(end 0.3302 0.4318)
						)
					)
					(width 0)
					(fill yes)
				)
			)
		)
		(pad "2" smd custom
			(at 0 0.762 270)
			(size 0.2159 0.2159)
			(layers "B.Cu" "B.Mask" "B.Paste")
			(net "GND")
			(options
				(clearance outline)
				(anchor circle)
			)
			(primitives
				(gr_poly
					(pts
						(arc
							(start -0.3302 0.4318)
							(mid -0.402042 0.402042)
							(end -0.4318 0.3302)
						)
						(arc
							(start -0.4318 -0.3302)
							(mid -0.402042 -0.402042)
							(end -0.3302 -0.4318)
						)
						(arc
							(start 0.3302 -0.4318)
							(mid 0.402042 -0.402042)
							(end 0.4318 -0.3302)
						)
						(arc
							(start 0.4318 0.3302)
							(mid 0.402042 0.402042)
							(end 0.3302 0.4318)
						)
					)
					(width 0)
					(fill yes)
				)
			)
		)
	)
	(footprint ""
		(layer "B.Cu")
		(at 89.662 -155.6004 90)
		(property "Reference" "C12"
			(at 0 0 90)
			(layer "B.SilkS")
			(hide yes)
			(effects
				(font
					(size 1.27 1.27)
				)
				(justify mirror)
			)
		)
		(property "Value" "SC1U16V2KX-7-GP"
			(at -1.7526 -1.6002 90)
			(unlocked yes)
			(layer "B.Fab")
			(hide yes)
			(effects
				(font
					(size 1.016 1.016)
					(thickness 0.1524)
				)
				(justify mirror)
			)
		)
		(property "Device Type" "C402-TO0D2H24"
			(at -1.7526 -3.1242 90)
			(unlocked yes)
			(layer "B.Fab")
			(hide yes)
			(effects
				(font
					(size 1.016 1.016)
					(thickness 0.1524)
				)
				(justify mirror)
			)
		)
		(duplicate_pad_numbers_are_jumpers no)
		(fp_rect
			(start 0.4826 0.889)
			(end -0.4826 -0.889)
			(stroke
				(width 0)
				(type default)
			)
			(fill no)
			(layer "B.CrtYd")
		)
		(fp_rect
			(start 0.4826 0.889)
			(end -0.4826 -0.889)
			(stroke
				(width 0)
				(type default)
			)
			(fill no)
			(layer "B.Fab")
		)
		(pad "1" smd custom
			(at 0 -0.4572 270)
			(size 0.1524 0.1524)
			(layers "B.Cu" "B.Mask" "B.Paste")
			(net "P3V3_STBY")
			(options
				(clearance outline)
				(anchor circle)
			)
			(primitives
				(gr_poly
					(pts
						(arc
							(start -0.254 -0.3048)
							(mid -0.325842 -0.275042)
							(end -0.3556 -0.2032)
						)
						(arc
							(start -0.3556 0.2032)
							(mid -0.325842 0.275042)
							(end -0.254 0.3048)
						)
						(arc
							(start 0.254 0.3048)
							(mid 0.325842 0.275042)
							(end 0.3556 0.2032)
						)
						(arc
							(start 0.3556 -0.2032)
							(mid 0.325842 -0.275042)
							(end 0.254 -0.3048)
						)
					)
					(width 0)
					(fill yes)
				)
			)
		)
		(pad "2" smd custom
			(at 0 0.4572 270)
			(size 0.1524 0.1524)
			(layers "B.Cu" "B.Mask" "B.Paste")
			(net "GND")
			(options
				(clearance outline)
				(anchor circle)
			)
			(primitives
				(gr_poly
					(pts
						(arc
							(start -0.254 -0.3048)
							(mid -0.325842 -0.275042)
							(end -0.3556 -0.2032)
						)
						(arc
							(start -0.3556 0.2032)
							(mid -0.325842 0.275042)
							(end -0.254 0.3048)
						)
						(arc
							(start 0.254 0.3048)
							(mid 0.325842 0.275042)
							(end 0.3556 0.2032)
						)
						(arc
							(start 0.3556 -0.2032)
							(mid 0.325842 -0.275042)
							(end 0.254 -0.3048)
						)
					)
					(width 0)
					(fill yes)
				)
			)
		)
	)
	(footprint ""
		(layer "B.Cu")
		(at 38.038278 -153.050748 -90)
		(property "Reference" "R321"
			(at 0 0 90)
			(layer "B.SilkS")
			(hide yes)
			(effects
				(font
					(size 1.27 1.27)
				)
				(justify mirror)
			)
		)
		(property "Value" "0R2J-2-GP"
			(at -0.064008 -3.993896 270)
			(unlocked yes)
			(layer "B.Fab")
			(hide yes)
			(effects
				(font
					(size 1.016 1.016)
					(thickness 0.1524)
				)
				(justify mirror)
			)
		)
		(property "Device Type" "R402H16"
			(at -0.064008 -5.517896 270)
			(unlocked yes)
			(layer "B.Fab")
			(hide yes)
			(effects
				(font
					(size 1.016 1.016)
					(thickness 0.1524)
				)
				(justify mirror)
			)
		)
		(duplicate_pad_numbers_are_jumpers no)
		(fp_line
			(start -0.508 -0.9398)
			(end 0.508 -0.9398)
			(stroke
				(width 0.1524)
				(type default)
			)
			(layer "B.SilkS")
		)
		(fp_line
			(start 0.508 -0.9398)
			(end 0.508 0.9398)
			(stroke
				(width 0.1524)
				(type default)
			)
			(layer "B.SilkS")
		)
		(fp_rect
			(start 0.508 0.9398)
			(end -0.508 -0.9398)
			(stroke
				(width 0)
				(type default)
			)
			(fill no)
			(layer "B.CrtYd")
		)
		(fp_rect
			(start 0.508 0.9398)
			(end -0.508 -0.9398)
			(stroke
				(width 0)
				(type default)
			)
			(fill no)
			(layer "B.Fab")
		)
		(pad "1" smd custom
			(at 0 -0.4445 90)
			(size 0.1397 0.1397)
			(layers "B.Cu" "B.Mask" "B.Paste")
			(net "SCC_B_HB_IN_R")
			(options
				(clearance outline)
				(anchor circle)
			)
			(primitives
				(gr_poly
					(pts
						(arc
							(start -0.1778 0.2794)
							(mid -0.249642 0.249642)
							(end -0.2794 0.1778)
						)
						(arc
							(start -0.2794 -0.1778)
							(mid -0.249642 -0.249642)
							(end -0.1778 -0.2794)
						)
						(arc
							(start 0.1778 -0.2794)
							(mid 0.249642 -0.249642)
							(end 0.2794 -0.1778)
						)
						(arc
							(start 0.2794 0.1778)
							(mid 0.249642 0.249642)
							(end 0.1778 0.2794)
						)
					)
					(width 0)
					(fill yes)
				)
			)
		)
		(pad "2" smd custom
			(at 0 0.4445 90)
			(size 0.1397 0.1397)
			(layers "B.Cu" "B.Mask" "B.Paste")
			(net "SCC_RMT_HEARTBEAT")
			(options
				(clearance outline)
				(anchor circle)
			)
			(primitives
				(gr_poly
					(pts
						(arc
							(start -0.1778 0.2794)
							(mid -0.249642 0.249642)
							(end -0.2794 0.1778)
						)
						(arc
							(start -0.2794 -0.1778)
							(mid -0.249642 -0.249642)
							(end -0.1778 -0.2794)
						)
						(arc
							(start 0.1778 -0.2794)
							(mid 0.249642 -0.249642)
							(end 0.2794 -0.1778)
						)
						(arc
							(start 0.2794 0.1778)
							(mid 0.249642 0.249642)
							(end 0.1778 0.2794)
						)
					)
					(width 0)
					(fill yes)
				)
			)
		)
	)
	(footprint ""
		(layer "B.Cu")
		(at 178.098704 -140.824966 90)
		(property "Reference" "C157"
			(at 0 0 90)
			(layer "B.SilkS")
			(hide yes)
			(effects
				(font
					(size 1.27 1.27)
				)
				(justify mirror)
			)
		)
		(property "Value" "SC4D7U25V5KX-1-GP"
			(at 0.0762 -6.1214 90)
			(unlocked yes)
			(layer "B.Fab")
			(hide yes)
			(effects
				(font
					(size 1.016 1.016)
					(thickness 0.1524)
				)
				(justify mirror)
			)
		)
		(property "Device Type" "C805H58"
			(at 0.0762 -8.1534 90)
			(unlocked yes)
			(layer "B.Fab")
			(hide yes)
			(effects
				(font
					(size 1.016 1.016)
					(thickness 0.1524)
				)
				(justify mirror)
			)
		)
		(duplicate_pad_numbers_are_jumpers no)
		(fp_line
			(start -0.635 0)
			(end 0.635 0)
			(stroke
				(width 0.508)
				(type default)
			)
			(layer "B.SilkS")
		)
		(fp_rect
			(start 0.9652 1.778)
			(end -0.9652 -1.778)
			(stroke
				(width 0)
				(type default)
			)
			(fill no)
			(layer "B.CrtYd")
		)
		(fp_poly
			(pts
				(xy 0.9652 -1.778) (xy -0.9652 -1.778) (xy -0.9652 1.778) (xy 0.9652 1.778)
			)
			(stroke
				(width 0)
				(type default)
			)
			(fill no)
			(layer "B.Fab")
		)
		(pad "1" smd rect
			(at 0 -0.9652 270)
			(size 1.397 1.143)
			(layers "B.Cu" "B.Mask" "B.Paste")
			(net "P12V_STBY_VDD_PU1")
		)
		(pad "2" smd rect
			(at 0 0.9652 270)
			(size 1.397 1.143)
			(layers "B.Cu" "B.Mask" "B.Paste")
			(net "GND")
		)
	)
	(footprint ""
		(layer "B.Cu")
		(at 12.091924 -138.144504 90)
		(property "Reference" "R247"
			(at 0 0 90)
			(layer "B.SilkS")
			(hide yes)
			(effects
				(font
					(size 1.27 1.27)
				)
				(justify mirror)
			)
		)
		(property "Value" "120R2F-GP"
			(at -0.064008 -3.993896 90)
			(unlocked yes)
			(layer "B.Fab")
			(hide yes)
			(effects
				(font
					(size 1.016 1.016)
					(thickness 0.1524)
				)
				(justify mirror)
			)
		)
		(property "Device Type" "R402H16"
			(at -0.064008 -5.517896 90)
			(unlocked yes)
			(layer "B.Fab")
			(hide yes)
			(effects
				(font
					(size 1.016 1.016)
					(thickness 0.1524)
				)
				(justify mirror)
			)
		)
		(duplicate_pad_numbers_are_jumpers no)
		(fp_line
			(start 0.508 -0.9398)
			(end 0.508 0.9398)
			(stroke
				(width 0.1524)
				(type default)
			)
			(layer "B.SilkS")
		)
		(fp_line
			(start -0.508 -0.9398)
			(end 0.508 -0.9398)
			(stroke
				(width 0.1524)
				(type default)
			)
			(layer "B.SilkS")
		)
		(fp_rect
			(start 0.508 0.9398)
			(end -0.508 -0.9398)
			(stroke
				(width 0)
				(type default)
			)
			(fill no)
			(layer "B.CrtYd")
		)
		(fp_rect
			(start 0.508 0.9398)
			(end -0.508 -0.9398)
			(stroke
				(width 0)
				(type default)
			)
			(fill no)
			(layer "B.Fab")
		)
		(pad "1" smd custom
			(at 0 -0.4445 270)
			(size 0.1397 0.1397)
			(layers "B.Cu" "B.Mask" "B.Paste")
			(net "MEMA_6")
			(options
				(clearance outline)
				(anchor circle)
			)
			(primitives
				(gr_poly
					(pts
						(arc
							(start -0.1778 0.2794)
							(mid -0.249642 0.249642)
							(end -0.2794 0.1778)
						)
						(arc
							(start -0.2794 -0.1778)
							(mid -0.249642 -0.249642)
							(end -0.1778 -0.2794)
						)
						(arc
							(start 0.1778 -0.2794)
							(mid 0.249642 -0.249642)
							(end 0.2794 -0.1778)
						)
						(arc
							(start 0.2794 0.1778)
							(mid 0.249642 0.249642)
							(end 0.1778 0.2794)
						)
					)
					(width 0)
					(fill yes)
				)
			)
		)
		(pad "2" smd custom
			(at 0 0.4445 270)
			(size 0.1397 0.1397)
			(layers "B.Cu" "B.Mask" "B.Paste")
			(net "P1V2_STBY")
			(options
				(clearance outline)
				(anchor circle)
			)
			(primitives
				(gr_poly
					(pts
						(arc
							(start -0.1778 0.2794)
							(mid -0.249642 0.249642)
							(end -0.2794 0.1778)
						)
						(arc
							(start -0.2794 -0.1778)
							(mid -0.249642 -0.249642)
							(end -0.1778 -0.2794)
						)
						(arc
							(start 0.1778 -0.2794)
							(mid 0.249642 -0.249642)
							(end 0.2794 -0.1778)
						)
						(arc
							(start 0.2794 0.1778)
							(mid 0.249642 0.249642)
							(end 0.1778 0.2794)
						)
					)
					(width 0)
					(fill yes)
				)
			)
		)
	)
	(footprint ""
		(layer "B.Cu")
		(at 56.843168 -163.069524 -90)
		(property "Reference" "R413"
			(at 0 0 90)
			(layer "B.SilkS")
			(hide yes)
			(effects
				(font
					(size 1.27 1.27)
				)
				(justify mirror)
			)
		)
		(property "Value" "2K7R2F-GP"
			(at -0.064008 -3.993896 270)
			(unlocked yes)
			(layer "B.Fab")
			(hide yes)
			(effects
				(font
					(size 1.016 1.016)
					(thickness 0.1524)
				)
				(justify mirror)
			)
		)
		(property "Device Type" "R402H16"
			(at -0.064008 -5.517896 270)
			(unlocked yes)
			(layer "B.Fab")
			(hide yes)
			(effects
				(font
					(size 1.016 1.016)
					(thickness 0.1524)
				)
				(justify mirror)
			)
		)
		(duplicate_pad_numbers_are_jumpers no)
		(fp_line
			(start -0.508 -0.9398)
			(end 0.508 -0.9398)
			(stroke
				(width 0.1524)
				(type default)
			)
			(layer "B.SilkS")
		)
		(fp_line
			(start 0.508 -0.9398)
			(end 0.508 0.9398)
			(stroke
				(width 0.1524)
				(type default)
			)
			(layer "B.SilkS")
		)
		(fp_rect
			(start 0.508 0.9398)
			(end -0.508 -0.9398)
			(stroke
				(width 0)
				(type default)
			)
			(fill no)
			(layer "B.CrtYd")
		)
		(fp_rect
			(start 0.508 0.9398)
			(end -0.508 -0.9398)
			(stroke
				(width 0)
				(type default)
			)
			(fill no)
			(layer "B.Fab")
		)
		(pad "1" smd custom
			(at 0 -0.4445 90)
			(size 0.1397 0.1397)
			(layers "B.Cu" "B.Mask" "B.Paste")
			(net "P5V_STBY")
			(options
				(clearance outline)
				(anchor circle)
			)
			(primitives
				(gr_poly
					(pts
						(arc
							(start -0.1778 0.2794)
							(mid -0.249642 0.249642)
							(end -0.2794 0.1778)
						)
						(arc
							(start -0.2794 -0.1778)
							(mid -0.249642 -0.249642)
							(end -0.1778 -0.2794)
						)
						(arc
							(start 0.1778 -0.2794)
							(mid 0.249642 -0.249642)
							(end 0.2794 -0.1778)
						)
						(arc
							(start 0.2794 0.1778)
							(mid 0.249642 0.249642)
							(end 0.1778 0.2794)
						)
					)
					(width 0)
					(fill yes)
				)
			)
		)
		(pad "2" smd custom
			(at 0 0.4445 90)
			(size 0.1397 0.1397)
			(layers "B.Cu" "B.Mask" "B.Paste")
			(net "ADC_P5V_STBY")
			(options
				(clearance outline)
				(anchor circle)
			)
			(primitives
				(gr_poly
					(pts
						(arc
							(start -0.1778 0.2794)
							(mid -0.249642 0.249642)
							(end -0.2794 0.1778)
						)
						(arc
							(start -0.2794 -0.1778)
							(mid -0.249642 -0.249642)
							(end -0.1778 -0.2794)
						)
						(arc
							(start 0.1778 -0.2794)
							(mid 0.249642 -0.249642)
							(end 0.2794 -0.1778)
						)
						(arc
							(start 0.2794 0.1778)
							(mid 0.249642 0.249642)
							(end 0.1778 0.2794)
						)
					)
					(width 0)
					(fill yes)
				)
			)
		)
	)
	(footprint ""
		(layer "B.Cu")
		(at 39.020496 -138.098276)
		(property "Reference" "TP17"
			(at 0 0 0)
			(layer "B.SilkS")
			(hide yes)
			(effects
				(font
					(size 1.27 1.27)
				)
				(justify mirror)
			)
		)
		(property "Value" "TPAD28-2-GP"
			(at 0.0127 -1.6637 0)
			(unlocked yes)
			(layer "B.Fab")
			(hide yes)
			(effects
				(font
					(size 1.016 1.016)
					(thickness 0.1524)
				)
				(justify mirror)
			)
		)
		(property "Device Type" "TPAD28"
			(at 0.0127 -3.1877 0)
			(unlocked yes)
			(layer "B.Fab")
			(hide yes)
			(effects
				(font
					(size 1.016 1.016)
					(thickness 0.1524)
				)
				(justify mirror)
			)
		)
		(duplicate_pad_numbers_are_jumpers no)
		(fp_poly
			(pts
				(arc
					(start 0.3556 0)
					(mid -0.3556 0)
					(end 0.3556 0)
				)
			)
			(stroke
				(width 0)
				(type default)
			)
			(fill no)
			(layer "B.CrtYd")
		)
		(fp_poly
			(pts
				(arc
					(start 0.6096 0)
					(mid -0.6096 0)
					(end 0.6096 0)
				)
			)
			(stroke
				(width 0)
				(type default)
			)
			(fill no)
			(layer "B.Fab")
		)
		(pad "1" smd circle
			(at 0 0 180)
			(size 0.7112 0.7112)
			(layers "B.Cu" "B.Mask" "B.Paste")
			(net "TP_BMC_GPIOR3")
		)
	)
	(footprint ""
		(layer "B.Cu")
		(at 167.28059 -38.416738)
		(property "Reference" "C501"
			(at 0 0 0)
			(layer "B.SilkS")
			(hide yes)
			(effects
				(font
					(size 1.27 1.27)
				)
				(justify mirror)
			)
		)
		(property "Value" "SCD01U16V1KX-GP"
			(at 2.8321 -1.7399 0)
			(unlocked yes)
			(layer "B.Fab")
			(hide yes)
			(effects
				(font
					(size 1.016 1.016)
					(thickness 0.1524)
				)
				(justify mirror)
			)
		)
		(property "Device Type" "C0201H13"
			(at 2.8321 -3.2639 0)
			(unlocked yes)
			(layer "B.Fab")
			(hide yes)
			(effects
				(font
					(size 1.016 1.016)
					(thickness 0.1524)
				)
				(justify mirror)
			)
		)
		(duplicate_pad_numbers_are_jumpers no)
		(fp_rect
			(start 0.2794 0.6477)
			(end -0.2794 -0.6477)
			(stroke
				(width 0)
				(type default)
			)
			(fill no)
			(layer "B.CrtYd")
		)
		(fp_rect
			(start 0.2794 0.6477)
			(end -0.2794 -0.6477)
			(stroke
				(width 0)
				(type default)
			)
			(fill no)
			(layer "B.Fab")
		)
		(pad "1" smd custom
			(at 0 -0.2794 180)
			(size 0.0762 0.0762)
			(layers "B.Cu" "B.Mask" "B.Paste")
			(net "PHY_CON_B_TO_IOC_2_DN")
			(options
				(clearance outline)
				(anchor circle)
			)
			(primitives
				(gr_poly
					(pts
						(arc
							(start 0.1524 0.127)
							(mid 0.137521 0.162921)
							(end 0.1016 0.1778)
						)
						(arc
							(start -0.1016 0.1778)
							(mid -0.137521 0.162921)
							(end -0.1524 0.127)
						)
						(arc
							(start -0.1524 -0.127)
							(mid -0.137521 -0.162921)
							(end -0.1016 -0.1778)
						)
						(arc
							(start 0.1016 -0.1778)
							(mid 0.137521 -0.162921)
							(end 0.1524 -0.127)
						)
					)
					(width 0)
					(fill yes)
				)
			)
		)
		(pad "2" smd custom
			(at 0 0.2794 180)
			(size 0.0762 0.0762)
			(layers "B.Cu" "B.Mask" "B.Paste")
			(net "PHY_CON_B_TO_IOC_2_DN_C")
			(options
				(clearance outline)
				(anchor circle)
			)
			(primitives
				(gr_poly
					(pts
						(arc
							(start 0.1524 0.127)
							(mid 0.137521 0.162921)
							(end 0.1016 0.1778)
						)
						(arc
							(start -0.1016 0.1778)
							(mid -0.137521 0.162921)
							(end -0.1524 0.127)
						)
						(arc
							(start -0.1524 -0.127)
							(mid -0.137521 -0.162921)
							(end -0.1016 -0.1778)
						)
						(arc
							(start 0.1016 -0.1778)
							(mid 0.137521 -0.162921)
							(end 0.1524 -0.127)
						)
					)
					(width 0)
					(fill yes)
				)
			)
		)
	)
	(footprint ""
		(layer "B.Cu")
		(at 90.2462 -173.5836 90)
		(property "Reference" "R417"
			(at 0 0 90)
			(layer "B.SilkS")
			(hide yes)
			(effects
				(font
					(size 1.27 1.27)
				)
				(justify mirror)
			)
		)
		(property "Value" "0R2J-2-GP"
			(at -0.064008 -3.993896 90)
			(unlocked yes)
			(layer "B.Fab")
			(hide yes)
			(effects
				(font
					(size 1.016 1.016)
					(thickness 0.1524)
				)
				(justify mirror)
			)
		)
		(property "Device Type" "R402H16"
			(at -0.064008 -5.517896 90)
			(unlocked yes)
			(layer "B.Fab")
			(hide yes)
			(effects
				(font
					(size 1.016 1.016)
					(thickness 0.1524)
				)
				(justify mirror)
			)
		)
		(duplicate_pad_numbers_are_jumpers no)
		(fp_line
			(start 0.508 -0.9398)
			(end 0.508 0.9398)
			(stroke
				(width 0.1524)
				(type default)
			)
			(layer "B.SilkS")
		)
		(fp_line
			(start -0.508 -0.9398)
			(end 0.508 -0.9398)
			(stroke
				(width 0.1524)
				(type default)
			)
			(layer "B.SilkS")
		)
		(fp_rect
			(start 0.508 0.9398)
			(end -0.508 -0.9398)
			(stroke
				(width 0)
				(type default)
			)
			(fill no)
			(layer "B.CrtYd")
		)
		(fp_rect
			(start 0.508 0.9398)
			(end -0.508 -0.9398)
			(stroke
				(width 0)
				(type default)
			)
			(fill no)
			(layer "B.Fab")
		)
		(pad "1" smd custom
			(at 0 -0.4445 270)
			(size 0.1397 0.1397)
			(layers "B.Cu" "B.Mask" "B.Paste")
			(net "PCIE_RST_R_N")
			(options
				(clearance outline)
				(anchor circle)
			)
			(primitives
				(gr_poly
					(pts
						(arc
							(start -0.1778 0.2794)
							(mid -0.249642 0.249642)
							(end -0.2794 0.1778)
						)
						(arc
							(start -0.2794 -0.1778)
							(mid -0.249642 -0.249642)
							(end -0.1778 -0.2794)
						)
						(arc
							(start 0.1778 -0.2794)
							(mid 0.249642 -0.249642)
							(end 0.2794 -0.1778)
						)
						(arc
							(start 0.2794 0.1778)
							(mid 0.249642 0.249642)
							(end 0.1778 0.2794)
						)
					)
					(width 0)
					(fill yes)
				)
			)
		)
		(pad "2" smd custom
			(at 0 0.4445 270)
			(size 0.1397 0.1397)
			(layers "B.Cu" "B.Mask" "B.Paste")
			(net "PCIE_COMP_TO_IOM_RST_4")
			(options
				(clearance outline)
				(anchor circle)
			)
			(primitives
				(gr_poly
					(pts
						(arc
							(start -0.1778 0.2794)
							(mid -0.249642 0.249642)
							(end -0.2794 0.1778)
						)
						(arc
							(start -0.2794 -0.1778)
							(mid -0.249642 -0.249642)
							(end -0.1778 -0.2794)
						)
						(arc
							(start 0.1778 -0.2794)
							(mid 0.249642 -0.249642)
							(end 0.2794 -0.1778)
						)
						(arc
							(start 0.2794 0.1778)
							(mid 0.249642 0.249642)
							(end 0.1778 0.2794)
						)
					)
					(width 0)
					(fill yes)
				)
			)
		)
	)
	(footprint ""
		(layer "B.Cu")
		(at 53.5686 -135.7122)
		(property "Reference" "R355"
			(at 0 0 0)
			(layer "B.SilkS")
			(hide yes)
			(effects
				(font
					(size 1.27 1.27)
				)
				(justify mirror)
			)
		)
		(property "Value" "4K7R2F-GP"
			(at -0.064008 -3.993896 0)
			(unlocked yes)
			(layer "B.Fab")
			(hide yes)
			(effects
				(font
					(size 1.016 1.016)
					(thickness 0.1524)
				)
				(justify mirror)
			)
		)
		(property "Device Type" "R402H16"
			(at -0.064008 -5.517896 0)
			(unlocked yes)
			(layer "B.Fab")
			(hide yes)
			(effects
				(font
					(size 1.016 1.016)
					(thickness 0.1524)
				)
				(justify mirror)
			)
		)
		(duplicate_pad_numbers_are_jumpers no)
		(fp_line
			(start -0.508 -0.9398)
			(end 0.508 -0.9398)
			(stroke
				(width 0.1524)
				(type default)
			)
			(layer "B.SilkS")
		)
		(fp_line
			(start 0.508 -0.9398)
			(end 0.508 0.9398)
			(stroke
				(width 0.1524)
				(type default)
			)
			(layer "B.SilkS")
		)
		(fp_rect
			(start 0.508 0.9398)
			(end -0.508 -0.9398)
			(stroke
				(width 0)
				(type default)
			)
			(fill no)
			(layer "B.CrtYd")
		)
		(fp_rect
			(start 0.508 0.9398)
			(end -0.508 -0.9398)
			(stroke
				(width 0)
				(type default)
			)
			(fill no)
			(layer "B.Fab")
		)
		(pad "1" smd custom
			(at 0 -0.4445 180)
			(size 0.1397 0.1397)
			(layers "B.Cu" "B.Mask" "B.Paste")
			(net "SLOTID_1")
			(options
				(clearance outline)
				(anchor circle)
			)
			(primitives
				(gr_poly
					(pts
						(arc
							(start -0.1778 0.2794)
							(mid -0.249642 0.249642)
							(end -0.2794 0.1778)
						)
						(arc
							(start -0.2794 -0.1778)
							(mid -0.249642 -0.249642)
							(end -0.1778 -0.2794)
						)
						(arc
							(start 0.1778 -0.2794)
							(mid 0.249642 -0.249642)
							(end 0.2794 -0.1778)
						)
						(arc
							(start 0.2794 0.1778)
							(mid 0.249642 0.249642)
							(end 0.1778 0.2794)
						)
					)
					(width 0)
					(fill yes)
				)
			)
		)
		(pad "2" smd custom
			(at 0 0.4445 180)
			(size 0.1397 0.1397)
			(layers "B.Cu" "B.Mask" "B.Paste")
			(net "GND")
			(options
				(clearance outline)
				(anchor circle)
			)
			(primitives
				(gr_poly
					(pts
						(arc
							(start -0.1778 0.2794)
							(mid -0.249642 0.249642)
							(end -0.2794 0.1778)
						)
						(arc
							(start -0.2794 -0.1778)
							(mid -0.249642 -0.249642)
							(end -0.1778 -0.2794)
						)
						(arc
							(start 0.1778 -0.2794)
							(mid 0.249642 -0.249642)
							(end 0.2794 -0.1778)
						)
						(arc
							(start 0.2794 0.1778)
							(mid 0.249642 0.249642)
							(end 0.1778 0.2794)
						)
					)
					(width 0)
					(fill yes)
				)
			)
		)
	)
	(footprint ""
		(layer "B.Cu")
		(at 78.9178 -142.4686 180)
		(property "Reference" "R127"
			(at 0 0 0)
			(layer "B.SilkS")
			(hide yes)
			(effects
				(font
					(size 1.27 1.27)
				)
				(justify mirror)
			)
		)
		(property "Value" "0R2J-2-GP"
			(at -0.064008 -3.993896 180)
			(unlocked yes)
			(layer "B.Fab")
			(hide yes)
			(effects
				(font
					(size 1.016 1.016)
					(thickness 0.1524)
				)
				(justify mirror)
			)
		)
		(property "Device Type" "R402H16"
			(at -0.064008 -5.517896 180)
			(unlocked yes)
			(layer "B.Fab")
			(hide yes)
			(effects
				(font
					(size 1.016 1.016)
					(thickness 0.1524)
				)
				(justify mirror)
			)
		)
		(duplicate_pad_numbers_are_jumpers no)
		(fp_line
			(start 0.508 -0.9398)
			(end 0.508 0.9398)
			(stroke
				(width 0.1524)
				(type default)
			)
			(layer "B.SilkS")
		)
		(fp_line
			(start -0.508 -0.9398)
			(end 0.508 -0.9398)
			(stroke
				(width 0.1524)
				(type default)
			)
			(layer "B.SilkS")
		)
		(fp_rect
			(start 0.508 0.9398)
			(end -0.508 -0.9398)
			(stroke
				(width 0)
				(type default)
			)
			(fill no)
			(layer "B.CrtYd")
		)
		(fp_rect
			(start 0.508 0.9398)
			(end -0.508 -0.9398)
			(stroke
				(width 0)
				(type default)
			)
			(fill no)
			(layer "B.Fab")
		)
		(pad "1" smd custom
			(at 0 -0.4445)
			(size 0.1397 0.1397)
			(layers "B.Cu" "B.Mask" "B.Paste")
			(net "I2C_EXP_LOC_SCL")
			(options
				(clearance outline)
				(anchor circle)
			)
			(primitives
				(gr_poly
					(pts
						(arc
							(start -0.1778 0.2794)
							(mid -0.249642 0.249642)
							(end -0.2794 0.1778)
						)
						(arc
							(start -0.2794 -0.1778)
							(mid -0.249642 -0.249642)
							(end -0.1778 -0.2794)
						)
						(arc
							(start 0.1778 -0.2794)
							(mid 0.249642 -0.249642)
							(end 0.2794 -0.1778)
						)
						(arc
							(start 0.2794 0.1778)
							(mid 0.249642 0.249642)
							(end 0.1778 0.2794)
						)
					)
					(width 0)
					(fill yes)
				)
			)
		)
		(pad "2" smd custom
			(at 0 0.4445)
			(size 0.1397 0.1397)
			(layers "B.Cu" "B.Mask" "B.Paste")
			(net "I2C_EXP_LOC_SCL_R")
			(options
				(clearance outline)
				(anchor circle)
			)
			(primitives
				(gr_poly
					(pts
						(arc
							(start -0.1778 0.2794)
							(mid -0.249642 0.249642)
							(end -0.2794 0.1778)
						)
						(arc
							(start -0.2794 -0.1778)
							(mid -0.249642 -0.249642)
							(end -0.1778 -0.2794)
						)
						(arc
							(start 0.1778 -0.2794)
							(mid 0.249642 -0.249642)
							(end 0.2794 -0.1778)
						)
						(arc
							(start 0.2794 0.1778)
							(mid 0.249642 0.249642)
							(end 0.1778 0.2794)
						)
					)
					(width 0)
					(fill yes)
				)
			)
		)
	)
	(footprint ""
		(layer "B.Cu")
		(at 44.323 -135.6614 180)
		(property "Reference" "R372"
			(at 0 0 0)
			(layer "B.SilkS")
			(hide yes)
			(effects
				(font
					(size 1.27 1.27)
				)
				(justify mirror)
			)
		)
		(property "Value" "4K7R2F-GP"
			(at -0.064008 -3.993896 180)
			(unlocked yes)
			(layer "B.Fab")
			(hide yes)
			(effects
				(font
					(size 1.016 1.016)
					(thickness 0.1524)
				)
				(justify mirror)
			)
		)
		(property "Device Type" "R402H16"
			(at -0.064008 -5.517896 180)
			(unlocked yes)
			(layer "B.Fab")
			(hide yes)
			(effects
				(font
					(size 1.016 1.016)
					(thickness 0.1524)
				)
				(justify mirror)
			)
		)
		(duplicate_pad_numbers_are_jumpers no)
		(fp_line
			(start 0.508 -0.9398)
			(end 0.508 0.9398)
			(stroke
				(width 0.1524)
				(type default)
			)
			(layer "B.SilkS")
		)
		(fp_line
			(start -0.508 -0.9398)
			(end 0.508 -0.9398)
			(stroke
				(width 0.1524)
				(type default)
			)
			(layer "B.SilkS")
		)
		(fp_rect
			(start 0.508 0.9398)
			(end -0.508 -0.9398)
			(stroke
				(width 0)
				(type default)
			)
			(fill no)
			(layer "B.CrtYd")
		)
		(fp_rect
			(start 0.508 0.9398)
			(end -0.508 -0.9398)
			(stroke
				(width 0)
				(type default)
			)
			(fill no)
			(layer "B.Fab")
		)
		(pad "1" smd custom
			(at 0 -0.4445)
			(size 0.1397 0.1397)
			(layers "B.Cu" "B.Mask" "B.Paste")
			(net "P3V3_STBY")
			(options
				(clearance outline)
				(anchor circle)
			)
			(primitives
				(gr_poly
					(pts
						(arc
							(start -0.1778 0.2794)
							(mid -0.249642 0.249642)
							(end -0.2794 0.1778)
						)
						(arc
							(start -0.2794 -0.1778)
							(mid -0.249642 -0.249642)
							(end -0.1778 -0.2794)
						)
						(arc
							(start 0.1778 -0.2794)
							(mid 0.249642 -0.249642)
							(end 0.2794 -0.1778)
						)
						(arc
							(start 0.2794 0.1778)
							(mid 0.249642 0.249642)
							(end 0.1778 0.2794)
						)
					)
					(width 0)
					(fill yes)
				)
			)
		)
		(pad "2" smd custom
			(at 0 0.4445)
			(size 0.1397 0.1397)
			(layers "B.Cu" "B.Mask" "B.Paste")
			(net "BMC_GPIOS4")
			(options
				(clearance outline)
				(anchor circle)
			)
			(primitives
				(gr_poly
					(pts
						(arc
							(start -0.1778 0.2794)
							(mid -0.249642 0.249642)
							(end -0.2794 0.1778)
						)
						(arc
							(start -0.2794 -0.1778)
							(mid -0.249642 -0.249642)
							(end -0.1778 -0.2794)
						)
						(arc
							(start 0.1778 -0.2794)
							(mid 0.249642 -0.249642)
							(end 0.2794 -0.1778)
						)
						(arc
							(start 0.2794 0.1778)
							(mid 0.249642 0.249642)
							(end 0.1778 0.2794)
						)
					)
					(width 0)
					(fill yes)
				)
			)
		)
	)
	(footprint ""
		(layer "B.Cu")
		(at 38.98773 -140.300964 180)
		(property "Reference" "C97"
			(at 0 0 0)
			(layer "B.SilkS")
			(hide yes)
			(effects
				(font
					(size 1.27 1.27)
				)
				(justify mirror)
			)
		)
		(property "Value" "SC1U16V3KX-5GP"
			(at 0 -2.8194 180)
			(unlocked yes)
			(layer "B.Fab")
			(hide yes)
			(effects
				(font
					(size 1.016 1.016)
					(thickness 0.1524)
				)
				(justify mirror)
			)
		)
		(property "Device Type" "C603H36"
			(at 0 -4.3434 180)
			(unlocked yes)
			(layer "B.Fab")
			(hide yes)
			(effects
				(font
					(size 1.016 1.016)
					(thickness 0.1524)
				)
				(justify mirror)
			)
		)
		(duplicate_pad_numbers_are_jumpers no)
		(fp_line
			(start -0.508 0)
			(end 0.508 0)
			(stroke
				(width 0.2032)
				(type default)
			)
			(layer "B.SilkS")
		)
		(fp_rect
			(start 0.5842 1.3335)
			(end -0.5842 -1.3335)
			(stroke
				(width 0)
				(type default)
			)
			(fill no)
			(layer "B.CrtYd")
		)
		(fp_rect
			(start 0.5842 1.3335)
			(end -0.5842 -1.3335)
			(stroke
				(width 0)
				(type default)
			)
			(fill no)
			(layer "B.Fab")
		)
		(pad "1" smd custom
			(at 0 -0.762)
			(size 0.2159 0.2159)
			(layers "B.Cu" "B.Mask" "B.Paste")
			(net "P3V3_STBY")
			(options
				(clearance outline)
				(anchor circle)
			)
			(primitives
				(gr_poly
					(pts
						(arc
							(start -0.3302 0.4318)
							(mid -0.402042 0.402042)
							(end -0.4318 0.3302)
						)
						(arc
							(start -0.4318 -0.3302)
							(mid -0.402042 -0.402042)
							(end -0.3302 -0.4318)
						)
						(arc
							(start 0.3302 -0.4318)
							(mid 0.402042 -0.402042)
							(end 0.4318 -0.3302)
						)
						(arc
							(start 0.4318 0.3302)
							(mid 0.402042 0.402042)
							(end 0.3302 0.4318)
						)
					)
					(width 0)
					(fill yes)
				)
			)
		)
		(pad "2" smd custom
			(at 0 0.762)
			(size 0.2159 0.2159)
			(layers "B.Cu" "B.Mask" "B.Paste")
			(net "GND")
			(options
				(clearance outline)
				(anchor circle)
			)
			(primitives
				(gr_poly
					(pts
						(arc
							(start -0.3302 0.4318)
							(mid -0.402042 0.402042)
							(end -0.4318 0.3302)
						)
						(arc
							(start -0.4318 -0.3302)
							(mid -0.402042 -0.402042)
							(end -0.3302 -0.4318)
						)
						(arc
							(start 0.3302 -0.4318)
							(mid 0.402042 -0.402042)
							(end 0.4318 -0.3302)
						)
						(arc
							(start 0.4318 0.3302)
							(mid 0.402042 0.402042)
							(end 0.3302 0.4318)
						)
					)
					(width 0)
					(fill yes)
				)
			)
		)
	)
	(footprint ""
		(layer "B.Cu")
		(at 35.007296 -139.330684 180)
		(property "Reference" "C106"
			(at 0 0 0)
			(layer "B.SilkS")
			(hide yes)
			(effects
				(font
					(size 1.27 1.27)
				)
				(justify mirror)
			)
		)
		(property "Value" "SC4D7U25V5KX-1-GP"
			(at 0.0762 -6.1214 180)
			(unlocked yes)
			(layer "B.Fab")
			(hide yes)
			(effects
				(font
					(size 1.016 1.016)
					(thickness 0.1524)
				)
				(justify mirror)
			)
		)
		(property "Device Type" "C805H58"
			(at 0.0762 -8.1534 180)
			(unlocked yes)
			(layer "B.Fab")
			(hide yes)
			(effects
				(font
					(size 1.016 1.016)
					(thickness 0.1524)
				)
				(justify mirror)
			)
		)
		(duplicate_pad_numbers_are_jumpers no)
		(fp_line
			(start -0.635 0)
			(end 0.635 0)
			(stroke
				(width 0.508)
				(type default)
			)
			(layer "B.SilkS")
		)
		(fp_rect
			(start 0.9652 1.778)
			(end -0.9652 -1.778)
			(stroke
				(width 0)
				(type default)
			)
			(fill no)
			(layer "B.CrtYd")
		)
		(fp_poly
			(pts
				(xy 0.9652 -1.778) (xy -0.9652 -1.778) (xy -0.9652 1.778) (xy 0.9652 1.778)
			)
			(stroke
				(width 0)
				(type default)
			)
			(fill no)
			(layer "B.Fab")
		)
		(pad "1" smd rect
			(at 0 -0.9652)
			(size 1.397 1.143)
			(layers "B.Cu" "B.Mask" "B.Paste")
			(net "P3V3_STBY")
		)
		(pad "2" smd rect
			(at 0 0.9652)
			(size 1.397 1.143)
			(layers "B.Cu" "B.Mask" "B.Paste")
			(net "GND")
		)
	)
	(footprint ""
		(layer "B.Cu")
		(at 180.866542 -64.486282 90)
		(property "Reference" "R584"
			(at 0 0 90)
			(layer "B.SilkS")
			(hide yes)
			(effects
				(font
					(size 1.27 1.27)
				)
				(justify mirror)
			)
		)
		(property "Value" "2K2R2F-GP"
			(at -0.064008 -3.993896 90)
			(unlocked yes)
			(layer "B.Fab")
			(hide yes)
			(effects
				(font
					(size 1.016 1.016)
					(thickness 0.1524)
				)
				(justify mirror)
			)
		)
		(property "Device Type" "R402H16"
			(at -0.064008 -5.517896 90)
			(unlocked yes)
			(layer "B.Fab")
			(hide yes)
			(effects
				(font
					(size 1.016 1.016)
					(thickness 0.1524)
				)
				(justify mirror)
			)
		)
		(duplicate_pad_numbers_are_jumpers no)
		(fp_line
			(start 0.508 -0.9398)
			(end 0.508 0.9398)
			(stroke
				(width 0.1524)
				(type default)
			)
			(layer "B.SilkS")
		)
		(fp_line
			(start -0.508 -0.9398)
			(end 0.508 -0.9398)
			(stroke
				(width 0.1524)
				(type default)
			)
			(layer "B.SilkS")
		)
		(fp_rect
			(start 0.508 0.9398)
			(end -0.508 -0.9398)
			(stroke
				(width 0)
				(type default)
			)
			(fill no)
			(layer "B.CrtYd")
		)
		(fp_rect
			(start 0.508 0.9398)
			(end -0.508 -0.9398)
			(stroke
				(width 0)
				(type default)
			)
			(fill no)
			(layer "B.Fab")
		)
		(pad "1" smd custom
			(at 0 -0.4445 270)
			(size 0.1397 0.1397)
			(layers "B.Cu" "B.Mask" "B.Paste")
			(net "P1V8")
			(options
				(clearance outline)
				(anchor circle)
			)
			(primitives
				(gr_poly
					(pts
						(arc
							(start -0.1778 0.2794)
							(mid -0.249642 0.249642)
							(end -0.2794 0.1778)
						)
						(arc
							(start -0.2794 -0.1778)
							(mid -0.249642 -0.249642)
							(end -0.1778 -0.2794)
						)
						(arc
							(start 0.1778 -0.2794)
							(mid 0.249642 -0.249642)
							(end 0.2794 -0.1778)
						)
						(arc
							(start 0.2794 0.1778)
							(mid 0.249642 0.249642)
							(end 0.1778 0.2794)
						)
					)
					(width 0)
					(fill yes)
				)
			)
		)
		(pad "2" smd custom
			(at 0 0.4445 270)
			(size 0.1397 0.1397)
			(layers "B.Cu" "B.Mask" "B.Paste")
			(net "IOC_SCL_3")
			(options
				(clearance outline)
				(anchor circle)
			)
			(primitives
				(gr_poly
					(pts
						(arc
							(start -0.1778 0.2794)
							(mid -0.249642 0.249642)
							(end -0.2794 0.1778)
						)
						(arc
							(start -0.2794 -0.1778)
							(mid -0.249642 -0.249642)
							(end -0.1778 -0.2794)
						)
						(arc
							(start 0.1778 -0.2794)
							(mid 0.249642 -0.249642)
							(end 0.2794 -0.1778)
						)
						(arc
							(start 0.2794 0.1778)
							(mid 0.249642 0.249642)
							(end 0.1778 0.2794)
						)
					)
					(width 0)
					(fill yes)
				)
			)
		)
	)
	(footprint ""
		(layer "B.Cu")
		(at 203.327 -77.978 90)
		(property "Reference" "C377"
			(at 0 0 90)
			(layer "B.SilkS")
			(hide yes)
			(effects
				(font
					(size 1.27 1.27)
				)
				(justify mirror)
			)
		)
		(property "Value" "SCD1U6D3V1KX-GP"
			(at 2.8321 -1.7399 90)
			(unlocked yes)
			(layer "B.Fab")
			(hide yes)
			(effects
				(font
					(size 1.016 1.016)
					(thickness 0.1524)
				)
				(justify mirror)
			)
		)
		(property "Device Type" "C0201H13"
			(at 2.8321 -3.2639 90)
			(unlocked yes)
			(layer "B.Fab")
			(hide yes)
			(effects
				(font
					(size 1.016 1.016)
					(thickness 0.1524)
				)
				(justify mirror)
			)
		)
		(duplicate_pad_numbers_are_jumpers no)
		(fp_rect
			(start 0.2794 0.6477)
			(end -0.2794 -0.6477)
			(stroke
				(width 0)
				(type default)
			)
			(fill no)
			(layer "B.CrtYd")
		)
		(fp_rect
			(start 0.2794 0.6477)
			(end -0.2794 -0.6477)
			(stroke
				(width 0)
				(type default)
			)
			(fill no)
			(layer "B.Fab")
		)
		(pad "1" smd custom
			(at 0 -0.2794 270)
			(size 0.0762 0.0762)
			(layers "B.Cu" "B.Mask" "B.Paste")
			(net "SAS0_AVDD")
			(options
				(clearance outline)
				(anchor circle)
			)
			(primitives
				(gr_poly
					(pts
						(arc
							(start 0.1524 0.127)
							(mid 0.137521 0.162921)
							(end 0.1016 0.1778)
						)
						(arc
							(start -0.1016 0.1778)
							(mid -0.137521 0.162921)
							(end -0.1524 0.127)
						)
						(arc
							(start -0.1524 -0.127)
							(mid -0.137521 -0.162921)
							(end -0.1016 -0.1778)
						)
						(arc
							(start 0.1016 -0.1778)
							(mid 0.137521 -0.162921)
							(end 0.1524 -0.127)
						)
					)
					(width 0)
					(fill yes)
				)
			)
		)
		(pad "2" smd custom
			(at 0 0.2794 270)
			(size 0.0762 0.0762)
			(layers "B.Cu" "B.Mask" "B.Paste")
			(net "GND")
			(options
				(clearance outline)
				(anchor circle)
			)
			(primitives
				(gr_poly
					(pts
						(arc
							(start 0.1524 0.127)
							(mid 0.137521 0.162921)
							(end 0.1016 0.1778)
						)
						(arc
							(start -0.1016 0.1778)
							(mid -0.137521 0.162921)
							(end -0.1524 0.127)
						)
						(arc
							(start -0.1524 -0.127)
							(mid -0.137521 -0.162921)
							(end -0.1016 -0.1778)
						)
						(arc
							(start 0.1016 -0.1778)
							(mid 0.137521 -0.162921)
							(end 0.1524 -0.127)
						)
					)
					(width 0)
					(fill yes)
				)
			)
		)
	)
	(footprint ""
		(layer "B.Cu")
		(at 23.440644 -131.007358 180)
		(property "Reference" "R249"
			(at 0 0 0)
			(layer "B.SilkS")
			(hide yes)
			(effects
				(font
					(size 1.27 1.27)
				)
				(justify mirror)
			)
		)
		(property "Value" "120R2F-GP"
			(at -0.064008 -3.993896 180)
			(unlocked yes)
			(layer "B.Fab")
			(hide yes)
			(effects
				(font
					(size 1.016 1.016)
					(thickness 0.1524)
				)
				(justify mirror)
			)
		)
		(property "Device Type" "R402H16"
			(at -0.064008 -5.517896 180)
			(unlocked yes)
			(layer "B.Fab")
			(hide yes)
			(effects
				(font
					(size 1.016 1.016)
					(thickness 0.1524)
				)
				(justify mirror)
			)
		)
		(duplicate_pad_numbers_are_jumpers no)
		(fp_line
			(start 0.508 -0.9398)
			(end 0.508 0.9398)
			(stroke
				(width 0.1524)
				(type default)
			)
			(layer "B.SilkS")
		)
		(fp_line
			(start -0.508 -0.9398)
			(end 0.508 -0.9398)
			(stroke
				(width 0.1524)
				(type default)
			)
			(layer "B.SilkS")
		)
		(fp_rect
			(start 0.508 0.9398)
			(end -0.508 -0.9398)
			(stroke
				(width 0)
				(type default)
			)
			(fill no)
			(layer "B.CrtYd")
		)
		(fp_rect
			(start 0.508 0.9398)
			(end -0.508 -0.9398)
			(stroke
				(width 0)
				(type default)
			)
			(fill no)
			(layer "B.Fab")
		)
		(pad "1" smd custom
			(at 0 -0.4445)
			(size 0.1397 0.1397)
			(layers "B.Cu" "B.Mask" "B.Paste")
			(net "MEMA_7")
			(options
				(clearance outline)
				(anchor circle)
			)
			(primitives
				(gr_poly
					(pts
						(arc
							(start -0.1778 0.2794)
							(mid -0.249642 0.249642)
							(end -0.2794 0.1778)
						)
						(arc
							(start -0.2794 -0.1778)
							(mid -0.249642 -0.249642)
							(end -0.1778 -0.2794)
						)
						(arc
							(start 0.1778 -0.2794)
							(mid 0.249642 -0.249642)
							(end 0.2794 -0.1778)
						)
						(arc
							(start 0.2794 0.1778)
							(mid 0.249642 0.249642)
							(end 0.1778 0.2794)
						)
					)
					(width 0)
					(fill yes)
				)
			)
		)
		(pad "2" smd custom
			(at 0 0.4445)
			(size 0.1397 0.1397)
			(layers "B.Cu" "B.Mask" "B.Paste")
			(net "P1V2_STBY")
			(options
				(clearance outline)
				(anchor circle)
			)
			(primitives
				(gr_poly
					(pts
						(arc
							(start -0.1778 0.2794)
							(mid -0.249642 0.249642)
							(end -0.2794 0.1778)
						)
						(arc
							(start -0.2794 -0.1778)
							(mid -0.249642 -0.249642)
							(end -0.1778 -0.2794)
						)
						(arc
							(start 0.1778 -0.2794)
							(mid 0.249642 -0.249642)
							(end 0.2794 -0.1778)
						)
						(arc
							(start 0.2794 0.1778)
							(mid 0.249642 0.249642)
							(end 0.1778 0.2794)
						)
					)
					(width 0)
					(fill yes)
				)
			)
		)
	)
	(footprint ""
		(layer "B.Cu")
		(at 36.585398 -140.280644)
		(property "Reference" "C104"
			(at 0 0 0)
			(layer "B.SilkS")
			(hide yes)
			(effects
				(font
					(size 1.27 1.27)
				)
				(justify mirror)
			)
		)
		(property "Value" "SC10U6D3V3KX-1-GP"
			(at 0 -2.8194 0)
			(unlocked yes)
			(layer "B.Fab")
			(hide yes)
			(effects
				(font
					(size 1.016 1.016)
					(thickness 0.1524)
				)
				(justify mirror)
			)
		)
		(property "Device Type" "C603H40"
			(at 0 -4.3434 0)
			(unlocked yes)
			(layer "B.Fab")
			(hide yes)
			(effects
				(font
					(size 1.016 1.016)
					(thickness 0.1524)
				)
				(justify mirror)
			)
		)
		(duplicate_pad_numbers_are_jumpers no)
		(fp_line
			(start -0.508 0)
			(end 0.508 0)
			(stroke
				(width 0.2032)
				(type default)
			)
			(layer "B.SilkS")
		)
		(fp_rect
			(start 0.5842 1.3335)
			(end -0.5842 -1.3335)
			(stroke
				(width 0)
				(type default)
			)
			(fill no)
			(layer "B.CrtYd")
		)
		(fp_rect
			(start 0.5842 1.3335)
			(end -0.5842 -1.3335)
			(stroke
				(width 0)
				(type default)
			)
			(fill no)
			(layer "B.Fab")
		)
		(pad "1" smd custom
			(at 0 -0.762 180)
			(size 0.2159 0.2159)
			(layers "B.Cu" "B.Mask" "B.Paste")
			(net "GND")
			(options
				(clearance outline)
				(anchor circle)
			)
			(primitives
				(gr_poly
					(pts
						(arc
							(start -0.3302 0.4318)
							(mid -0.402042 0.402042)
							(end -0.4318 0.3302)
						)
						(arc
							(start -0.4318 -0.3302)
							(mid -0.402042 -0.402042)
							(end -0.3302 -0.4318)
						)
						(arc
							(start 0.3302 -0.4318)
							(mid 0.402042 -0.402042)
							(end 0.4318 -0.3302)
						)
						(arc
							(start 0.4318 0.3302)
							(mid 0.402042 0.402042)
							(end 0.3302 0.4318)
						)
					)
					(width 0)
					(fill yes)
				)
			)
		)
		(pad "2" smd custom
			(at 0 0.762 180)
			(size 0.2159 0.2159)
			(layers "B.Cu" "B.Mask" "B.Paste")
			(net "P3V3_STBY")
			(options
				(clearance outline)
				(anchor circle)
			)
			(primitives
				(gr_poly
					(pts
						(arc
							(start -0.3302 0.4318)
							(mid -0.402042 0.402042)
							(end -0.4318 0.3302)
						)
						(arc
							(start -0.4318 -0.3302)
							(mid -0.402042 -0.402042)
							(end -0.3302 -0.4318)
						)
						(arc
							(start 0.3302 -0.4318)
							(mid 0.402042 -0.402042)
							(end 0.4318 -0.3302)
						)
						(arc
							(start 0.4318 0.3302)
							(mid 0.402042 0.402042)
							(end 0.3302 0.4318)
						)
					)
					(width 0)
					(fill yes)
				)
			)
		)
	)
	(footprint ""
		(layer "B.Cu")
		(at 43.3832 -128.2192)
		(property "Reference" "R270"
			(at 0 0 0)
			(layer "B.SilkS")
			(hide yes)
			(effects
				(font
					(size 1.27 1.27)
				)
				(justify mirror)
			)
		)
		(property "Value" "33R2F-3-GP"
			(at -0.064008 -3.993896 0)
			(unlocked yes)
			(layer "B.Fab")
			(hide yes)
			(effects
				(font
					(size 1.016 1.016)
					(thickness 0.1524)
				)
				(justify mirror)
			)
		)
		(property "Device Type" "R402H16"
			(at -0.064008 -5.517896 0)
			(unlocked yes)
			(layer "B.Fab")
			(hide yes)
			(effects
				(font
					(size 1.016 1.016)
					(thickness 0.1524)
				)
				(justify mirror)
			)
		)
		(duplicate_pad_numbers_are_jumpers no)
		(fp_line
			(start -0.508 -0.9398)
			(end 0.508 -0.9398)
			(stroke
				(width 0.1524)
				(type default)
			)
			(layer "B.SilkS")
		)
		(fp_line
			(start 0.508 -0.9398)
			(end 0.508 0.9398)
			(stroke
				(width 0.1524)
				(type default)
			)
			(layer "B.SilkS")
		)
		(fp_rect
			(start 0.508 0.9398)
			(end -0.508 -0.9398)
			(stroke
				(width 0)
				(type default)
			)
			(fill no)
			(layer "B.CrtYd")
		)
		(fp_rect
			(start 0.508 0.9398)
			(end -0.508 -0.9398)
			(stroke
				(width 0)
				(type default)
			)
			(fill no)
			(layer "B.Fab")
		)
		(pad "1" smd custom
			(at 0 -0.4445 180)
			(size 0.1397 0.1397)
			(layers "B.Cu" "B.Mask" "B.Paste")
			(net "BMC_SPI_MISO")
			(options
				(clearance outline)
				(anchor circle)
			)
			(primitives
				(gr_poly
					(pts
						(arc
							(start -0.1778 0.2794)
							(mid -0.249642 0.249642)
							(end -0.2794 0.1778)
						)
						(arc
							(start -0.2794 -0.1778)
							(mid -0.249642 -0.249642)
							(end -0.1778 -0.2794)
						)
						(arc
							(start 0.1778 -0.2794)
							(mid 0.249642 -0.249642)
							(end 0.2794 -0.1778)
						)
						(arc
							(start 0.2794 0.1778)
							(mid 0.249642 0.249642)
							(end 0.1778 0.2794)
						)
					)
					(width 0)
					(fill yes)
				)
			)
		)
		(pad "2" smd custom
			(at 0 0.4445 180)
			(size 0.1397 0.1397)
			(layers "B.Cu" "B.Mask" "B.Paste")
			(net "BMC_SPI_MISO_R")
			(options
				(clearance outline)
				(anchor circle)
			)
			(primitives
				(gr_poly
					(pts
						(arc
							(start -0.1778 0.2794)
							(mid -0.249642 0.249642)
							(end -0.2794 0.1778)
						)
						(arc
							(start -0.2794 -0.1778)
							(mid -0.249642 -0.249642)
							(end -0.1778 -0.2794)
						)
						(arc
							(start 0.1778 -0.2794)
							(mid 0.249642 -0.249642)
							(end 0.2794 -0.1778)
						)
						(arc
							(start 0.2794 0.1778)
							(mid 0.249642 0.249642)
							(end 0.1778 0.2794)
						)
					)
					(width 0)
					(fill yes)
				)
			)
		)
	)
	(footprint ""
		(layer "B.Cu")
		(at 201.070718 -81.153 180)
		(property "Reference" "C290"
			(at 0 0 0)
			(layer "B.SilkS")
			(hide yes)
			(effects
				(font
					(size 1.27 1.27)
				)
				(justify mirror)
			)
		)
		(property "Value" "SCD22U10V1KX-GP"
			(at 2.8321 -1.7399 180)
			(unlocked yes)
			(layer "B.Fab")
			(hide yes)
			(effects
				(font
					(size 1.016 1.016)
					(thickness 0.1524)
				)
				(justify mirror)
			)
		)
		(property "Device Type" "C0201H13"
			(at 2.8321 -3.2639 180)
			(unlocked yes)
			(layer "B.Fab")
			(hide yes)
			(effects
				(font
					(size 1.016 1.016)
					(thickness 0.1524)
				)
				(justify mirror)
			)
		)
		(duplicate_pad_numbers_are_jumpers no)
		(fp_rect
			(start 0.2794 0.6477)
			(end -0.2794 -0.6477)
			(stroke
				(width 0)
				(type default)
			)
			(fill no)
			(layer "B.CrtYd")
		)
		(fp_rect
			(start 0.2794 0.6477)
			(end -0.2794 -0.6477)
			(stroke
				(width 0)
				(type default)
			)
			(fill no)
			(layer "B.Fab")
		)
		(pad "1" smd custom
			(at 0 -0.2794)
			(size 0.0762 0.0762)
			(layers "B.Cu" "B.Mask" "B.Paste")
			(net "PCIE_IOM_TO_COMP_8_DN_C")
			(options
				(clearance outline)
				(anchor circle)
			)
			(primitives
				(gr_poly
					(pts
						(arc
							(start 0.1524 0.127)
							(mid 0.137521 0.162921)
							(end 0.1016 0.1778)
						)
						(arc
							(start -0.1016 0.1778)
							(mid -0.137521 0.162921)
							(end -0.1524 0.127)
						)
						(arc
							(start -0.1524 -0.127)
							(mid -0.137521 -0.162921)
							(end -0.1016 -0.1778)
						)
						(arc
							(start 0.1016 -0.1778)
							(mid 0.137521 -0.162921)
							(end 0.1524 -0.127)
						)
					)
					(width 0)
					(fill yes)
				)
			)
		)
		(pad "2" smd custom
			(at 0 0.2794)
			(size 0.0762 0.0762)
			(layers "B.Cu" "B.Mask" "B.Paste")
			(net "PCIE_IOM_TO_COMP_8_DN")
			(options
				(clearance outline)
				(anchor circle)
			)
			(primitives
				(gr_poly
					(pts
						(arc
							(start 0.1524 0.127)
							(mid 0.137521 0.162921)
							(end 0.1016 0.1778)
						)
						(arc
							(start -0.1016 0.1778)
							(mid -0.137521 0.162921)
							(end -0.1524 0.127)
						)
						(arc
							(start -0.1524 -0.127)
							(mid -0.137521 -0.162921)
							(end -0.1016 -0.1778)
						)
						(arc
							(start 0.1016 -0.1778)
							(mid 0.137521 -0.162921)
							(end 0.1524 -0.127)
						)
					)
					(width 0)
					(fill yes)
				)
			)
		)
	)
	(footprint ""
		(layer "B.Cu")
		(at 97.62871 -153.851102 45)
		(property "Reference" "TP6"
			(at 0 0 45)
			(layer "B.SilkS")
			(hide yes)
			(effects
				(font
					(size 1.27 1.27)
				)
				(justify mirror)
			)
		)
		(property "Value" "TPAD28-2-GP"
			(at 0.012752 -1.663607 45)
			(unlocked yes)
			(layer "B.Fab")
			(hide yes)
			(effects
				(font
					(size 1.016 1.016)
					(thickness 0.1524)
				)
				(justify mirror)
			)
		)
		(property "Device Type" "TPAD28"
			(at 0.012752 -3.187736 45)
			(unlocked yes)
			(layer "B.Fab")
			(hide yes)
			(effects
				(font
					(size 1.016 1.016)
					(thickness 0.1524)
				)
				(justify mirror)
			)
		)
		(duplicate_pad_numbers_are_jumpers no)
		(fp_poly
			(pts
				(arc
					(start 0.251447 0.251447)
					(mid -0.251447 -0.251447)
					(end 0.251447 0.251447)
				)
			)
			(stroke
				(width 0)
				(type default)
			)
			(fill no)
			(layer "B.CrtYd")
		)
		(fp_poly
			(pts
				(arc
					(start 0.431052 0.431052)
					(mid -0.431052 -0.431052)
					(end 0.431052 0.431052)
				)
			)
			(stroke
				(width 0)
				(type default)
			)
			(fill no)
			(layer "B.Fab")
		)
		(pad "1" smd circle
			(at 0 0 225)
			(size 0.7112 0.7112)
			(layers "B.Cu" "B.Mask" "B.Paste")
			(net "TP_USB_SDA")
		)
	)
	(footprint ""
		(layer "B.Cu")
		(at 194.279266 -72.380856 -90)
		(property "Reference" "C358"
			(at 0 0 90)
			(layer "B.SilkS")
			(hide yes)
			(effects
				(font
					(size 1.27 1.27)
				)
				(justify mirror)
			)
		)
		(property "Value" "SC1U6D3V1MX-GP"
			(at -1.9177 2.0193 270)
			(unlocked yes)
			(layer "B.Fab")
			(hide yes)
			(effects
				(font
					(size 1.016 1.016)
					(thickness 0.1524)
				)
				(justify mirror)
			)
		)
		(property "Device Type" "C0201H14"
			(at -1.9177 0.4953 270)
			(unlocked yes)
			(layer "B.Fab")
			(hide yes)
			(effects
				(font
					(size 1.016 1.016)
					(thickness 0.1524)
				)
				(justify mirror)
			)
		)
		(duplicate_pad_numbers_are_jumpers no)
		(fp_rect
			(start 0.1524 0.3048)
			(end -0.1524 -0.3048)
			(stroke
				(width 0)
				(type default)
			)
			(fill no)
			(layer "B.CrtYd")
		)
		(fp_poly
			(pts
				(xy 0.2794 0.6477) (xy 0.2794 -0.6477) (xy -0.2794 -0.6477) (xy -0.2794 -0.1905) (xy -0.1524 -0.1905)
				(xy -0.1524 -0.3048) (xy 0.1524 -0.3048) (xy 0.1524 0.3048) (xy -0.1524 0.3048) (xy -0.1524 -0.1778)
				(xy -0.2794 -0.1778) (xy -0.2794 0.6477)
			)
			(stroke
				(width 0)
				(type default)
			)
			(fill no)
			(layer "B.CrtYd")
		)
		(fp_rect
			(start 0.2794 0.6477)
			(end -0.2794 -0.6477)
			(stroke
				(width 0)
				(type default)
			)
			(fill no)
			(layer "B.Fab")
		)
		(pad "1" smd custom
			(at 0 -0.2794 90)
			(size 0.0762 0.0762)
			(layers "B.Cu" "B.Mask" "B.Paste")
			(net "PCE_VDDH")
			(options
				(clearance outline)
				(anchor circle)
			)
			(primitives
				(gr_poly
					(pts
						(arc
							(start 0.1524 0.127)
							(mid 0.137521 0.162921)
							(end 0.1016 0.1778)
						)
						(arc
							(start -0.1016 0.1778)
							(mid -0.137521 0.162921)
							(end -0.1524 0.127)
						)
						(arc
							(start -0.1524 -0.127)
							(mid -0.137521 -0.162921)
							(end -0.1016 -0.1778)
						)
						(arc
							(start 0.1016 -0.1778)
							(mid 0.137521 -0.162921)
							(end 0.1524 -0.127)
						)
					)
					(width 0)
					(fill yes)
				)
			)
		)
		(pad "2" smd custom
			(at 0 0.2794 90)
			(size 0.0762 0.0762)
			(layers "B.Cu" "B.Mask" "B.Paste")
			(net "GND")
			(options
				(clearance outline)
				(anchor circle)
			)
			(primitives
				(gr_poly
					(pts
						(arc
							(start 0.1524 0.127)
							(mid 0.137521 0.162921)
							(end 0.1016 0.1778)
						)
						(arc
							(start -0.1016 0.1778)
							(mid -0.137521 0.162921)
							(end -0.1524 0.127)
						)
						(arc
							(start -0.1524 -0.127)
							(mid -0.137521 -0.162921)
							(end -0.1016 -0.1778)
						)
						(arc
							(start 0.1016 -0.1778)
							(mid 0.137521 -0.162921)
							(end 0.1524 -0.127)
						)
					)
					(width 0)
					(fill yes)
				)
			)
		)
	)
	(footprint ""
		(layer "B.Cu")
		(at 48.387 -138.9634)
		(property "Reference" "TP20"
			(at 0 0 0)
			(layer "B.SilkS")
			(hide yes)
			(effects
				(font
					(size 1.27 1.27)
				)
				(justify mirror)
			)
		)
		(property "Value" "TPAD28-2-GP"
			(at 0.0127 -1.6637 0)
			(unlocked yes)
			(layer "B.Fab")
			(hide yes)
			(effects
				(font
					(size 1.016 1.016)
					(thickness 0.1524)
				)
				(justify mirror)
			)
		)
		(property "Device Type" "TPAD28"
			(at 0.0127 -3.1877 0)
			(unlocked yes)
			(layer "B.Fab")
			(hide yes)
			(effects
				(font
					(size 1.016 1.016)
					(thickness 0.1524)
				)
				(justify mirror)
			)
		)
		(duplicate_pad_numbers_are_jumpers no)
		(fp_poly
			(pts
				(arc
					(start 0.3556 0)
					(mid -0.3556 0)
					(end 0.3556 0)
				)
			)
			(stroke
				(width 0)
				(type default)
			)
			(fill no)
			(layer "B.CrtYd")
		)
		(fp_poly
			(pts
				(arc
					(start 0.6096 0)
					(mid -0.6096 0)
					(end 0.6096 0)
				)
			)
			(stroke
				(width 0)
				(type default)
			)
			(fill no)
			(layer "B.Fab")
		)
		(pad "1" smd circle
			(at 0 0 180)
			(size 0.7112 0.7112)
			(layers "B.Cu" "B.Mask" "B.Paste")
			(net "TP_M2_1_ALERT#")
		)
	)
	(footprint ""
		(layer "B.Cu")
		(at 55.9562 -132.5626)
		(property "Reference" "C116"
			(at 0 0 0)
			(layer "B.SilkS")
			(hide yes)
			(effects
				(font
					(size 1.27 1.27)
				)
				(justify mirror)
			)
		)
		(property "Value" "SC4D7U25V5KX-1-GP"
			(at 0.0762 -6.1214 0)
			(unlocked yes)
			(layer "B.Fab")
			(hide yes)
			(effects
				(font
					(size 1.016 1.016)
					(thickness 0.1524)
				)
				(justify mirror)
			)
		)
		(property "Device Type" "C805H58"
			(at 0.0762 -8.1534 0)
			(unlocked yes)
			(layer "B.Fab")
			(hide yes)
			(effects
				(font
					(size 1.016 1.016)
					(thickness 0.1524)
				)
				(justify mirror)
			)
		)
		(duplicate_pad_numbers_are_jumpers no)
		(fp_line
			(start -0.635 0)
			(end 0.635 0)
			(stroke
				(width 0.508)
				(type default)
			)
			(layer "B.SilkS")
		)
		(fp_rect
			(start 0.9652 1.778)
			(end -0.9652 -1.778)
			(stroke
				(width 0)
				(type default)
			)
			(fill no)
			(layer "B.CrtYd")
		)
		(fp_poly
			(pts
				(xy 0.9652 -1.778) (xy -0.9652 -1.778) (xy -0.9652 1.778) (xy 0.9652 1.778)
			)
			(stroke
				(width 0)
				(type default)
			)
			(fill no)
			(layer "B.Fab")
		)
		(pad "1" smd rect
			(at 0 -0.9652 180)
			(size 1.397 1.143)
			(layers "B.Cu" "B.Mask" "B.Paste")
			(net "P1V15_STBY")
		)
		(pad "2" smd rect
			(at 0 0.9652 180)
			(size 1.397 1.143)
			(layers "B.Cu" "B.Mask" "B.Paste")
			(net "GND")
		)
	)
	(footprint ""
		(layer "B.Cu")
		(at 10.193528 -132.402834 90)
		(property "Reference" "R237"
			(at 0 0 90)
			(layer "B.SilkS")
			(hide yes)
			(effects
				(font
					(size 1.27 1.27)
				)
				(justify mirror)
			)
		)
		(property "Value" "120R2F-GP"
			(at -0.064008 -3.993896 90)
			(unlocked yes)
			(layer "B.Fab")
			(hide yes)
			(effects
				(font
					(size 1.016 1.016)
					(thickness 0.1524)
				)
				(justify mirror)
			)
		)
		(property "Device Type" "R402H16"
			(at -0.064008 -5.517896 90)
			(unlocked yes)
			(layer "B.Fab")
			(hide yes)
			(effects
				(font
					(size 1.016 1.016)
					(thickness 0.1524)
				)
				(justify mirror)
			)
		)
		(duplicate_pad_numbers_are_jumpers no)
		(fp_line
			(start 0.508 -0.9398)
			(end 0.508 0.9398)
			(stroke
				(width 0.1524)
				(type default)
			)
			(layer "B.SilkS")
		)
		(fp_line
			(start -0.508 -0.9398)
			(end 0.508 -0.9398)
			(stroke
				(width 0.1524)
				(type default)
			)
			(layer "B.SilkS")
		)
		(fp_rect
			(start 0.508 0.9398)
			(end -0.508 -0.9398)
			(stroke
				(width 0)
				(type default)
			)
			(fill no)
			(layer "B.CrtYd")
		)
		(fp_rect
			(start 0.508 0.9398)
			(end -0.508 -0.9398)
			(stroke
				(width 0)
				(type default)
			)
			(fill no)
			(layer "B.Fab")
		)
		(pad "1" smd custom
			(at 0 -0.4445 270)
			(size 0.1397 0.1397)
			(layers "B.Cu" "B.Mask" "B.Paste")
			(net "GND")
			(options
				(clearance outline)
				(anchor circle)
			)
			(primitives
				(gr_poly
					(pts
						(arc
							(start -0.1778 0.2794)
							(mid -0.249642 0.249642)
							(end -0.2794 0.1778)
						)
						(arc
							(start -0.2794 -0.1778)
							(mid -0.249642 -0.249642)
							(end -0.1778 -0.2794)
						)
						(arc
							(start 0.1778 -0.2794)
							(mid 0.249642 -0.249642)
							(end 0.2794 -0.1778)
						)
						(arc
							(start 0.2794 0.1778)
							(mid 0.249642 0.249642)
							(end 0.1778 0.2794)
						)
					)
					(width 0)
					(fill yes)
				)
			)
		)
		(pad "2" smd custom
			(at 0 0.4445 270)
			(size 0.1397 0.1397)
			(layers "B.Cu" "B.Mask" "B.Paste")
			(net "MEMA_2")
			(options
				(clearance outline)
				(anchor circle)
			)
			(primitives
				(gr_poly
					(pts
						(arc
							(start -0.1778 0.2794)
							(mid -0.249642 0.249642)
							(end -0.2794 0.1778)
						)
						(arc
							(start -0.2794 -0.1778)
							(mid -0.249642 -0.249642)
							(end -0.1778 -0.2794)
						)
						(arc
							(start 0.1778 -0.2794)
							(mid 0.249642 -0.249642)
							(end 0.2794 -0.1778)
						)
						(arc
							(start 0.2794 0.1778)
							(mid 0.249642 0.249642)
							(end 0.1778 0.2794)
						)
					)
					(width 0)
					(fill yes)
				)
			)
		)
	)
	(footprint ""
		(layer "B.Cu")
		(at 52.0446 -165.8874 90)
		(property "Reference" "R414"
			(at 0 0 90)
			(layer "B.SilkS")
			(hide yes)
			(effects
				(font
					(size 1.27 1.27)
				)
				(justify mirror)
			)
		)
		(property "Value" "1KR2F-3-GP"
			(at -0.064008 -3.993896 90)
			(unlocked yes)
			(layer "B.Fab")
			(hide yes)
			(effects
				(font
					(size 1.016 1.016)
					(thickness 0.1524)
				)
				(justify mirror)
			)
		)
		(property "Device Type" "R402H16"
			(at -0.064008 -5.517896 90)
			(unlocked yes)
			(layer "B.Fab")
			(hide yes)
			(effects
				(font
					(size 1.016 1.016)
					(thickness 0.1524)
				)
				(justify mirror)
			)
		)
		(duplicate_pad_numbers_are_jumpers no)
		(fp_line
			(start 0.508 -0.9398)
			(end 0.508 0.9398)
			(stroke
				(width 0.1524)
				(type default)
			)
			(layer "B.SilkS")
		)
		(fp_line
			(start -0.508 -0.9398)
			(end 0.508 -0.9398)
			(stroke
				(width 0.1524)
				(type default)
			)
			(layer "B.SilkS")
		)
		(fp_rect
			(start 0.508 0.9398)
			(end -0.508 -0.9398)
			(stroke
				(width 0)
				(type default)
			)
			(fill no)
			(layer "B.CrtYd")
		)
		(fp_rect
			(start 0.508 0.9398)
			(end -0.508 -0.9398)
			(stroke
				(width 0)
				(type default)
			)
			(fill no)
			(layer "B.Fab")
		)
		(pad "1" smd custom
			(at 0 -0.4445 270)
			(size 0.1397 0.1397)
			(layers "B.Cu" "B.Mask" "B.Paste")
			(net "P0V975")
			(options
				(clearance outline)
				(anchor circle)
			)
			(primitives
				(gr_poly
					(pts
						(arc
							(start -0.1778 0.2794)
							(mid -0.249642 0.249642)
							(end -0.2794 0.1778)
						)
						(arc
							(start -0.2794 -0.1778)
							(mid -0.249642 -0.249642)
							(end -0.1778 -0.2794)
						)
						(arc
							(start 0.1778 -0.2794)
							(mid 0.249642 -0.249642)
							(end 0.2794 -0.1778)
						)
						(arc
							(start 0.2794 0.1778)
							(mid 0.249642 0.249642)
							(end 0.1778 0.2794)
						)
					)
					(width 0)
					(fill yes)
				)
			)
		)
		(pad "2" smd custom
			(at 0 0.4445 270)
			(size 0.1397 0.1397)
			(layers "B.Cu" "B.Mask" "B.Paste")
			(net "ADC_P0V975")
			(options
				(clearance outline)
				(anchor circle)
			)
			(primitives
				(gr_poly
					(pts
						(arc
							(start -0.1778 0.2794)
							(mid -0.249642 0.249642)
							(end -0.2794 0.1778)
						)
						(arc
							(start -0.2794 -0.1778)
							(mid -0.249642 -0.249642)
							(end -0.1778 -0.2794)
						)
						(arc
							(start 0.1778 -0.2794)
							(mid 0.249642 -0.249642)
							(end 0.2794 -0.1778)
						)
						(arc
							(start 0.2794 0.1778)
							(mid 0.249642 0.249642)
							(end 0.1778 0.2794)
						)
					)
					(width 0)
					(fill yes)
				)
			)
		)
	)
	(footprint ""
		(layer "B.Cu")
		(at 191.689736 -25.908 -90)
		(property "Reference" "C490"
			(at 0 0 90)
			(layer "B.SilkS")
			(hide yes)
			(effects
				(font
					(size 1.27 1.27)
				)
				(justify mirror)
			)
		)
		(property "Value" "SCD01U16V1KX-GP"
			(at 2.8321 -1.7399 270)
			(unlocked yes)
			(layer "B.Fab")
			(hide yes)
			(effects
				(font
					(size 1.016 1.016)
					(thickness 0.1524)
				)
				(justify mirror)
			)
		)
		(property "Device Type" "C0201H13"
			(at 2.8321 -3.2639 270)
			(unlocked yes)
			(layer "B.Fab")
			(hide yes)
			(effects
				(font
					(size 1.016 1.016)
					(thickness 0.1524)
				)
				(justify mirror)
			)
		)
		(duplicate_pad_numbers_are_jumpers no)
		(fp_rect
			(start 0.2794 0.6477)
			(end -0.2794 -0.6477)
			(stroke
				(width 0)
				(type default)
			)
			(fill no)
			(layer "B.CrtYd")
		)
		(fp_rect
			(start 0.2794 0.6477)
			(end -0.2794 -0.6477)
			(stroke
				(width 0)
				(type default)
			)
			(fill no)
			(layer "B.Fab")
		)
		(pad "1" smd custom
			(at 0 -0.2794 90)
			(size 0.0762 0.0762)
			(layers "B.Cu" "B.Mask" "B.Paste")
			(net "PHY_CON_A_TO_IOC_3_DP")
			(options
				(clearance outline)
				(anchor circle)
			)
			(primitives
				(gr_poly
					(pts
						(arc
							(start 0.1524 0.127)
							(mid 0.137521 0.162921)
							(end 0.1016 0.1778)
						)
						(arc
							(start -0.1016 0.1778)
							(mid -0.137521 0.162921)
							(end -0.1524 0.127)
						)
						(arc
							(start -0.1524 -0.127)
							(mid -0.137521 -0.162921)
							(end -0.1016 -0.1778)
						)
						(arc
							(start 0.1016 -0.1778)
							(mid 0.137521 -0.162921)
							(end 0.1524 -0.127)
						)
					)
					(width 0)
					(fill yes)
				)
			)
		)
		(pad "2" smd custom
			(at 0 0.2794 90)
			(size 0.0762 0.0762)
			(layers "B.Cu" "B.Mask" "B.Paste")
			(net "PHY_CON_A_TO_IOC_3_DP_C")
			(options
				(clearance outline)
				(anchor circle)
			)
			(primitives
				(gr_poly
					(pts
						(arc
							(start 0.1524 0.127)
							(mid 0.137521 0.162921)
							(end 0.1016 0.1778)
						)
						(arc
							(start -0.1016 0.1778)
							(mid -0.137521 0.162921)
							(end -0.1524 0.127)
						)
						(arc
							(start -0.1524 -0.127)
							(mid -0.137521 -0.162921)
							(end -0.1016 -0.1778)
						)
						(arc
							(start 0.1016 -0.1778)
							(mid 0.137521 -0.162921)
							(end 0.1524 -0.127)
						)
					)
					(width 0)
					(fill yes)
				)
			)
		)
	)
	(footprint ""
		(layer "B.Cu")
		(at 187.7314 -76.740004)
		(property "Reference" "TP89"
			(at 0 0 0)
			(layer "B.SilkS")
			(hide yes)
			(effects
				(font
					(size 1.27 1.27)
				)
				(justify mirror)
			)
		)
		(property "Value" "TPAD28-2-GP"
			(at 0.0127 -1.6637 0)
			(unlocked yes)
			(layer "B.Fab")
			(hide yes)
			(effects
				(font
					(size 1.016 1.016)
					(thickness 0.1524)
				)
				(justify mirror)
			)
		)
		(property "Device Type" "TPAD28"
			(at 0.0127 -3.1877 0)
			(unlocked yes)
			(layer "B.Fab")
			(hide yes)
			(effects
				(font
					(size 1.016 1.016)
					(thickness 0.1524)
				)
				(justify mirror)
			)
		)
		(duplicate_pad_numbers_are_jumpers no)
		(fp_poly
			(pts
				(arc
					(start 0.3556 0)
					(mid -0.3556 0)
					(end 0.3556 0)
				)
			)
			(stroke
				(width 0)
				(type default)
			)
			(fill no)
			(layer "B.CrtYd")
		)
		(fp_poly
			(pts
				(arc
					(start 0.6096 0)
					(mid -0.6096 0)
					(end 0.6096 0)
				)
			)
			(stroke
				(width 0)
				(type default)
			)
			(fill no)
			(layer "B.Fab")
		)
		(pad "1" smd circle
			(at 0 0 180)
			(size 0.7112 0.7112)
			(layers "B.Cu" "B.Mask" "B.Paste")
			(net "IOC_GPIO_3")
		)
	)
	(footprint ""
		(layer "B.Cu")
		(at 57.3278 -145.2626 -90)
		(property "Reference" "R361"
			(at 0 0 90)
			(layer "B.SilkS")
			(hide yes)
			(effects
				(font
					(size 1.27 1.27)
				)
				(justify mirror)
			)
		)
		(property "Value" "10KR2F-2-GP"
			(at -0.064008 -3.993896 270)
			(unlocked yes)
			(layer "B.Fab")
			(hide yes)
			(effects
				(font
					(size 1.016 1.016)
					(thickness 0.1524)
				)
				(justify mirror)
			)
		)
		(property "Device Type" "R402H16"
			(at -0.064008 -5.517896 270)
			(unlocked yes)
			(layer "B.Fab")
			(hide yes)
			(effects
				(font
					(size 1.016 1.016)
					(thickness 0.1524)
				)
				(justify mirror)
			)
		)
		(duplicate_pad_numbers_are_jumpers no)
		(fp_line
			(start -0.508 -0.9398)
			(end 0.508 -0.9398)
			(stroke
				(width 0.1524)
				(type default)
			)
			(layer "B.SilkS")
		)
		(fp_line
			(start 0.508 -0.9398)
			(end 0.508 0.9398)
			(stroke
				(width 0.1524)
				(type default)
			)
			(layer "B.SilkS")
		)
		(fp_rect
			(start 0.508 0.9398)
			(end -0.508 -0.9398)
			(stroke
				(width 0)
				(type default)
			)
			(fill no)
			(layer "B.CrtYd")
		)
		(fp_rect
			(start 0.508 0.9398)
			(end -0.508 -0.9398)
			(stroke
				(width 0)
				(type default)
			)
			(fill no)
			(layer "B.Fab")
		)
		(pad "1" smd custom
			(at 0 -0.4445 90)
			(size 0.1397 0.1397)
			(layers "B.Cu" "B.Mask" "B.Paste")
			(net "P3V3_STBY")
			(options
				(clearance outline)
				(anchor circle)
			)
			(primitives
				(gr_poly
					(pts
						(arc
							(start -0.1778 0.2794)
							(mid -0.249642 0.249642)
							(end -0.2794 0.1778)
						)
						(arc
							(start -0.2794 -0.1778)
							(mid -0.249642 -0.249642)
							(end -0.1778 -0.2794)
						)
						(arc
							(start 0.1778 -0.2794)
							(mid 0.249642 -0.249642)
							(end 0.2794 -0.1778)
						)
						(arc
							(start 0.2794 0.1778)
							(mid 0.249642 0.249642)
							(end 0.1778 0.2794)
						)
					)
					(width 0)
					(fill yes)
				)
			)
		)
		(pad "2" smd custom
			(at 0 0.4445 90)
			(size 0.1397 0.1397)
			(layers "B.Cu" "B.Mask" "B.Paste")
			(net "JTAG_BMC_TDO")
			(options
				(clearance outline)
				(anchor circle)
			)
			(primitives
				(gr_poly
					(pts
						(arc
							(start -0.1778 0.2794)
							(mid -0.249642 0.249642)
							(end -0.2794 0.1778)
						)
						(arc
							(start -0.2794 -0.1778)
							(mid -0.249642 -0.249642)
							(end -0.1778 -0.2794)
						)
						(arc
							(start 0.1778 -0.2794)
							(mid 0.249642 -0.249642)
							(end 0.2794 -0.1778)
						)
						(arc
							(start 0.2794 0.1778)
							(mid 0.249642 0.249642)
							(end 0.1778 0.2794)
						)
					)
					(width 0)
					(fill yes)
				)
			)
		)
	)
	(footprint ""
		(layer "B.Cu")
		(at 48.999394 -161.276792)
		(property "Reference" "R310"
			(at 0 0 0)
			(layer "B.SilkS")
			(hide yes)
			(effects
				(font
					(size 1.27 1.27)
				)
				(justify mirror)
			)
		)
		(property "Value" "4K7R2F-GP"
			(at -0.064008 -3.993896 0)
			(unlocked yes)
			(layer "B.Fab")
			(hide yes)
			(effects
				(font
					(size 1.016 1.016)
					(thickness 0.1524)
				)
				(justify mirror)
			)
		)
		(property "Device Type" "R402H16"
			(at -0.064008 -5.517896 0)
			(unlocked yes)
			(layer "B.Fab")
			(hide yes)
			(effects
				(font
					(size 1.016 1.016)
					(thickness 0.1524)
				)
				(justify mirror)
			)
		)
		(duplicate_pad_numbers_are_jumpers no)
		(fp_line
			(start -0.508 -0.9398)
			(end 0.508 -0.9398)
			(stroke
				(width 0.1524)
				(type default)
			)
			(layer "B.SilkS")
		)
		(fp_line
			(start 0.508 -0.9398)
			(end 0.508 0.9398)
			(stroke
				(width 0.1524)
				(type default)
			)
			(layer "B.SilkS")
		)
		(fp_rect
			(start 0.508 0.9398)
			(end -0.508 -0.9398)
			(stroke
				(width 0)
				(type default)
			)
			(fill no)
			(layer "B.CrtYd")
		)
		(fp_rect
			(start 0.508 0.9398)
			(end -0.508 -0.9398)
			(stroke
				(width 0)
				(type default)
			)
			(fill no)
			(layer "B.Fab")
		)
		(pad "1" smd custom
			(at 0 -0.4445 180)
			(size 0.1397 0.1397)
			(layers "B.Cu" "B.Mask" "B.Paste")
			(net "P3V3_STBY")
			(options
				(clearance outline)
				(anchor circle)
			)
			(primitives
				(gr_poly
					(pts
						(arc
							(start -0.1778 0.2794)
							(mid -0.249642 0.249642)
							(end -0.2794 0.1778)
						)
						(arc
							(start -0.2794 -0.1778)
							(mid -0.249642 -0.249642)
							(end -0.1778 -0.2794)
						)
						(arc
							(start 0.1778 -0.2794)
							(mid 0.249642 -0.249642)
							(end 0.2794 -0.1778)
						)
						(arc
							(start 0.2794 0.1778)
							(mid 0.249642 0.249642)
							(end 0.1778 0.2794)
						)
					)
					(width 0)
					(fill yes)
				)
			)
		)
		(pad "2" smd custom
			(at 0 0.4445 180)
			(size 0.1397 0.1397)
			(layers "B.Cu" "B.Mask" "B.Paste")
			(net "BOARD_REV_1")
			(options
				(clearance outline)
				(anchor circle)
			)
			(primitives
				(gr_poly
					(pts
						(arc
							(start -0.1778 0.2794)
							(mid -0.249642 0.249642)
							(end -0.2794 0.1778)
						)
						(arc
							(start -0.2794 -0.1778)
							(mid -0.249642 -0.249642)
							(end -0.1778 -0.2794)
						)
						(arc
							(start 0.1778 -0.2794)
							(mid 0.249642 -0.249642)
							(end 0.2794 -0.1778)
						)
						(arc
							(start 0.2794 0.1778)
							(mid 0.249642 0.249642)
							(end 0.1778 0.2794)
						)
					)
					(width 0)
					(fill yes)
				)
			)
		)
	)
	(footprint ""
		(layer "B.Cu")
		(at 177.78095 -80.948276)
		(property "Reference" "C362"
			(at 0 0 0)
			(layer "B.SilkS")
			(hide yes)
			(effects
				(font
					(size 1.27 1.27)
				)
				(justify mirror)
			)
		)
		(property "Value" "SC100U6D3V6MX-GP"
			(at 0.0762 -5.1308 0)
			(unlocked yes)
			(layer "B.Fab")
			(hide yes)
			(effects
				(font
					(size 1.016 1.016)
					(thickness 0.1524)
				)
				(justify mirror)
			)
		)
		(property "Device Type" "C1206H71"
			(at 0.127 -6.6548 0)
			(unlocked yes)
			(layer "B.Fab")
			(hide yes)
			(effects
				(font
					(size 1.016 1.016)
					(thickness 0.1524)
				)
				(justify mirror)
			)
		)
		(duplicate_pad_numbers_are_jumpers no)
		(fp_line
			(start -1.016 -2.2352)
			(end -1.016 -0.8382)
			(stroke
				(width 0.1524)
				(type default)
			)
			(layer "B.SilkS")
		)
		(fp_line
			(start -1.016 0.8382)
			(end -1.016 2.2352)
			(stroke
				(width 0.1524)
				(type default)
			)
			(layer "B.SilkS")
		)
		(fp_line
			(start -1.016 2.2352)
			(end 1.016 2.2352)
			(stroke
				(width 0.1524)
				(type default)
			)
			(layer "B.SilkS")
		)
		(fp_line
			(start 1.016 -2.2352)
			(end -1.016 -2.2352)
			(stroke
				(width 0.1524)
				(type default)
			)
			(layer "B.SilkS")
		)
		(fp_line
			(start 1.016 -0.8382)
			(end 1.016 -2.2352)
			(stroke
				(width 0.1524)
				(type default)
			)
			(layer "B.SilkS")
		)
		(fp_line
			(start 1.016 2.2352)
			(end 1.016 0.8382)
			(stroke
				(width 0.1524)
				(type default)
			)
			(layer "B.SilkS")
		)
		(fp_rect
			(start 1.0922 2.3114)
			(end -1.0922 -2.3114)
			(stroke
				(width 0)
				(type default)
			)
			(fill no)
			(layer "B.CrtYd")
		)
		(fp_poly
			(pts
				(xy -1.0922 -2.3114) (xy -1.0922 2.3114) (xy 1.0922 2.3114) (xy 1.0922 -2.3114)
			)
			(stroke
				(width 0)
				(type default)
			)
			(fill no)
			(layer "B.Fab")
		)
		(pad "1" smd rect
			(at 0 -1.397 180)
			(size 1.651 1.27)
			(layers "B.Cu" "B.Mask" "B.Paste")
			(net "GND")
		)
		(pad "2" smd rect
			(at 0 1.397 180)
			(size 1.651 1.27)
			(layers "B.Cu" "B.Mask" "B.Paste")
			(net "PCE_AVDD")
		)
	)
	(footprint ""
		(layer "B.Cu")
		(at 95.377 -7.874 90)
		(property "Reference" "R37"
			(at 0 0 90)
			(layer "B.SilkS")
			(hide yes)
			(effects
				(font
					(size 1.27 1.27)
				)
				(justify mirror)
			)
		)
		(property "Value" "1MR2F-GP"
			(at -0.064008 -3.993896 90)
			(unlocked yes)
			(layer "B.Fab")
			(hide yes)
			(effects
				(font
					(size 1.016 1.016)
					(thickness 0.1524)
				)
				(justify mirror)
			)
		)
		(property "Device Type" "R402H16"
			(at -0.064008 -5.517896 90)
			(unlocked yes)
			(layer "B.Fab")
			(hide yes)
			(effects
				(font
					(size 1.016 1.016)
					(thickness 0.1524)
				)
				(justify mirror)
			)
		)
		(duplicate_pad_numbers_are_jumpers no)
		(fp_line
			(start 0.508 -0.9398)
			(end 0.508 0.9398)
			(stroke
				(width 0.1524)
				(type default)
			)
			(layer "B.SilkS")
		)
		(fp_line
			(start -0.508 -0.9398)
			(end 0.508 -0.9398)
			(stroke
				(width 0.1524)
				(type default)
			)
			(layer "B.SilkS")
		)
		(fp_rect
			(start 0.508 0.9398)
			(end -0.508 -0.9398)
			(stroke
				(width 0)
				(type default)
			)
			(fill no)
			(layer "B.CrtYd")
		)
		(fp_rect
			(start 0.508 0.9398)
			(end -0.508 -0.9398)
			(stroke
				(width 0)
				(type default)
			)
			(fill no)
			(layer "B.Fab")
		)
		(pad "1" smd custom
			(at 0 -0.4445 270)
			(size 0.1397 0.1397)
			(layers "B.Cu" "B.Mask" "B.Paste")
			(net "USB_CONN_GND")
			(options
				(clearance outline)
				(anchor circle)
			)
			(primitives
				(gr_poly
					(pts
						(arc
							(start -0.1778 0.2794)
							(mid -0.249642 0.249642)
							(end -0.2794 0.1778)
						)
						(arc
							(start -0.2794 -0.1778)
							(mid -0.249642 -0.249642)
							(end -0.1778 -0.2794)
						)
						(arc
							(start 0.1778 -0.2794)
							(mid 0.249642 -0.249642)
							(end 0.2794 -0.1778)
						)
						(arc
							(start 0.2794 0.1778)
							(mid 0.249642 0.249642)
							(end 0.1778 0.2794)
						)
					)
					(width 0)
					(fill yes)
				)
			)
		)
		(pad "2" smd custom
			(at 0 0.4445 270)
			(size 0.1397 0.1397)
			(layers "B.Cu" "B.Mask" "B.Paste")
			(net "GND")
			(options
				(clearance outline)
				(anchor circle)
			)
			(primitives
				(gr_poly
					(pts
						(arc
							(start -0.1778 0.2794)
							(mid -0.249642 0.249642)
							(end -0.2794 0.1778)
						)
						(arc
							(start -0.2794 -0.1778)
							(mid -0.249642 -0.249642)
							(end -0.1778 -0.2794)
						)
						(arc
							(start 0.1778 -0.2794)
							(mid 0.249642 -0.249642)
							(end 0.2794 -0.1778)
						)
						(arc
							(start 0.2794 0.1778)
							(mid 0.249642 0.249642)
							(end 0.1778 0.2794)
						)
					)
					(width 0)
					(fill yes)
				)
			)
		)
	)
	(footprint ""
		(layer "B.Cu")
		(at 32.7914 -150.9522 180)
		(property "Reference" "C92"
			(at 0 0 0)
			(layer "B.SilkS")
			(hide yes)
			(effects
				(font
					(size 1.27 1.27)
				)
				(justify mirror)
			)
		)
		(property "Value" "SC1U16V3KX-5GP"
			(at 0 -2.8194 180)
			(unlocked yes)
			(layer "B.Fab")
			(hide yes)
			(effects
				(font
					(size 1.016 1.016)
					(thickness 0.1524)
				)
				(justify mirror)
			)
		)
		(property "Device Type" "C603H36"
			(at 0 -4.3434 180)
			(unlocked yes)
			(layer "B.Fab")
			(hide yes)
			(effects
				(font
					(size 1.016 1.016)
					(thickness 0.1524)
				)
				(justify mirror)
			)
		)
		(duplicate_pad_numbers_are_jumpers no)
		(fp_line
			(start -0.508 0)
			(end 0.508 0)
			(stroke
				(width 0.2032)
				(type default)
			)
			(layer "B.SilkS")
		)
		(fp_rect
			(start 0.5842 1.3335)
			(end -0.5842 -1.3335)
			(stroke
				(width 0)
				(type default)
			)
			(fill no)
			(layer "B.CrtYd")
		)
		(fp_rect
			(start 0.5842 1.3335)
			(end -0.5842 -1.3335)
			(stroke
				(width 0)
				(type default)
			)
			(fill no)
			(layer "B.Fab")
		)
		(pad "1" smd custom
			(at 0 -0.762)
			(size 0.2159 0.2159)
			(layers "B.Cu" "B.Mask" "B.Paste")
			(net "MPLLAV33")
			(options
				(clearance outline)
				(anchor circle)
			)
			(primitives
				(gr_poly
					(pts
						(arc
							(start -0.3302 0.4318)
							(mid -0.402042 0.402042)
							(end -0.4318 0.3302)
						)
						(arc
							(start -0.4318 -0.3302)
							(mid -0.402042 -0.402042)
							(end -0.3302 -0.4318)
						)
						(arc
							(start 0.3302 -0.4318)
							(mid 0.402042 -0.402042)
							(end 0.4318 -0.3302)
						)
						(arc
							(start 0.4318 0.3302)
							(mid 0.402042 0.402042)
							(end 0.3302 0.4318)
						)
					)
					(width 0)
					(fill yes)
				)
			)
		)
		(pad "2" smd custom
			(at 0 0.762)
			(size 0.2159 0.2159)
			(layers "B.Cu" "B.Mask" "B.Paste")
			(net "GND")
			(options
				(clearance outline)
				(anchor circle)
			)
			(primitives
				(gr_poly
					(pts
						(arc
							(start -0.3302 0.4318)
							(mid -0.402042 0.402042)
							(end -0.4318 0.3302)
						)
						(arc
							(start -0.4318 -0.3302)
							(mid -0.402042 -0.402042)
							(end -0.3302 -0.4318)
						)
						(arc
							(start 0.3302 -0.4318)
							(mid 0.402042 -0.402042)
							(end 0.4318 -0.3302)
						)
						(arc
							(start 0.4318 0.3302)
							(mid 0.402042 0.402042)
							(end 0.3302 0.4318)
						)
					)
					(width 0)
					(fill yes)
				)
			)
		)
	)
	(footprint ""
		(layer "B.Cu")
		(at 124.835666 -7.733792 -90)
		(property "Reference" "R433"
			(at 0 0 90)
			(layer "B.SilkS")
			(hide yes)
			(effects
				(font
					(size 1.27 1.27)
				)
				(justify mirror)
			)
		)
		(property "Value" "10KR2F-2-GP"
			(at -0.064008 -3.993896 270)
			(unlocked yes)
			(layer "B.Fab")
			(hide yes)
			(effects
				(font
					(size 1.016 1.016)
					(thickness 0.1524)
				)
				(justify mirror)
			)
		)
		(property "Device Type" "R402H16"
			(at -0.064008 -5.517896 270)
			(unlocked yes)
			(layer "B.Fab")
			(hide yes)
			(effects
				(font
					(size 1.016 1.016)
					(thickness 0.1524)
				)
				(justify mirror)
			)
		)
		(duplicate_pad_numbers_are_jumpers no)
		(fp_line
			(start -0.508 -0.9398)
			(end 0.508 -0.9398)
			(stroke
				(width 0.1524)
				(type default)
			)
			(layer "B.SilkS")
		)
		(fp_line
			(start 0.508 -0.9398)
			(end 0.508 0.9398)
			(stroke
				(width 0.1524)
				(type default)
			)
			(layer "B.SilkS")
		)
		(fp_rect
			(start 0.508 0.9398)
			(end -0.508 -0.9398)
			(stroke
				(width 0)
				(type default)
			)
			(fill no)
			(layer "B.CrtYd")
		)
		(fp_rect
			(start 0.508 0.9398)
			(end -0.508 -0.9398)
			(stroke
				(width 0)
				(type default)
			)
			(fill no)
			(layer "B.Fab")
		)
		(pad "1" smd custom
			(at 0 -0.4445 90)
			(size 0.1397 0.1397)
			(layers "B.Cu" "B.Mask" "B.Paste")
			(net "P12V_STBY")
			(options
				(clearance outline)
				(anchor circle)
			)
			(primitives
				(gr_poly
					(pts
						(arc
							(start -0.1778 0.2794)
							(mid -0.249642 0.249642)
							(end -0.2794 0.1778)
						)
						(arc
							(start -0.2794 -0.1778)
							(mid -0.249642 -0.249642)
							(end -0.1778 -0.2794)
						)
						(arc
							(start 0.1778 -0.2794)
							(mid 0.249642 -0.249642)
							(end 0.2794 -0.1778)
						)
						(arc
							(start 0.2794 0.1778)
							(mid 0.249642 0.249642)
							(end 0.1778 0.2794)
						)
					)
					(width 0)
					(fill yes)
				)
			)
		)
		(pad "2" smd custom
			(at 0 0.4445 90)
			(size 0.1397 0.1397)
			(layers "B.Cu" "B.Mask" "B.Paste")
			(net "P12V_IOM_PGOOD")
			(options
				(clearance outline)
				(anchor circle)
			)
			(primitives
				(gr_poly
					(pts
						(arc
							(start -0.1778 0.2794)
							(mid -0.249642 0.249642)
							(end -0.2794 0.1778)
						)
						(arc
							(start -0.2794 -0.1778)
							(mid -0.249642 -0.249642)
							(end -0.1778 -0.2794)
						)
						(arc
							(start 0.1778 -0.2794)
							(mid 0.249642 -0.249642)
							(end 0.2794 -0.1778)
						)
						(arc
							(start 0.2794 0.1778)
							(mid 0.249642 0.249642)
							(end 0.1778 0.2794)
						)
					)
					(width 0)
					(fill yes)
				)
			)
		)
	)
	(footprint ""
		(layer "B.Cu")
		(at 60.4774 -148.5138 180)
		(property "Reference" "R384"
			(at 0 0 0)
			(layer "B.SilkS")
			(hide yes)
			(effects
				(font
					(size 1.27 1.27)
				)
				(justify mirror)
			)
		)
		(property "Value" "4K7R2F-GP"
			(at -0.064008 -3.993896 180)
			(unlocked yes)
			(layer "B.Fab")
			(hide yes)
			(effects
				(font
					(size 1.016 1.016)
					(thickness 0.1524)
				)
				(justify mirror)
			)
		)
		(property "Device Type" "R402H16"
			(at -0.064008 -5.517896 180)
			(unlocked yes)
			(layer "B.Fab")
			(hide yes)
			(effects
				(font
					(size 1.016 1.016)
					(thickness 0.1524)
				)
				(justify mirror)
			)
		)
		(duplicate_pad_numbers_are_jumpers no)
		(fp_line
			(start 0.508 -0.9398)
			(end 0.508 0.9398)
			(stroke
				(width 0.1524)
				(type default)
			)
			(layer "B.SilkS")
		)
		(fp_line
			(start -0.508 -0.9398)
			(end 0.508 -0.9398)
			(stroke
				(width 0.1524)
				(type default)
			)
			(layer "B.SilkS")
		)
		(fp_rect
			(start 0.508 0.9398)
			(end -0.508 -0.9398)
			(stroke
				(width 0)
				(type default)
			)
			(fill no)
			(layer "B.CrtYd")
		)
		(fp_rect
			(start 0.508 0.9398)
			(end -0.508 -0.9398)
			(stroke
				(width 0)
				(type default)
			)
			(fill no)
			(layer "B.Fab")
		)
		(pad "1" smd custom
			(at 0 -0.4445)
			(size 0.1397 0.1397)
			(layers "B.Cu" "B.Mask" "B.Paste")
			(net "P3V3_STBY")
			(options
				(clearance outline)
				(anchor circle)
			)
			(primitives
				(gr_poly
					(pts
						(arc
							(start -0.1778 0.2794)
							(mid -0.249642 0.249642)
							(end -0.2794 0.1778)
						)
						(arc
							(start -0.2794 -0.1778)
							(mid -0.249642 -0.249642)
							(end -0.1778 -0.2794)
						)
						(arc
							(start 0.1778 -0.2794)
							(mid 0.249642 -0.249642)
							(end 0.2794 -0.1778)
						)
						(arc
							(start 0.2794 0.1778)
							(mid 0.249642 0.249642)
							(end 0.1778 0.2794)
						)
					)
					(width 0)
					(fill yes)
				)
			)
		)
		(pad "2" smd custom
			(at 0 0.4445)
			(size 0.1397 0.1397)
			(layers "B.Cu" "B.Mask" "B.Paste")
			(net "MAC1_TXD3")
			(options
				(clearance outline)
				(anchor circle)
			)
			(primitives
				(gr_poly
					(pts
						(arc
							(start -0.1778 0.2794)
							(mid -0.249642 0.249642)
							(end -0.2794 0.1778)
						)
						(arc
							(start -0.2794 -0.1778)
							(mid -0.249642 -0.249642)
							(end -0.1778 -0.2794)
						)
						(arc
							(start 0.1778 -0.2794)
							(mid 0.249642 -0.249642)
							(end 0.2794 -0.1778)
						)
						(arc
							(start 0.2794 0.1778)
							(mid 0.249642 0.249642)
							(end 0.1778 0.2794)
						)
					)
					(width 0)
					(fill yes)
				)
			)
		)
	)
	(footprint ""
		(layer "B.Cu")
		(at 19.15287 -131.007358 180)
		(property "Reference" "R236"
			(at 0 0 0)
			(layer "B.SilkS")
			(hide yes)
			(effects
				(font
					(size 1.27 1.27)
				)
				(justify mirror)
			)
		)
		(property "Value" "120R2F-GP"
			(at -0.064008 -3.993896 180)
			(unlocked yes)
			(layer "B.Fab")
			(hide yes)
			(effects
				(font
					(size 1.016 1.016)
					(thickness 0.1524)
				)
				(justify mirror)
			)
		)
		(property "Device Type" "R402H16"
			(at -0.064008 -5.517896 180)
			(unlocked yes)
			(layer "B.Fab")
			(hide yes)
			(effects
				(font
					(size 1.016 1.016)
					(thickness 0.1524)
				)
				(justify mirror)
			)
		)
		(duplicate_pad_numbers_are_jumpers no)
		(fp_line
			(start 0.508 -0.9398)
			(end 0.508 0.9398)
			(stroke
				(width 0.1524)
				(type default)
			)
			(layer "B.SilkS")
		)
		(fp_line
			(start -0.508 -0.9398)
			(end 0.508 -0.9398)
			(stroke
				(width 0.1524)
				(type default)
			)
			(layer "B.SilkS")
		)
		(fp_rect
			(start 0.508 0.9398)
			(end -0.508 -0.9398)
			(stroke
				(width 0)
				(type default)
			)
			(fill no)
			(layer "B.CrtYd")
		)
		(fp_rect
			(start 0.508 0.9398)
			(end -0.508 -0.9398)
			(stroke
				(width 0)
				(type default)
			)
			(fill no)
			(layer "B.Fab")
		)
		(pad "1" smd custom
			(at 0 -0.4445)
			(size 0.1397 0.1397)
			(layers "B.Cu" "B.Mask" "B.Paste")
			(net "MEMA_1")
			(options
				(clearance outline)
				(anchor circle)
			)
			(primitives
				(gr_poly
					(pts
						(arc
							(start -0.1778 0.2794)
							(mid -0.249642 0.249642)
							(end -0.2794 0.1778)
						)
						(arc
							(start -0.2794 -0.1778)
							(mid -0.249642 -0.249642)
							(end -0.1778 -0.2794)
						)
						(arc
							(start 0.1778 -0.2794)
							(mid 0.249642 -0.249642)
							(end 0.2794 -0.1778)
						)
						(arc
							(start 0.2794 0.1778)
							(mid 0.249642 0.249642)
							(end 0.1778 0.2794)
						)
					)
					(width 0)
					(fill yes)
				)
			)
		)
		(pad "2" smd custom
			(at 0 0.4445)
			(size 0.1397 0.1397)
			(layers "B.Cu" "B.Mask" "B.Paste")
			(net "P1V2_STBY")
			(options
				(clearance outline)
				(anchor circle)
			)
			(primitives
				(gr_poly
					(pts
						(arc
							(start -0.1778 0.2794)
							(mid -0.249642 0.249642)
							(end -0.2794 0.1778)
						)
						(arc
							(start -0.2794 -0.1778)
							(mid -0.249642 -0.249642)
							(end -0.1778 -0.2794)
						)
						(arc
							(start 0.1778 -0.2794)
							(mid 0.249642 -0.249642)
							(end 0.2794 -0.1778)
						)
						(arc
							(start 0.2794 0.1778)
							(mid 0.249642 0.249642)
							(end 0.1778 0.2794)
						)
					)
					(width 0)
					(fill yes)
				)
			)
		)
	)
	(footprint ""
		(layer "B.Cu")
		(at 175.768 -77.978 180)
		(property "Reference" "C344"
			(at 0 0 0)
			(layer "B.SilkS")
			(hide yes)
			(effects
				(font
					(size 1.27 1.27)
				)
				(justify mirror)
			)
		)
		(property "Value" "SC1U6D3V1MX-GP"
			(at -1.9177 2.0193 180)
			(unlocked yes)
			(layer "B.Fab")
			(hide yes)
			(effects
				(font
					(size 1.016 1.016)
					(thickness 0.1524)
				)
				(justify mirror)
			)
		)
		(property "Device Type" "C0201H14"
			(at -1.9177 0.4953 180)
			(unlocked yes)
			(layer "B.Fab")
			(hide yes)
			(effects
				(font
					(size 1.016 1.016)
					(thickness 0.1524)
				)
				(justify mirror)
			)
		)
		(duplicate_pad_numbers_are_jumpers no)
		(fp_rect
			(start 0.1524 0.3048)
			(end -0.1524 -0.3048)
			(stroke
				(width 0)
				(type default)
			)
			(fill no)
			(layer "B.CrtYd")
		)
		(fp_poly
			(pts
				(xy 0.2794 0.6477) (xy 0.2794 -0.6477) (xy -0.2794 -0.6477) (xy -0.2794 -0.1905) (xy -0.1524 -0.1905)
				(xy -0.1524 -0.3048) (xy 0.1524 -0.3048) (xy 0.1524 0.3048) (xy -0.1524 0.3048) (xy -0.1524 -0.1778)
				(xy -0.2794 -0.1778) (xy -0.2794 0.6477)
			)
			(stroke
				(width 0)
				(type default)
			)
			(fill no)
			(layer "B.CrtYd")
		)
		(fp_rect
			(start 0.2794 0.6477)
			(end -0.2794 -0.6477)
			(stroke
				(width 0)
				(type default)
			)
			(fill no)
			(layer "B.Fab")
		)
		(pad "1" smd custom
			(at 0 -0.2794)
			(size 0.0762 0.0762)
			(layers "B.Cu" "B.Mask" "B.Paste")
			(net "PLL_VDD")
			(options
				(clearance outline)
				(anchor circle)
			)
			(primitives
				(gr_poly
					(pts
						(arc
							(start 0.1524 0.127)
							(mid 0.137521 0.162921)
							(end 0.1016 0.1778)
						)
						(arc
							(start -0.1016 0.1778)
							(mid -0.137521 0.162921)
							(end -0.1524 0.127)
						)
						(arc
							(start -0.1524 -0.127)
							(mid -0.137521 -0.162921)
							(end -0.1016 -0.1778)
						)
						(arc
							(start 0.1016 -0.1778)
							(mid 0.137521 -0.162921)
							(end 0.1524 -0.127)
						)
					)
					(width 0)
					(fill yes)
				)
			)
		)
		(pad "2" smd custom
			(at 0 0.2794)
			(size 0.0762 0.0762)
			(layers "B.Cu" "B.Mask" "B.Paste")
			(net "GND")
			(options
				(clearance outline)
				(anchor circle)
			)
			(primitives
				(gr_poly
					(pts
						(arc
							(start 0.1524 0.127)
							(mid 0.137521 0.162921)
							(end 0.1016 0.1778)
						)
						(arc
							(start -0.1016 0.1778)
							(mid -0.137521 0.162921)
							(end -0.1524 0.127)
						)
						(arc
							(start -0.1524 -0.127)
							(mid -0.137521 -0.162921)
							(end -0.1016 -0.1778)
						)
						(arc
							(start 0.1016 -0.1778)
							(mid 0.137521 -0.162921)
							(end 0.1524 -0.127)
						)
					)
					(width 0)
					(fill yes)
				)
			)
		)
	)
	(footprint ""
		(layer "B.Cu")
		(at 82.169 -173.2026 90)
		(property "Reference" "C125"
			(at 0 0 90)
			(layer "B.SilkS")
			(hide yes)
			(effects
				(font
					(size 1.27 1.27)
				)
				(justify mirror)
			)
		)
		(property "Value" "SCD1U25V2KX-2-GP"
			(at -1.1811 -2.7051 90)
			(unlocked yes)
			(layer "B.Fab")
			(hide yes)
			(effects
				(font
					(size 1.016 1.016)
					(thickness 0.1524)
				)
				(justify mirror)
			)
		)
		(property "Device Type" "C402H22"
			(at -1.1811 -4.2291 90)
			(unlocked yes)
			(layer "B.Fab")
			(hide yes)
			(effects
				(font
					(size 1.016 1.016)
					(thickness 0.1524)
				)
				(justify mirror)
			)
		)
		(duplicate_pad_numbers_are_jumpers no)
		(fp_rect
			(start 0.4318 0.9525)
			(end -0.4318 -0.9525)
			(stroke
				(width 0)
				(type default)
			)
			(fill no)
			(layer "B.CrtYd")
		)
		(fp_rect
			(start 0.4318 0.9525)
			(end -0.4318 -0.9525)
			(stroke
				(width 0)
				(type default)
			)
			(fill no)
			(layer "B.Fab")
		)
		(pad "1" smd custom
			(at 0 -0.4445 270)
			(size 0.1524 0.1524)
			(layers "B.Cu" "B.Mask" "B.Paste")
			(net "P3V3_STBY")
			(options
				(clearance outline)
				(anchor circle)
			)
			(primitives
				(gr_poly
					(pts
						(arc
							(start 0.3048 0.2032)
							(mid 0.275042 0.275042)
							(end 0.2032 0.3048)
						)
						(arc
							(start -0.2032 0.3048)
							(mid -0.275042 0.275042)
							(end -0.3048 0.2032)
						)
						(arc
							(start -0.3048 -0.2032)
							(mid -0.275042 -0.275042)
							(end -0.2032 -0.3048)
						)
						(arc
							(start 0.2032 -0.3048)
							(mid 0.275042 -0.275042)
							(end 0.3048 -0.2032)
						)
					)
					(width 0)
					(fill yes)
				)
			)
		)
		(pad "2" smd custom
			(at 0 0.4445 270)
			(size 0.1524 0.1524)
			(layers "B.Cu" "B.Mask" "B.Paste")
			(net "GND")
			(options
				(clearance outline)
				(anchor circle)
			)
			(primitives
				(gr_poly
					(pts
						(arc
							(start 0.3048 0.2032)
							(mid 0.275042 0.275042)
							(end 0.2032 0.3048)
						)
						(arc
							(start -0.2032 0.3048)
							(mid -0.275042 0.275042)
							(end -0.3048 0.2032)
						)
						(arc
							(start -0.3048 -0.2032)
							(mid -0.275042 -0.275042)
							(end -0.2032 -0.3048)
						)
						(arc
							(start 0.2032 -0.3048)
							(mid 0.275042 -0.275042)
							(end 0.3048 -0.2032)
						)
					)
					(width 0)
					(fill yes)
				)
			)
		)
	)
	(footprint ""
		(layer "B.Cu")
		(at 168.656 -107.061 -90)
		(property "Reference" "C447"
			(at 0 0 90)
			(layer "B.SilkS")
			(hide yes)
			(effects
				(font
					(size 1.27 1.27)
				)
				(justify mirror)
			)
		)
		(property "Value" "SCD1U16V2KX-3GP"
			(at -1.1811 -2.7051 270)
			(unlocked yes)
			(layer "B.Fab")
			(hide yes)
			(effects
				(font
					(size 1.016 1.016)
					(thickness 0.1524)
				)
				(justify mirror)
			)
		)
		(property "Device Type" "C402H22"
			(at -1.1811 -4.2291 270)
			(unlocked yes)
			(layer "B.Fab")
			(hide yes)
			(effects
				(font
					(size 1.016 1.016)
					(thickness 0.1524)
				)
				(justify mirror)
			)
		)
		(duplicate_pad_numbers_are_jumpers no)
		(fp_rect
			(start 0.4318 0.9525)
			(end -0.4318 -0.9525)
			(stroke
				(width 0)
				(type default)
			)
			(fill no)
			(layer "B.CrtYd")
		)
		(fp_rect
			(start 0.4318 0.9525)
			(end -0.4318 -0.9525)
			(stroke
				(width 0)
				(type default)
			)
			(fill no)
			(layer "B.Fab")
		)
		(pad "1" smd custom
			(at 0 -0.4445 90)
			(size 0.1524 0.1524)
			(layers "B.Cu" "B.Mask" "B.Paste")
			(net "P1V8")
			(options
				(clearance outline)
				(anchor circle)
			)
			(primitives
				(gr_poly
					(pts
						(arc
							(start 0.3048 0.2032)
							(mid 0.275042 0.275042)
							(end 0.2032 0.3048)
						)
						(arc
							(start -0.2032 0.3048)
							(mid -0.275042 0.275042)
							(end -0.3048 0.2032)
						)
						(arc
							(start -0.3048 -0.2032)
							(mid -0.275042 -0.275042)
							(end -0.2032 -0.3048)
						)
						(arc
							(start 0.2032 -0.3048)
							(mid 0.275042 -0.275042)
							(end 0.3048 -0.2032)
						)
					)
					(width 0)
					(fill yes)
				)
			)
		)
		(pad "2" smd custom
			(at 0 0.4445 90)
			(size 0.1524 0.1524)
			(layers "B.Cu" "B.Mask" "B.Paste")
			(net "GND")
			(options
				(clearance outline)
				(anchor circle)
			)
			(primitives
				(gr_poly
					(pts
						(arc
							(start 0.3048 0.2032)
							(mid 0.275042 0.275042)
							(end 0.2032 0.3048)
						)
						(arc
							(start -0.2032 0.3048)
							(mid -0.275042 0.275042)
							(end -0.3048 0.2032)
						)
						(arc
							(start -0.3048 -0.2032)
							(mid -0.275042 -0.275042)
							(end -0.2032 -0.3048)
						)
						(arc
							(start 0.2032 -0.3048)
							(mid 0.275042 -0.275042)
							(end 0.3048 -0.2032)
						)
					)
					(width 0)
					(fill yes)
				)
			)
		)
	)
	(footprint ""
		(layer "B.Cu")
		(at 78.2066 -130.175)
		(property "Reference" "C502"
			(at 0 0 0)
			(layer "B.SilkS")
			(hide yes)
			(effects
				(font
					(size 1.27 1.27)
				)
				(justify mirror)
			)
		)
		(property "Value" "SCD1U16V2KX-3GP"
			(at -1.1811 -2.7051 0)
			(unlocked yes)
			(layer "B.Fab")
			(hide yes)
			(effects
				(font
					(size 1.016 1.016)
					(thickness 0.1524)
				)
				(justify mirror)
			)
		)
		(property "Device Type" "C402H22"
			(at -1.1811 -4.2291 0)
			(unlocked yes)
			(layer "B.Fab")
			(hide yes)
			(effects
				(font
					(size 1.016 1.016)
					(thickness 0.1524)
				)
				(justify mirror)
			)
		)
		(duplicate_pad_numbers_are_jumpers no)
		(fp_rect
			(start 0.4318 0.9525)
			(end -0.4318 -0.9525)
			(stroke
				(width 0)
				(type default)
			)
			(fill no)
			(layer "B.CrtYd")
		)
		(fp_rect
			(start 0.4318 0.9525)
			(end -0.4318 -0.9525)
			(stroke
				(width 0)
				(type default)
			)
			(fill no)
			(layer "B.Fab")
		)
		(pad "1" smd custom
			(at 0 -0.4445 180)
			(size 0.1524 0.1524)
			(layers "B.Cu" "B.Mask" "B.Paste")
			(net "P3V3_STBY")
			(options
				(clearance outline)
				(anchor circle)
			)
			(primitives
				(gr_poly
					(pts
						(arc
							(start 0.3048 0.2032)
							(mid 0.275042 0.275042)
							(end 0.2032 0.3048)
						)
						(arc
							(start -0.2032 0.3048)
							(mid -0.275042 0.275042)
							(end -0.3048 0.2032)
						)
						(arc
							(start -0.3048 -0.2032)
							(mid -0.275042 -0.275042)
							(end -0.2032 -0.3048)
						)
						(arc
							(start 0.2032 -0.3048)
							(mid 0.275042 -0.275042)
							(end 0.3048 -0.2032)
						)
					)
					(width 0)
					(fill yes)
				)
			)
		)
		(pad "2" smd custom
			(at 0 0.4445 180)
			(size 0.1524 0.1524)
			(layers "B.Cu" "B.Mask" "B.Paste")
			(net "GND")
			(options
				(clearance outline)
				(anchor circle)
			)
			(primitives
				(gr_poly
					(pts
						(arc
							(start 0.3048 0.2032)
							(mid 0.275042 0.275042)
							(end 0.2032 0.3048)
						)
						(arc
							(start -0.2032 0.3048)
							(mid -0.275042 0.275042)
							(end -0.3048 0.2032)
						)
						(arc
							(start -0.3048 -0.2032)
							(mid -0.275042 -0.275042)
							(end -0.2032 -0.3048)
						)
						(arc
							(start 0.2032 -0.3048)
							(mid 0.275042 -0.275042)
							(end 0.3048 -0.2032)
						)
					)
					(width 0)
					(fill yes)
				)
			)
		)
	)
	(footprint ""
		(layer "B.Cu")
		(at 208.7372 -63.0428 -90)
		(property "Reference" "R589"
			(at 0 0 90)
			(layer "B.SilkS")
			(hide yes)
			(effects
				(font
					(size 1.27 1.27)
				)
				(justify mirror)
			)
		)
		(property "Value" "2K2R2F-GP"
			(at -0.064008 -3.993896 270)
			(unlocked yes)
			(layer "B.Fab")
			(hide yes)
			(effects
				(font
					(size 1.016 1.016)
					(thickness 0.1524)
				)
				(justify mirror)
			)
		)
		(property "Device Type" "R402H16"
			(at -0.064008 -5.517896 270)
			(unlocked yes)
			(layer "B.Fab")
			(hide yes)
			(effects
				(font
					(size 1.016 1.016)
					(thickness 0.1524)
				)
				(justify mirror)
			)
		)
		(duplicate_pad_numbers_are_jumpers no)
		(fp_line
			(start -0.508 -0.9398)
			(end 0.508 -0.9398)
			(stroke
				(width 0.1524)
				(type default)
			)
			(layer "B.SilkS")
		)
		(fp_line
			(start 0.508 -0.9398)
			(end 0.508 0.9398)
			(stroke
				(width 0.1524)
				(type default)
			)
			(layer "B.SilkS")
		)
		(fp_rect
			(start 0.508 0.9398)
			(end -0.508 -0.9398)
			(stroke
				(width 0)
				(type default)
			)
			(fill no)
			(layer "B.CrtYd")
		)
		(fp_rect
			(start 0.508 0.9398)
			(end -0.508 -0.9398)
			(stroke
				(width 0)
				(type default)
			)
			(fill no)
			(layer "B.Fab")
		)
		(pad "1" smd custom
			(at 0 -0.4445 90)
			(size 0.1397 0.1397)
			(layers "B.Cu" "B.Mask" "B.Paste")
			(net "P1V8")
			(options
				(clearance outline)
				(anchor circle)
			)
			(primitives
				(gr_poly
					(pts
						(arc
							(start -0.1778 0.2794)
							(mid -0.249642 0.249642)
							(end -0.2794 0.1778)
						)
						(arc
							(start -0.2794 -0.1778)
							(mid -0.249642 -0.249642)
							(end -0.1778 -0.2794)
						)
						(arc
							(start 0.1778 -0.2794)
							(mid 0.249642 -0.249642)
							(end 0.2794 -0.1778)
						)
						(arc
							(start 0.2794 0.1778)
							(mid 0.249642 0.249642)
							(end 0.1778 0.2794)
						)
					)
					(width 0)
					(fill yes)
				)
			)
		)
		(pad "2" smd custom
			(at 0 0.4445 90)
			(size 0.1397 0.1397)
			(layers "B.Cu" "B.Mask" "B.Paste")
			(net "SIO_DIN_0")
			(options
				(clearance outline)
				(anchor circle)
			)
			(primitives
				(gr_poly
					(pts
						(arc
							(start -0.1778 0.2794)
							(mid -0.249642 0.249642)
							(end -0.2794 0.1778)
						)
						(arc
							(start -0.2794 -0.1778)
							(mid -0.249642 -0.249642)
							(end -0.1778 -0.2794)
						)
						(arc
							(start 0.1778 -0.2794)
							(mid 0.249642 -0.249642)
							(end 0.2794 -0.1778)
						)
						(arc
							(start 0.2794 0.1778)
							(mid 0.249642 0.249642)
							(end 0.1778 0.2794)
						)
					)
					(width 0)
					(fill yes)
				)
			)
		)
	)
	(footprint ""
		(layer "B.Cu")
		(at 50.59426 -155.3718 -90)
		(property "Reference" "R191"
			(at 0 0 90)
			(layer "B.SilkS")
			(hide yes)
			(effects
				(font
					(size 1.27 1.27)
				)
				(justify mirror)
			)
		)
		(property "Value" "2K2R2F-GP"
			(at -0.064008 -3.993896 270)
			(unlocked yes)
			(layer "B.Fab")
			(hide yes)
			(effects
				(font
					(size 1.016 1.016)
					(thickness 0.1524)
				)
				(justify mirror)
			)
		)
		(property "Device Type" "R402H16"
			(at -0.064008 -5.517896 270)
			(unlocked yes)
			(layer "B.Fab")
			(hide yes)
			(effects
				(font
					(size 1.016 1.016)
					(thickness 0.1524)
				)
				(justify mirror)
			)
		)
		(duplicate_pad_numbers_are_jumpers no)
		(fp_line
			(start -0.508 -0.9398)
			(end 0.508 -0.9398)
			(stroke
				(width 0.1524)
				(type default)
			)
			(layer "B.SilkS")
		)
		(fp_line
			(start 0.508 -0.9398)
			(end 0.508 0.9398)
			(stroke
				(width 0.1524)
				(type default)
			)
			(layer "B.SilkS")
		)
		(fp_rect
			(start 0.508 0.9398)
			(end -0.508 -0.9398)
			(stroke
				(width 0)
				(type default)
			)
			(fill no)
			(layer "B.CrtYd")
		)
		(fp_rect
			(start 0.508 0.9398)
			(end -0.508 -0.9398)
			(stroke
				(width 0)
				(type default)
			)
			(fill no)
			(layer "B.Fab")
		)
		(pad "1" smd custom
			(at 0 -0.4445 90)
			(size 0.1397 0.1397)
			(layers "B.Cu" "B.Mask" "B.Paste")
			(net "I2C_MEZZ_OOB_SCL")
			(options
				(clearance outline)
				(anchor circle)
			)
			(primitives
				(gr_poly
					(pts
						(arc
							(start -0.1778 0.2794)
							(mid -0.249642 0.249642)
							(end -0.2794 0.1778)
						)
						(arc
							(start -0.2794 -0.1778)
							(mid -0.249642 -0.249642)
							(end -0.1778 -0.2794)
						)
						(arc
							(start 0.1778 -0.2794)
							(mid 0.249642 -0.249642)
							(end 0.2794 -0.1778)
						)
						(arc
							(start 0.2794 0.1778)
							(mid 0.249642 0.249642)
							(end 0.1778 0.2794)
						)
					)
					(width 0)
					(fill yes)
				)
			)
		)
		(pad "2" smd custom
			(at 0 0.4445 90)
			(size 0.1397 0.1397)
			(layers "B.Cu" "B.Mask" "B.Paste")
			(net "P3V3_STBY")
			(options
				(clearance outline)
				(anchor circle)
			)
			(primitives
				(gr_poly
					(pts
						(arc
							(start -0.1778 0.2794)
							(mid -0.249642 0.249642)
							(end -0.2794 0.1778)
						)
						(arc
							(start -0.2794 -0.1778)
							(mid -0.249642 -0.249642)
							(end -0.1778 -0.2794)
						)
						(arc
							(start 0.1778 -0.2794)
							(mid 0.249642 -0.249642)
							(end 0.2794 -0.1778)
						)
						(arc
							(start 0.2794 0.1778)
							(mid 0.249642 0.249642)
							(end 0.1778 0.2794)
						)
					)
					(width 0)
					(fill yes)
				)
			)
		)
	)
	(footprint ""
		(layer "B.Cu")
		(at 41.1988 -154.11704 90)
		(property "Reference" "R326"
			(at 0 0 90)
			(layer "B.SilkS")
			(hide yes)
			(effects
				(font
					(size 1.27 1.27)
				)
				(justify mirror)
			)
		)
		(property "Value" "0R2J-2-GP"
			(at -0.064008 -3.993896 90)
			(unlocked yes)
			(layer "B.Fab")
			(hide yes)
			(effects
				(font
					(size 1.016 1.016)
					(thickness 0.1524)
				)
				(justify mirror)
			)
		)
		(property "Device Type" "R402H16"
			(at -0.064008 -5.517896 90)
			(unlocked yes)
			(layer "B.Fab")
			(hide yes)
			(effects
				(font
					(size 1.016 1.016)
					(thickness 0.1524)
				)
				(justify mirror)
			)
		)
		(duplicate_pad_numbers_are_jumpers no)
		(fp_line
			(start 0.508 -0.9398)
			(end 0.508 0.9398)
			(stroke
				(width 0.1524)
				(type default)
			)
			(layer "B.SilkS")
		)
		(fp_line
			(start -0.508 -0.9398)
			(end 0.508 -0.9398)
			(stroke
				(width 0.1524)
				(type default)
			)
			(layer "B.SilkS")
		)
		(fp_rect
			(start 0.508 0.9398)
			(end -0.508 -0.9398)
			(stroke
				(width 0)
				(type default)
			)
			(fill no)
			(layer "B.CrtYd")
		)
		(fp_rect
			(start 0.508 0.9398)
			(end -0.508 -0.9398)
			(stroke
				(width 0)
				(type default)
			)
			(fill no)
			(layer "B.Fab")
		)
		(pad "1" smd custom
			(at 0 -0.4445 270)
			(size 0.1397 0.1397)
			(layers "B.Cu" "B.Mask" "B.Paste")
			(net "BMC_LOC_HB")
			(options
				(clearance outline)
				(anchor circle)
			)
			(primitives
				(gr_poly
					(pts
						(arc
							(start -0.1778 0.2794)
							(mid -0.249642 0.249642)
							(end -0.2794 0.1778)
						)
						(arc
							(start -0.2794 -0.1778)
							(mid -0.249642 -0.249642)
							(end -0.1778 -0.2794)
						)
						(arc
							(start 0.1778 -0.2794)
							(mid 0.249642 -0.249642)
							(end 0.2794 -0.1778)
						)
						(arc
							(start 0.2794 0.1778)
							(mid 0.249642 0.249642)
							(end 0.1778 0.2794)
						)
					)
					(width 0)
					(fill yes)
				)
			)
		)
		(pad "2" smd custom
			(at 0 0.4445 270)
			(size 0.1397 0.1397)
			(layers "B.Cu" "B.Mask" "B.Paste")
			(net "BMC_LOC_HEARTBEAT")
			(options
				(clearance outline)
				(anchor circle)
			)
			(primitives
				(gr_poly
					(pts
						(arc
							(start -0.1778 0.2794)
							(mid -0.249642 0.249642)
							(end -0.2794 0.1778)
						)
						(arc
							(start -0.2794 -0.1778)
							(mid -0.249642 -0.249642)
							(end -0.1778 -0.2794)
						)
						(arc
							(start 0.1778 -0.2794)
							(mid 0.249642 -0.249642)
							(end 0.2794 -0.1778)
						)
						(arc
							(start 0.2794 0.1778)
							(mid 0.249642 0.249642)
							(end 0.1778 0.2794)
						)
					)
					(width 0)
					(fill yes)
				)
			)
		)
	)
	(footprint ""
		(layer "B.Cu")
		(at 57.937908 -134.910068)
		(property "Reference" "R169"
			(at 0 0 0)
			(layer "B.SilkS")
			(hide yes)
			(effects
				(font
					(size 1.27 1.27)
				)
				(justify mirror)
			)
		)
		(property "Value" "0R2J-2-GP"
			(at -0.064008 -3.993896 0)
			(unlocked yes)
			(layer "B.Fab")
			(hide yes)
			(effects
				(font
					(size 1.016 1.016)
					(thickness 0.1524)
				)
				(justify mirror)
			)
		)
		(property "Device Type" "R402H16"
			(at -0.064008 -5.517896 0)
			(unlocked yes)
			(layer "B.Fab")
			(hide yes)
			(effects
				(font
					(size 1.016 1.016)
					(thickness 0.1524)
				)
				(justify mirror)
			)
		)
		(duplicate_pad_numbers_are_jumpers no)
		(fp_line
			(start -0.508 -0.9398)
			(end 0.508 -0.9398)
			(stroke
				(width 0.1524)
				(type default)
			)
			(layer "B.SilkS")
		)
		(fp_line
			(start 0.508 -0.9398)
			(end 0.508 0.9398)
			(stroke
				(width 0.1524)
				(type default)
			)
			(layer "B.SilkS")
		)
		(fp_rect
			(start 0.508 0.9398)
			(end -0.508 -0.9398)
			(stroke
				(width 0)
				(type default)
			)
			(fill no)
			(layer "B.CrtYd")
		)
		(fp_rect
			(start 0.508 0.9398)
			(end -0.508 -0.9398)
			(stroke
				(width 0)
				(type default)
			)
			(fill no)
			(layer "B.Fab")
		)
		(pad "1" smd custom
			(at 0 -0.4445 180)
			(size 0.1397 0.1397)
			(layers "B.Cu" "B.Mask" "B.Paste")
			(net "COMP_PWR_BTN_R_N")
			(options
				(clearance outline)
				(anchor circle)
			)
			(primitives
				(gr_poly
					(pts
						(arc
							(start -0.1778 0.2794)
							(mid -0.249642 0.249642)
							(end -0.2794 0.1778)
						)
						(arc
							(start -0.2794 -0.1778)
							(mid -0.249642 -0.249642)
							(end -0.1778 -0.2794)
						)
						(arc
							(start 0.1778 -0.2794)
							(mid 0.249642 -0.249642)
							(end 0.2794 -0.1778)
						)
						(arc
							(start 0.2794 0.1778)
							(mid 0.249642 0.249642)
							(end 0.1778 0.2794)
						)
					)
					(width 0)
					(fill yes)
				)
			)
		)
		(pad "2" smd custom
			(at 0 0.4445 180)
			(size 0.1397 0.1397)
			(layers "B.Cu" "B.Mask" "B.Paste")
			(net "COMP_PWR_BTN_N")
			(options
				(clearance outline)
				(anchor circle)
			)
			(primitives
				(gr_poly
					(pts
						(arc
							(start -0.1778 0.2794)
							(mid -0.249642 0.249642)
							(end -0.2794 0.1778)
						)
						(arc
							(start -0.2794 -0.1778)
							(mid -0.249642 -0.249642)
							(end -0.1778 -0.2794)
						)
						(arc
							(start 0.1778 -0.2794)
							(mid 0.249642 -0.249642)
							(end 0.2794 -0.1778)
						)
						(arc
							(start 0.2794 0.1778)
							(mid 0.249642 0.249642)
							(end 0.1778 0.2794)
						)
					)
					(width 0)
					(fill yes)
				)
			)
		)
	)
	(footprint ""
		(layer "B.Cu")
		(at 211.836 -89.662 -90)
		(property "Reference" "R684"
			(at 0 0 90)
			(layer "B.SilkS")
			(hide yes)
			(effects
				(font
					(size 1.27 1.27)
				)
				(justify mirror)
			)
		)
		(property "Value" "10R2F-L-GP"
			(at -0.064008 -3.993896 270)
			(unlocked yes)
			(layer "B.Fab")
			(hide yes)
			(effects
				(font
					(size 1.016 1.016)
					(thickness 0.1524)
				)
				(justify mirror)
			)
		)
		(property "Device Type" "R402H14"
			(at -0.064008 -5.517896 270)
			(unlocked yes)
			(layer "B.Fab")
			(hide yes)
			(effects
				(font
					(size 1.016 1.016)
					(thickness 0.1524)
				)
				(justify mirror)
			)
		)
		(duplicate_pad_numbers_are_jumpers no)
		(fp_line
			(start -0.508 -0.9398)
			(end 0.508 -0.9398)
			(stroke
				(width 0.1524)
				(type default)
			)
			(layer "B.SilkS")
		)
		(fp_line
			(start 0.508 -0.9398)
			(end 0.508 0.9398)
			(stroke
				(width 0.1524)
				(type default)
			)
			(layer "B.SilkS")
		)
		(fp_rect
			(start 0.508 0.9398)
			(end -0.508 -0.9398)
			(stroke
				(width 0)
				(type default)
			)
			(fill no)
			(layer "B.CrtYd")
		)
		(fp_rect
			(start 0.508 0.9398)
			(end -0.508 -0.9398)
			(stroke
				(width 0)
				(type default)
			)
			(fill no)
			(layer "B.Fab")
		)
		(pad "1" smd custom
			(at 0 -0.4445 90)
			(size 0.1397 0.1397)
			(layers "B.Cu" "B.Mask" "B.Paste")
			(net "P1V8")
			(options
				(clearance outline)
				(anchor circle)
			)
			(primitives
				(gr_poly
					(pts
						(arc
							(start -0.1778 0.2794)
							(mid -0.249642 0.249642)
							(end -0.2794 0.1778)
						)
						(arc
							(start -0.2794 -0.1778)
							(mid -0.249642 -0.249642)
							(end -0.1778 -0.2794)
						)
						(arc
							(start 0.1778 -0.2794)
							(mid 0.249642 -0.249642)
							(end 0.2794 -0.1778)
						)
						(arc
							(start 0.2794 0.1778)
							(mid 0.249642 0.249642)
							(end 0.1778 0.2794)
						)
					)
					(width 0)
					(fill yes)
				)
			)
		)
		(pad "2" smd custom
			(at 0 0.4445 90)
			(size 0.1397 0.1397)
			(layers "B.Cu" "B.Mask" "B.Paste")
			(net "SAS0_VDDH")
			(options
				(clearance outline)
				(anchor circle)
			)
			(primitives
				(gr_poly
					(pts
						(arc
							(start -0.1778 0.2794)
							(mid -0.249642 0.249642)
							(end -0.2794 0.1778)
						)
						(arc
							(start -0.2794 -0.1778)
							(mid -0.249642 -0.249642)
							(end -0.1778 -0.2794)
						)
						(arc
							(start 0.1778 -0.2794)
							(mid 0.249642 -0.249642)
							(end 0.2794 -0.1778)
						)
						(arc
							(start 0.2794 0.1778)
							(mid 0.249642 0.249642)
							(end 0.1778 0.2794)
						)
					)
					(width 0)
					(fill yes)
				)
			)
		)
	)
	(footprint ""
		(layer "B.Cu")
		(at 44.5008 -140.97)
		(property "Reference" "TP28"
			(at 0 0 0)
			(layer "B.SilkS")
			(hide yes)
			(effects
				(font
					(size 1.27 1.27)
				)
				(justify mirror)
			)
		)
		(property "Value" "TPAD28-2-GP"
			(at 0.0127 -1.6637 0)
			(unlocked yes)
			(layer "B.Fab")
			(hide yes)
			(effects
				(font
					(size 1.016 1.016)
					(thickness 0.1524)
				)
				(justify mirror)
			)
		)
		(property "Device Type" "TPAD28"
			(at 0.0127 -3.1877 0)
			(unlocked yes)
			(layer "B.Fab")
			(hide yes)
			(effects
				(font
					(size 1.016 1.016)
					(thickness 0.1524)
				)
				(justify mirror)
			)
		)
		(duplicate_pad_numbers_are_jumpers no)
		(fp_poly
			(pts
				(arc
					(start 0.3556 0)
					(mid -0.3556 0)
					(end 0.3556 0)
				)
			)
			(stroke
				(width 0)
				(type default)
			)
			(fill no)
			(layer "B.CrtYd")
		)
		(fp_poly
			(pts
				(arc
					(start 0.6096 0)
					(mid -0.6096 0)
					(end 0.6096 0)
				)
			)
			(stroke
				(width 0)
				(type default)
			)
			(fill no)
			(layer "B.Fab")
		)
		(pad "1" smd circle
			(at 0 0 180)
			(size 0.7112 0.7112)
			(layers "B.Cu" "B.Mask" "B.Paste")
			(net "TP_BMC_GPIOR2")
		)
	)
	(footprint ""
		(layer "B.Cu")
		(at 57.42305 -146.511264 -90)
		(property "Reference" "R360"
			(at 0 0 90)
			(layer "B.SilkS")
			(hide yes)
			(effects
				(font
					(size 1.27 1.27)
				)
				(justify mirror)
			)
		)
		(property "Value" "10KR2F-2-GP"
			(at -0.064008 -3.993896 270)
			(unlocked yes)
			(layer "B.Fab")
			(hide yes)
			(effects
				(font
					(size 1.016 1.016)
					(thickness 0.1524)
				)
				(justify mirror)
			)
		)
		(property "Device Type" "R402H16"
			(at -0.064008 -5.517896 270)
			(unlocked yes)
			(layer "B.Fab")
			(hide yes)
			(effects
				(font
					(size 1.016 1.016)
					(thickness 0.1524)
				)
				(justify mirror)
			)
		)
		(duplicate_pad_numbers_are_jumpers no)
		(fp_line
			(start -0.508 -0.9398)
			(end 0.508 -0.9398)
			(stroke
				(width 0.1524)
				(type default)
			)
			(layer "B.SilkS")
		)
		(fp_line
			(start 0.508 -0.9398)
			(end 0.508 0.9398)
			(stroke
				(width 0.1524)
				(type default)
			)
			(layer "B.SilkS")
		)
		(fp_rect
			(start 0.508 0.9398)
			(end -0.508 -0.9398)
			(stroke
				(width 0)
				(type default)
			)
			(fill no)
			(layer "B.CrtYd")
		)
		(fp_rect
			(start 0.508 0.9398)
			(end -0.508 -0.9398)
			(stroke
				(width 0)
				(type default)
			)
			(fill no)
			(layer "B.Fab")
		)
		(pad "1" smd custom
			(at 0 -0.4445 90)
			(size 0.1397 0.1397)
			(layers "B.Cu" "B.Mask" "B.Paste")
			(net "P3V3_STBY")
			(options
				(clearance outline)
				(anchor circle)
			)
			(primitives
				(gr_poly
					(pts
						(arc
							(start -0.1778 0.2794)
							(mid -0.249642 0.249642)
							(end -0.2794 0.1778)
						)
						(arc
							(start -0.2794 -0.1778)
							(mid -0.249642 -0.249642)
							(end -0.1778 -0.2794)
						)
						(arc
							(start 0.1778 -0.2794)
							(mid 0.249642 -0.249642)
							(end 0.2794 -0.1778)
						)
						(arc
							(start 0.2794 0.1778)
							(mid 0.249642 0.249642)
							(end 0.1778 0.2794)
						)
					)
					(width 0)
					(fill yes)
				)
			)
		)
		(pad "2" smd custom
			(at 0 0.4445 90)
			(size 0.1397 0.1397)
			(layers "B.Cu" "B.Mask" "B.Paste")
			(net "JTAG_BMC_TCK")
			(options
				(clearance outline)
				(anchor circle)
			)
			(primitives
				(gr_poly
					(pts
						(arc
							(start -0.1778 0.2794)
							(mid -0.249642 0.249642)
							(end -0.2794 0.1778)
						)
						(arc
							(start -0.2794 -0.1778)
							(mid -0.249642 -0.249642)
							(end -0.1778 -0.2794)
						)
						(arc
							(start 0.1778 -0.2794)
							(mid 0.249642 -0.249642)
							(end 0.2794 -0.1778)
						)
						(arc
							(start 0.2794 0.1778)
							(mid 0.249642 0.249642)
							(end 0.1778 0.2794)
						)
					)
					(width 0)
					(fill yes)
				)
			)
		)
	)
	(footprint ""
		(layer "B.Cu")
		(at 146.558 -17.145 90)
		(property "Reference" "U52"
			(at 0 0 90)
			(layer "B.SilkS")
			(hide yes)
			(effects
				(font
					(size 1.27 1.27)
				)
				(justify mirror)
			)
		)
		(property "Value" "SN74LVC1G08DCKR-GP"
			(at 2.3368 -8.6868 90)
			(unlocked yes)
			(layer "B.Fab")
			(hide yes)
			(effects
				(font
					(size 1.016 1.016)
					(thickness 0.1524)
				)
				(justify mirror)
			)
		)
		(property "Device Type" "SC70-5H44"
			(at 2.3114 -10.414 90)
			(unlocked yes)
			(layer "B.Fab")
			(hide yes)
			(effects
				(font
					(size 1.016 1.016)
					(thickness 0.1524)
				)
				(justify mirror)
			)
		)
		(duplicate_pad_numbers_are_jumpers no)
		(fp_line
			(start -0.6604 -1.8034)
			(end -1.3843 -1.8034)
			(stroke
				(width 0.3302)
				(type default)
			)
			(layer "B.SilkS")
		)
		(fp_line
			(start -1.3843 -1.8034)
			(end -1.3843 -1.1176)
			(stroke
				(width 0.3302)
				(type default)
			)
			(layer "B.SilkS")
		)
		(fp_line
			(start 1.27 -1.7018)
			(end -1.27 -1.7018)
			(stroke
				(width 0.1524)
				(type default)
			)
			(layer "B.SilkS")
		)
		(fp_line
			(start -1.27 -1.7018)
			(end -1.27 1.7018)
			(stroke
				(width 0.1524)
				(type default)
			)
			(layer "B.SilkS")
		)
		(fp_line
			(start 1.27 1.7018)
			(end 1.27 -1.7018)
			(stroke
				(width 0.1524)
				(type default)
			)
			(layer "B.SilkS")
		)
		(fp_line
			(start -1.27 1.7018)
			(end 1.27 1.7018)
			(stroke
				(width 0.1524)
				(type default)
			)
			(layer "B.SilkS")
		)
		(fp_rect
			(start 1.524 1.9558)
			(end -1.524 -1.9558)
			(stroke
				(width 0)
				(type default)
			)
			(fill no)
			(layer "B.CrtYd")
		)
		(fp_poly
			(pts
				(xy 1.524 -1.9558) (xy -1.524 -1.9558) (xy -1.524 1.9558) (xy 1.524 1.9558)
			)
			(stroke
				(width 0)
				(type default)
			)
			(fill no)
			(layer "B.Fab")
		)
		(pad "1" smd rect
			(at -0.65024 -0.8255 270)
			(size 0.4064 1.2192)
			(layers "B.Cu" "B.Mask" "B.Paste")
			(net "BMC_EXT2_LED_Y")
		)
		(pad "2" smd rect
			(at 0 -0.8255 270)
			(size 0.4064 1.2192)
			(layers "B.Cu" "B.Mask" "B.Paste")
			(net "EXT2_LED_YELLOW_D")
		)
		(pad "3" smd rect
			(at 0.65024 -0.8255 270)
			(size 0.4064 1.2192)
			(layers "B.Cu" "B.Mask" "B.Paste")
			(net "GND")
		)
		(pad "4" smd rect
			(at 0.65024 0.8255 270)
			(size 0.4064 1.2192)
			(layers "B.Cu" "B.Mask" "B.Paste")
			(net "EXT2_LED_YELLOW_G1")
		)
		(pad "5" smd rect
			(at -0.65024 0.8255 270)
			(size 0.4064 1.2192)
			(layers "B.Cu" "B.Mask" "B.Paste")
			(net "P3V3_STBY")
		)
	)
	(footprint ""
		(layer "B.Cu")
		(at 54.053232 -165.936676 90)
		(property "Reference" "R416"
			(at 0 0 90)
			(layer "B.SilkS")
			(hide yes)
			(effects
				(font
					(size 1.27 1.27)
				)
				(justify mirror)
			)
		)
		(property "Value" "1KR2F-3-GP"
			(at -0.064008 -3.993896 90)
			(unlocked yes)
			(layer "B.Fab")
			(hide yes)
			(effects
				(font
					(size 1.016 1.016)
					(thickness 0.1524)
				)
				(justify mirror)
			)
		)
		(property "Device Type" "R402H16"
			(at -0.064008 -5.517896 90)
			(unlocked yes)
			(layer "B.Fab")
			(hide yes)
			(effects
				(font
					(size 1.016 1.016)
					(thickness 0.1524)
				)
				(justify mirror)
			)
		)
		(duplicate_pad_numbers_are_jumpers no)
		(fp_line
			(start 0.508 -0.9398)
			(end 0.508 0.9398)
			(stroke
				(width 0.1524)
				(type default)
			)
			(layer "B.SilkS")
		)
		(fp_line
			(start -0.508 -0.9398)
			(end 0.508 -0.9398)
			(stroke
				(width 0.1524)
				(type default)
			)
			(layer "B.SilkS")
		)
		(fp_rect
			(start 0.508 0.9398)
			(end -0.508 -0.9398)
			(stroke
				(width 0)
				(type default)
			)
			(fill no)
			(layer "B.CrtYd")
		)
		(fp_rect
			(start 0.508 0.9398)
			(end -0.508 -0.9398)
			(stroke
				(width 0)
				(type default)
			)
			(fill no)
			(layer "B.Fab")
		)
		(pad "1" smd custom
			(at 0 -0.4445 270)
			(size 0.1397 0.1397)
			(layers "B.Cu" "B.Mask" "B.Paste")
			(net "ADC_P0V975")
			(options
				(clearance outline)
				(anchor circle)
			)
			(primitives
				(gr_poly
					(pts
						(arc
							(start -0.1778 0.2794)
							(mid -0.249642 0.249642)
							(end -0.2794 0.1778)
						)
						(arc
							(start -0.2794 -0.1778)
							(mid -0.249642 -0.249642)
							(end -0.1778 -0.2794)
						)
						(arc
							(start 0.1778 -0.2794)
							(mid 0.249642 -0.249642)
							(end 0.2794 -0.1778)
						)
						(arc
							(start 0.2794 0.1778)
							(mid 0.249642 0.249642)
							(end 0.1778 0.2794)
						)
					)
					(width 0)
					(fill yes)
				)
			)
		)
		(pad "2" smd custom
			(at 0 0.4445 270)
			(size 0.1397 0.1397)
			(layers "B.Cu" "B.Mask" "B.Paste")
			(net "GND")
			(options
				(clearance outline)
				(anchor circle)
			)
			(primitives
				(gr_poly
					(pts
						(arc
							(start -0.1778 0.2794)
							(mid -0.249642 0.249642)
							(end -0.2794 0.1778)
						)
						(arc
							(start -0.2794 -0.1778)
							(mid -0.249642 -0.249642)
							(end -0.1778 -0.2794)
						)
						(arc
							(start 0.1778 -0.2794)
							(mid 0.249642 -0.249642)
							(end 0.2794 -0.1778)
						)
						(arc
							(start 0.2794 0.1778)
							(mid 0.249642 0.249642)
							(end 0.1778 0.2794)
						)
					)
					(width 0)
					(fill yes)
				)
			)
		)
	)
	(footprint ""
		(layer "B.Cu")
		(at 55.790592 -146.507454)
		(property "Reference" "TP81"
			(at 0 0 0)
			(layer "B.SilkS")
			(hide yes)
			(effects
				(font
					(size 1.27 1.27)
				)
				(justify mirror)
			)
		)
		(property "Value" "TPAD28-2-GP"
			(at 0.0127 -1.6637 0)
			(unlocked yes)
			(layer "B.Fab")
			(hide yes)
			(effects
				(font
					(size 1.016 1.016)
					(thickness 0.1524)
				)
				(justify mirror)
			)
		)
		(property "Device Type" "TPAD28"
			(at 0.0127 -3.1877 0)
			(unlocked yes)
			(layer "B.Fab")
			(hide yes)
			(effects
				(font
					(size 1.016 1.016)
					(thickness 0.1524)
				)
				(justify mirror)
			)
		)
		(duplicate_pad_numbers_are_jumpers no)
		(fp_poly
			(pts
				(arc
					(start 0.3556 0)
					(mid -0.3556 0)
					(end 0.3556 0)
				)
			)
			(stroke
				(width 0)
				(type default)
			)
			(fill no)
			(layer "B.CrtYd")
		)
		(fp_poly
			(pts
				(arc
					(start 0.6096 0)
					(mid -0.6096 0)
					(end 0.6096 0)
				)
			)
			(stroke
				(width 0)
				(type default)
			)
			(fill no)
			(layer "B.Fab")
		)
		(pad "1" smd circle
			(at 0 0 180)
			(size 0.7112 0.7112)
			(layers "B.Cu" "B.Mask" "B.Paste")
			(net "JTAG_BMC_TCK")
		)
	)
	(footprint ""
		(layer "B.Cu")
		(at 16.6116 -139.1412 180)
		(property "Reference" "C68"
			(at 0 0 0)
			(layer "B.SilkS")
			(hide yes)
			(effects
				(font
					(size 1.27 1.27)
				)
				(justify mirror)
			)
		)
		(property "Value" "SCD1U16V2KX-3GP"
			(at -1.1811 -2.7051 180)
			(unlocked yes)
			(layer "B.Fab")
			(hide yes)
			(effects
				(font
					(size 1.016 1.016)
					(thickness 0.1524)
				)
				(justify mirror)
			)
		)
		(property "Device Type" "C402H22"
			(at -1.1811 -4.2291 180)
			(unlocked yes)
			(layer "B.Fab")
			(hide yes)
			(effects
				(font
					(size 1.016 1.016)
					(thickness 0.1524)
				)
				(justify mirror)
			)
		)
		(duplicate_pad_numbers_are_jumpers no)
		(fp_rect
			(start 0.4318 0.9525)
			(end -0.4318 -0.9525)
			(stroke
				(width 0)
				(type default)
			)
			(fill no)
			(layer "B.CrtYd")
		)
		(fp_rect
			(start 0.4318 0.9525)
			(end -0.4318 -0.9525)
			(stroke
				(width 0)
				(type default)
			)
			(fill no)
			(layer "B.Fab")
		)
		(pad "1" smd custom
			(at 0 -0.4445)
			(size 0.1524 0.1524)
			(layers "B.Cu" "B.Mask" "B.Paste")
			(net "GND")
			(options
				(clearance outline)
				(anchor circle)
			)
			(primitives
				(gr_poly
					(pts
						(arc
							(start 0.3048 0.2032)
							(mid 0.275042 0.275042)
							(end 0.2032 0.3048)
						)
						(arc
							(start -0.2032 0.3048)
							(mid -0.275042 0.275042)
							(end -0.3048 0.2032)
						)
						(arc
							(start -0.3048 -0.2032)
							(mid -0.275042 -0.275042)
							(end -0.2032 -0.3048)
						)
						(arc
							(start 0.2032 -0.3048)
							(mid 0.275042 -0.275042)
							(end 0.3048 -0.2032)
						)
					)
					(width 0)
					(fill yes)
				)
			)
		)
		(pad "2" smd custom
			(at 0 0.4445)
			(size 0.1524 0.1524)
			(layers "B.Cu" "B.Mask" "B.Paste")
			(net "DDR_VREF")
			(options
				(clearance outline)
				(anchor circle)
			)
			(primitives
				(gr_poly
					(pts
						(arc
							(start 0.3048 0.2032)
							(mid 0.275042 0.275042)
							(end 0.2032 0.3048)
						)
						(arc
							(start -0.2032 0.3048)
							(mid -0.275042 0.275042)
							(end -0.3048 0.2032)
						)
						(arc
							(start -0.3048 -0.2032)
							(mid -0.275042 -0.275042)
							(end -0.2032 -0.3048)
						)
						(arc
							(start 0.2032 -0.3048)
							(mid 0.275042 -0.275042)
							(end 0.3048 -0.2032)
						)
					)
					(width 0)
					(fill yes)
				)
			)
		)
	)
	(footprint ""
		(layer "B.Cu")
		(at 180.175408 -66.547746 -90)
		(property "Reference" "R573"
			(at 0 0 90)
			(layer "B.SilkS")
			(hide yes)
			(effects
				(font
					(size 1.27 1.27)
				)
				(justify mirror)
			)
		)
		(property "Value" "10KR2F-2-GP"
			(at -0.064008 -3.993896 270)
			(unlocked yes)
			(layer "B.Fab")
			(hide yes)
			(effects
				(font
					(size 1.016 1.016)
					(thickness 0.1524)
				)
				(justify mirror)
			)
		)
		(property "Device Type" "R402H16"
			(at -0.064008 -5.517896 270)
			(unlocked yes)
			(layer "B.Fab")
			(hide yes)
			(effects
				(font
					(size 1.016 1.016)
					(thickness 0.1524)
				)
				(justify mirror)
			)
		)
		(duplicate_pad_numbers_are_jumpers no)
		(fp_line
			(start -0.508 -0.9398)
			(end 0.508 -0.9398)
			(stroke
				(width 0.1524)
				(type default)
			)
			(layer "B.SilkS")
		)
		(fp_line
			(start 0.508 -0.9398)
			(end 0.508 0.9398)
			(stroke
				(width 0.1524)
				(type default)
			)
			(layer "B.SilkS")
		)
		(fp_rect
			(start 0.508 0.9398)
			(end -0.508 -0.9398)
			(stroke
				(width 0)
				(type default)
			)
			(fill no)
			(layer "B.CrtYd")
		)
		(fp_rect
			(start 0.508 0.9398)
			(end -0.508 -0.9398)
			(stroke
				(width 0)
				(type default)
			)
			(fill no)
			(layer "B.Fab")
		)
		(pad "1" smd custom
			(at 0 -0.4445 90)
			(size 0.1397 0.1397)
			(layers "B.Cu" "B.Mask" "B.Paste")
			(net "IOC_CLK_SEL1")
			(options
				(clearance outline)
				(anchor circle)
			)
			(primitives
				(gr_poly
					(pts
						(arc
							(start -0.1778 0.2794)
							(mid -0.249642 0.249642)
							(end -0.2794 0.1778)
						)
						(arc
							(start -0.2794 -0.1778)
							(mid -0.249642 -0.249642)
							(end -0.1778 -0.2794)
						)
						(arc
							(start 0.1778 -0.2794)
							(mid 0.249642 -0.249642)
							(end 0.2794 -0.1778)
						)
						(arc
							(start 0.2794 0.1778)
							(mid 0.249642 0.249642)
							(end 0.1778 0.2794)
						)
					)
					(width 0)
					(fill yes)
				)
			)
		)
		(pad "2" smd custom
			(at 0 0.4445 90)
			(size 0.1397 0.1397)
			(layers "B.Cu" "B.Mask" "B.Paste")
			(net "P1V8")
			(options
				(clearance outline)
				(anchor circle)
			)
			(primitives
				(gr_poly
					(pts
						(arc
							(start -0.1778 0.2794)
							(mid -0.249642 0.249642)
							(end -0.2794 0.1778)
						)
						(arc
							(start -0.2794 -0.1778)
							(mid -0.249642 -0.249642)
							(end -0.1778 -0.2794)
						)
						(arc
							(start 0.1778 -0.2794)
							(mid 0.249642 -0.249642)
							(end 0.2794 -0.1778)
						)
						(arc
							(start 0.2794 0.1778)
							(mid 0.249642 0.249642)
							(end 0.1778 0.2794)
						)
					)
					(width 0)
					(fill yes)
				)
			)
		)
	)
	(footprint ""
		(layer "B.Cu")
		(at 124.841 -9.779 -90)
		(property "Reference" "R437"
			(at 0 0 90)
			(layer "B.SilkS")
			(hide yes)
			(effects
				(font
					(size 1.27 1.27)
				)
				(justify mirror)
			)
		)
		(property "Value" "100KR2F-L1-GP"
			(at -0.064008 -3.993896 270)
			(unlocked yes)
			(layer "B.Fab")
			(hide yes)
			(effects
				(font
					(size 1.016 1.016)
					(thickness 0.1524)
				)
				(justify mirror)
			)
		)
		(property "Device Type" "R402H16"
			(at -0.064008 -5.517896 270)
			(unlocked yes)
			(layer "B.Fab")
			(hide yes)
			(effects
				(font
					(size 1.016 1.016)
					(thickness 0.1524)
				)
				(justify mirror)
			)
		)
		(duplicate_pad_numbers_are_jumpers no)
		(fp_line
			(start -0.508 -0.9398)
			(end 0.508 -0.9398)
			(stroke
				(width 0.1524)
				(type default)
			)
			(layer "B.SilkS")
		)
		(fp_line
			(start 0.508 -0.9398)
			(end 0.508 0.9398)
			(stroke
				(width 0.1524)
				(type default)
			)
			(layer "B.SilkS")
		)
		(fp_rect
			(start 0.508 0.9398)
			(end -0.508 -0.9398)
			(stroke
				(width 0)
				(type default)
			)
			(fill no)
			(layer "B.CrtYd")
		)
		(fp_rect
			(start 0.508 0.9398)
			(end -0.508 -0.9398)
			(stroke
				(width 0)
				(type default)
			)
			(fill no)
			(layer "B.Fab")
		)
		(pad "1" smd custom
			(at 0 -0.4445 90)
			(size 0.1397 0.1397)
			(layers "B.Cu" "B.Mask" "B.Paste")
			(net "P12V_STBY")
			(options
				(clearance outline)
				(anchor circle)
			)
			(primitives
				(gr_poly
					(pts
						(arc
							(start -0.1778 0.2794)
							(mid -0.249642 0.249642)
							(end -0.2794 0.1778)
						)
						(arc
							(start -0.2794 -0.1778)
							(mid -0.249642 -0.249642)
							(end -0.1778 -0.2794)
						)
						(arc
							(start 0.1778 -0.2794)
							(mid 0.249642 -0.249642)
							(end 0.2794 -0.1778)
						)
						(arc
							(start 0.2794 0.1778)
							(mid 0.249642 0.249642)
							(end 0.1778 0.2794)
						)
					)
					(width 0)
					(fill yes)
				)
			)
		)
		(pad "2" smd custom
			(at 0 0.4445 90)
			(size 0.1397 0.1397)
			(layers "B.Cu" "B.Mask" "B.Paste")
			(net "MB0_P12V_PWGIN_R")
			(options
				(clearance outline)
				(anchor circle)
			)
			(primitives
				(gr_poly
					(pts
						(arc
							(start -0.1778 0.2794)
							(mid -0.249642 0.249642)
							(end -0.2794 0.1778)
						)
						(arc
							(start -0.2794 -0.1778)
							(mid -0.249642 -0.249642)
							(end -0.1778 -0.2794)
						)
						(arc
							(start 0.1778 -0.2794)
							(mid 0.249642 -0.249642)
							(end 0.2794 -0.1778)
						)
						(arc
							(start 0.2794 0.1778)
							(mid 0.249642 0.249642)
							(end 0.1778 0.2794)
						)
					)
					(width 0)
					(fill yes)
				)
			)
		)
	)
	(footprint ""
		(layer "B.Cu")
		(at 50.772568 -127.335788 180)
		(property "Reference" "R294"
			(at 0 0 0)
			(layer "B.SilkS")
			(hide yes)
			(effects
				(font
					(size 1.27 1.27)
				)
				(justify mirror)
			)
		)
		(property "Value" "0R2J-2-GP"
			(at -0.064008 -3.993896 180)
			(unlocked yes)
			(layer "B.Fab")
			(hide yes)
			(effects
				(font
					(size 1.016 1.016)
					(thickness 0.1524)
				)
				(justify mirror)
			)
		)
		(property "Device Type" "R402H16"
			(at -0.064008 -5.517896 180)
			(unlocked yes)
			(layer "B.Fab")
			(hide yes)
			(effects
				(font
					(size 1.016 1.016)
					(thickness 0.1524)
				)
				(justify mirror)
			)
		)
		(duplicate_pad_numbers_are_jumpers no)
		(fp_line
			(start 0.508 -0.9398)
			(end 0.508 0.9398)
			(stroke
				(width 0.1524)
				(type default)
			)
			(layer "B.SilkS")
		)
		(fp_line
			(start -0.508 -0.9398)
			(end 0.508 -0.9398)
			(stroke
				(width 0.1524)
				(type default)
			)
			(layer "B.SilkS")
		)
		(fp_rect
			(start 0.508 0.9398)
			(end -0.508 -0.9398)
			(stroke
				(width 0)
				(type default)
			)
			(fill no)
			(layer "B.CrtYd")
		)
		(fp_rect
			(start 0.508 0.9398)
			(end -0.508 -0.9398)
			(stroke
				(width 0)
				(type default)
			)
			(fill no)
			(layer "B.Fab")
		)
		(pad "1" smd custom
			(at 0 -0.4445)
			(size 0.1397 0.1397)
			(layers "B.Cu" "B.Mask" "B.Paste")
			(net "P12V_A_PGOOD")
			(options
				(clearance outline)
				(anchor circle)
			)
			(primitives
				(gr_poly
					(pts
						(arc
							(start -0.1778 0.2794)
							(mid -0.249642 0.249642)
							(end -0.2794 0.1778)
						)
						(arc
							(start -0.2794 -0.1778)
							(mid -0.249642 -0.249642)
							(end -0.1778 -0.2794)
						)
						(arc
							(start 0.1778 -0.2794)
							(mid 0.249642 -0.249642)
							(end 0.2794 -0.1778)
						)
						(arc
							(start 0.2794 0.1778)
							(mid 0.249642 0.249642)
							(end 0.1778 0.2794)
						)
					)
					(width 0)
					(fill yes)
				)
			)
		)
		(pad "2" smd custom
			(at 0 0.4445)
			(size 0.1397 0.1397)
			(layers "B.Cu" "B.Mask" "B.Paste")
			(net "P12V_A_PGOOD_R")
			(options
				(clearance outline)
				(anchor circle)
			)
			(primitives
				(gr_poly
					(pts
						(arc
							(start -0.1778 0.2794)
							(mid -0.249642 0.249642)
							(end -0.2794 0.1778)
						)
						(arc
							(start -0.2794 -0.1778)
							(mid -0.249642 -0.249642)
							(end -0.1778 -0.2794)
						)
						(arc
							(start 0.1778 -0.2794)
							(mid 0.249642 -0.249642)
							(end 0.2794 -0.1778)
						)
						(arc
							(start 0.2794 0.1778)
							(mid 0.249642 0.249642)
							(end 0.1778 0.2794)
						)
					)
					(width 0)
					(fill yes)
				)
			)
		)
	)
	(footprint ""
		(layer "B.Cu")
		(at 165.324536 -38.416738)
		(property "Reference" "C498"
			(at 0 0 0)
			(layer "B.SilkS")
			(hide yes)
			(effects
				(font
					(size 1.27 1.27)
				)
				(justify mirror)
			)
		)
		(property "Value" "SCD01U16V1KX-GP"
			(at 2.8321 -1.7399 0)
			(unlocked yes)
			(layer "B.Fab")
			(hide yes)
			(effects
				(font
					(size 1.016 1.016)
					(thickness 0.1524)
				)
				(justify mirror)
			)
		)
		(property "Device Type" "C0201H13"
			(at 2.8321 -3.2639 0)
			(unlocked yes)
			(layer "B.Fab")
			(hide yes)
			(effects
				(font
					(size 1.016 1.016)
					(thickness 0.1524)
				)
				(justify mirror)
			)
		)
		(duplicate_pad_numbers_are_jumpers no)
		(fp_rect
			(start 0.2794 0.6477)
			(end -0.2794 -0.6477)
			(stroke
				(width 0)
				(type default)
			)
			(fill no)
			(layer "B.CrtYd")
		)
		(fp_rect
			(start 0.2794 0.6477)
			(end -0.2794 -0.6477)
			(stroke
				(width 0)
				(type default)
			)
			(fill no)
			(layer "B.Fab")
		)
		(pad "1" smd custom
			(at 0 -0.2794 180)
			(size 0.0762 0.0762)
			(layers "B.Cu" "B.Mask" "B.Paste")
			(net "PHY_CON_B_TO_IOC_3_DP")
			(options
				(clearance outline)
				(anchor circle)
			)
			(primitives
				(gr_poly
					(pts
						(arc
							(start 0.1524 0.127)
							(mid 0.137521 0.162921)
							(end 0.1016 0.1778)
						)
						(arc
							(start -0.1016 0.1778)
							(mid -0.137521 0.162921)
							(end -0.1524 0.127)
						)
						(arc
							(start -0.1524 -0.127)
							(mid -0.137521 -0.162921)
							(end -0.1016 -0.1778)
						)
						(arc
							(start 0.1016 -0.1778)
							(mid 0.137521 -0.162921)
							(end 0.1524 -0.127)
						)
					)
					(width 0)
					(fill yes)
				)
			)
		)
		(pad "2" smd custom
			(at 0 0.2794 180)
			(size 0.0762 0.0762)
			(layers "B.Cu" "B.Mask" "B.Paste")
			(net "PHY_CON_B_TO_IOC_3_DP_C")
			(options
				(clearance outline)
				(anchor circle)
			)
			(primitives
				(gr_poly
					(pts
						(arc
							(start 0.1524 0.127)
							(mid 0.137521 0.162921)
							(end 0.1016 0.1778)
						)
						(arc
							(start -0.1016 0.1778)
							(mid -0.137521 0.162921)
							(end -0.1524 0.127)
						)
						(arc
							(start -0.1524 -0.127)
							(mid -0.137521 -0.162921)
							(end -0.1016 -0.1778)
						)
						(arc
							(start 0.1016 -0.1778)
							(mid 0.137521 -0.162921)
							(end 0.1524 -0.127)
						)
					)
					(width 0)
					(fill yes)
				)
			)
		)
	)
	(footprint ""
		(layer "B.Cu")
		(at 97.94748 -180.0098 90)
		(property "Reference" "U16"
			(at 0 0 90)
			(layer "B.SilkS")
			(hide yes)
			(effects
				(font
					(size 1.27 1.27)
				)
				(justify mirror)
			)
		)
		(property "Value" "NX3L1G66GW-GP"
			(at 2.3368 -8.6868 90)
			(unlocked yes)
			(layer "B.Fab")
			(hide yes)
			(effects
				(font
					(size 1.016 1.016)
					(thickness 0.1524)
				)
				(justify mirror)
			)
		)
		(property "Device Type" "SC70-5H44"
			(at 2.3114 -10.414 90)
			(unlocked yes)
			(layer "B.Fab")
			(hide yes)
			(effects
				(font
					(size 1.016 1.016)
					(thickness 0.1524)
				)
				(justify mirror)
			)
		)
		(duplicate_pad_numbers_are_jumpers no)
		(fp_line
			(start -0.6604 -1.8034)
			(end -1.3843 -1.8034)
			(stroke
				(width 0.3302)
				(type default)
			)
			(layer "B.SilkS")
		)
		(fp_line
			(start -1.3843 -1.8034)
			(end -1.3843 -1.1176)
			(stroke
				(width 0.3302)
				(type default)
			)
			(layer "B.SilkS")
		)
		(fp_line
			(start 1.27 -1.7018)
			(end -1.27 -1.7018)
			(stroke
				(width 0.1524)
				(type default)
			)
			(layer "B.SilkS")
		)
		(fp_line
			(start -1.27 -1.7018)
			(end -1.27 1.7018)
			(stroke
				(width 0.1524)
				(type default)
			)
			(layer "B.SilkS")
		)
		(fp_line
			(start 1.27 1.7018)
			(end 1.27 -1.7018)
			(stroke
				(width 0.1524)
				(type default)
			)
			(layer "B.SilkS")
		)
		(fp_line
			(start -1.27 1.7018)
			(end 1.27 1.7018)
			(stroke
				(width 0.1524)
				(type default)
			)
			(layer "B.SilkS")
		)
		(fp_rect
			(start 1.524 1.9558)
			(end -1.524 -1.9558)
			(stroke
				(width 0)
				(type default)
			)
			(fill no)
			(layer "B.CrtYd")
		)
		(fp_poly
			(pts
				(xy 1.524 -1.9558) (xy -1.524 -1.9558) (xy -1.524 1.9558) (xy 1.524 1.9558)
			)
			(stroke
				(width 0)
				(type default)
			)
			(fill no)
			(layer "B.Fab")
		)
		(pad "1" smd rect
			(at -0.65024 -0.8255 270)
			(size 0.4064 1.2192)
			(layers "B.Cu" "B.Mask" "B.Paste")
			(net "I2C_BMC_COMP_ALERT_N_R")
		)
		(pad "2" smd rect
			(at 0 -0.8255 270)
			(size 0.4064 1.2192)
			(layers "B.Cu" "B.Mask" "B.Paste")
			(net "I2C_COMP_ALERT_N")
		)
		(pad "3" smd rect
			(at 0.65024 -0.8255 270)
			(size 0.4064 1.2192)
			(layers "B.Cu" "B.Mask" "B.Paste")
			(net "GND")
		)
		(pad "4" smd rect
			(at 0.65024 0.8255 270)
			(size 0.4064 1.2192)
			(layers "B.Cu" "B.Mask" "B.Paste")
			(net "COMP_PWR_EN")
		)
		(pad "5" smd rect
			(at -0.65024 0.8255 270)
			(size 0.4064 1.2192)
			(layers "B.Cu" "B.Mask" "B.Paste")
			(net "P3V3_STBY")
		)
	)
	(footprint ""
		(layer "B.Cu")
		(at 44.141898 -149.135338 90)
		(property "Reference" "R143"
			(at 0 0 90)
			(layer "B.SilkS")
			(hide yes)
			(effects
				(font
					(size 1.27 1.27)
				)
				(justify mirror)
			)
		)
		(property "Value" "1KR2D-1-GP"
			(at -0.064008 -3.993896 90)
			(unlocked yes)
			(layer "B.Fab")
			(hide yes)
			(effects
				(font
					(size 1.016 1.016)
					(thickness 0.1524)
				)
				(justify mirror)
			)
		)
		(property "Device Type" "R402H16"
			(at -0.064008 -5.517896 90)
			(unlocked yes)
			(layer "B.Fab")
			(hide yes)
			(effects
				(font
					(size 1.016 1.016)
					(thickness 0.1524)
				)
				(justify mirror)
			)
		)
		(duplicate_pad_numbers_are_jumpers no)
		(fp_line
			(start 0.508 -0.9398)
			(end 0.508 0.9398)
			(stroke
				(width 0.1524)
				(type default)
			)
			(layer "B.SilkS")
		)
		(fp_line
			(start -0.508 -0.9398)
			(end 0.508 -0.9398)
			(stroke
				(width 0.1524)
				(type default)
			)
			(layer "B.SilkS")
		)
		(fp_rect
			(start 0.508 0.9398)
			(end -0.508 -0.9398)
			(stroke
				(width 0)
				(type default)
			)
			(fill no)
			(layer "B.CrtYd")
		)
		(fp_rect
			(start 0.508 0.9398)
			(end -0.508 -0.9398)
			(stroke
				(width 0)
				(type default)
			)
			(fill no)
			(layer "B.Fab")
		)
		(pad "1" smd custom
			(at 0 -0.4445 270)
			(size 0.1397 0.1397)
			(layers "B.Cu" "B.Mask" "B.Paste")
			(net "DDR_VREF")
			(options
				(clearance outline)
				(anchor circle)
			)
			(primitives
				(gr_poly
					(pts
						(arc
							(start -0.1778 0.2794)
							(mid -0.249642 0.249642)
							(end -0.2794 0.1778)
						)
						(arc
							(start -0.2794 -0.1778)
							(mid -0.249642 -0.249642)
							(end -0.1778 -0.2794)
						)
						(arc
							(start 0.1778 -0.2794)
							(mid 0.249642 -0.249642)
							(end 0.2794 -0.1778)
						)
						(arc
							(start 0.2794 0.1778)
							(mid 0.249642 0.249642)
							(end 0.1778 0.2794)
						)
					)
					(width 0)
					(fill yes)
				)
			)
		)
		(pad "2" smd custom
			(at 0 0.4445 270)
			(size 0.1397 0.1397)
			(layers "B.Cu" "B.Mask" "B.Paste")
			(net "GND")
			(options
				(clearance outline)
				(anchor circle)
			)
			(primitives
				(gr_poly
					(pts
						(arc
							(start -0.1778 0.2794)
							(mid -0.249642 0.249642)
							(end -0.2794 0.1778)
						)
						(arc
							(start -0.2794 -0.1778)
							(mid -0.249642 -0.249642)
							(end -0.1778 -0.2794)
						)
						(arc
							(start 0.1778 -0.2794)
							(mid 0.249642 -0.249642)
							(end 0.2794 -0.1778)
						)
						(arc
							(start 0.2794 0.1778)
							(mid 0.249642 0.249642)
							(end 0.1778 0.2794)
						)
					)
					(width 0)
					(fill yes)
				)
			)
		)
	)
	(footprint ""
		(layer "B.Cu")
		(at 62.2808 -175.2854 180)
		(property "Reference" "C33"
			(at 0 0 0)
			(layer "B.SilkS")
			(hide yes)
			(effects
				(font
					(size 1.27 1.27)
				)
				(justify mirror)
			)
		)
		(property "Value" "SCD1U16V2KX-3GP"
			(at -1.1811 -2.7051 180)
			(unlocked yes)
			(layer "B.Fab")
			(hide yes)
			(effects
				(font
					(size 1.016 1.016)
					(thickness 0.1524)
				)
				(justify mirror)
			)
		)
		(property "Device Type" "C402H22"
			(at -1.1811 -4.2291 180)
			(unlocked yes)
			(layer "B.Fab")
			(hide yes)
			(effects
				(font
					(size 1.016 1.016)
					(thickness 0.1524)
				)
				(justify mirror)
			)
		)
		(duplicate_pad_numbers_are_jumpers no)
		(fp_rect
			(start 0.4318 0.9525)
			(end -0.4318 -0.9525)
			(stroke
				(width 0)
				(type default)
			)
			(fill no)
			(layer "B.CrtYd")
		)
		(fp_rect
			(start 0.4318 0.9525)
			(end -0.4318 -0.9525)
			(stroke
				(width 0)
				(type default)
			)
			(fill no)
			(layer "B.Fab")
		)
		(pad "1" smd custom
			(at 0 -0.4445)
			(size 0.1524 0.1524)
			(layers "B.Cu" "B.Mask" "B.Paste")
			(net "P3V3_STBY")
			(options
				(clearance outline)
				(anchor circle)
			)
			(primitives
				(gr_poly
					(pts
						(arc
							(start 0.3048 0.2032)
							(mid 0.275042 0.275042)
							(end 0.2032 0.3048)
						)
						(arc
							(start -0.2032 0.3048)
							(mid -0.275042 0.275042)
							(end -0.3048 0.2032)
						)
						(arc
							(start -0.3048 -0.2032)
							(mid -0.275042 -0.275042)
							(end -0.2032 -0.3048)
						)
						(arc
							(start 0.2032 -0.3048)
							(mid 0.275042 -0.275042)
							(end 0.3048 -0.2032)
						)
					)
					(width 0)
					(fill yes)
				)
			)
		)
		(pad "2" smd custom
			(at 0 0.4445)
			(size 0.1524 0.1524)
			(layers "B.Cu" "B.Mask" "B.Paste")
			(net "GND")
			(options
				(clearance outline)
				(anchor circle)
			)
			(primitives
				(gr_poly
					(pts
						(arc
							(start 0.3048 0.2032)
							(mid 0.275042 0.275042)
							(end 0.2032 0.3048)
						)
						(arc
							(start -0.2032 0.3048)
							(mid -0.275042 0.275042)
							(end -0.3048 0.2032)
						)
						(arc
							(start -0.3048 -0.2032)
							(mid -0.275042 -0.275042)
							(end -0.2032 -0.3048)
						)
						(arc
							(start 0.2032 -0.3048)
							(mid 0.275042 -0.275042)
							(end 0.3048 -0.2032)
						)
					)
					(width 0)
					(fill yes)
				)
			)
		)
	)
	(footprint ""
		(layer "B.Cu")
		(at 38.0238 -182.6768 180)
		(property "Reference" "R484"
			(at 0 0 0)
			(layer "B.SilkS")
			(hide yes)
			(effects
				(font
					(size 1.27 1.27)
				)
				(justify mirror)
			)
		)
		(property "Value" "3D01R5F-GP"
			(at 0 -8.9535 180)
			(unlocked yes)
			(layer "B.Fab")
			(hide yes)
			(effects
				(font
					(size 1.27 1.016)
					(thickness 0.1524)
				)
				(justify mirror)
			)
		)
		(property "Device Type" "R805H24"
			(at 0 -10.6299 180)
			(unlocked yes)
			(layer "B.Fab")
			(hide yes)
			(effects
				(font
					(size 1.27 1.016)
					(thickness 0.1524)
				)
				(justify mirror)
			)
		)
		(duplicate_pad_numbers_are_jumpers no)
		(fp_line
			(start 0.889 1.7018)
			(end -0.889 1.7018)
			(stroke
				(width 0.1524)
				(type default)
			)
			(layer "B.SilkS")
		)
		(fp_line
			(start 0.889 0.0762)
			(end 0.889 1.7018)
			(stroke
				(width 0.1524)
				(type default)
			)
			(layer "B.SilkS")
		)
		(fp_line
			(start 0.889 -1.7018)
			(end 0.889 0.2794)
			(stroke
				(width 0.1524)
				(type default)
			)
			(layer "B.SilkS")
		)
		(fp_line
			(start -0.889 1.7018)
			(end -0.889 -0.508)
			(stroke
				(width 0.1524)
				(type default)
			)
			(layer "B.SilkS")
		)
		(fp_line
			(start -0.889 -1.7018)
			(end 0.889 -1.7018)
			(stroke
				(width 0.1524)
				(type default)
			)
			(layer "B.SilkS")
		)
		(fp_line
			(start -0.889 -1.7018)
			(end -0.889 -0.381)
			(stroke
				(width 0.1524)
				(type default)
			)
			(layer "B.SilkS")
		)
		(fp_poly
			(pts
				(xy -0.9652 -1.778) (xy -0.9652 1.778) (xy 0.9652 1.778) (xy 0.9652 -1.778)
			)
			(stroke
				(width 0)
				(type default)
			)
			(fill no)
			(layer "B.CrtYd")
		)
		(fp_rect
			(start 0.9652 1.778)
			(end -0.9652 -1.778)
			(stroke
				(width 0)
				(type default)
			)
			(fill no)
			(layer "B.Fab")
		)
		(pad "1" smd rect
			(at 0 -0.9652)
			(size 1.397 1.143)
			(layers "B.Cu" "B.Mask" "B.Paste")
			(net "P3V3_VBST")
		)
		(pad "2" smd rect
			(at 0 0.9652)
			(size 1.397 1.143)
			(layers "B.Cu" "B.Mask" "B.Paste")
			(net "P3V3_VBST_RC")
		)
	)
	(footprint ""
		(layer "B.Cu")
		(at 192.8876 -51.8922 -90)
		(property "Reference" "C333"
			(at 0 0 90)
			(layer "B.SilkS")
			(hide yes)
			(effects
				(font
					(size 1.27 1.27)
				)
				(justify mirror)
			)
		)
		(property "Value" "SCD1U6D3V1KX-GP"
			(at 2.8321 -1.7399 270)
			(unlocked yes)
			(layer "B.Fab")
			(hide yes)
			(effects
				(font
					(size 1.016 1.016)
					(thickness 0.1524)
				)
				(justify mirror)
			)
		)
		(property "Device Type" "C0201H13"
			(at 2.8321 -3.2639 270)
			(unlocked yes)
			(layer "B.Fab")
			(hide yes)
			(effects
				(font
					(size 1.016 1.016)
					(thickness 0.1524)
				)
				(justify mirror)
			)
		)
		(duplicate_pad_numbers_are_jumpers no)
		(fp_rect
			(start 0.2794 0.6477)
			(end -0.2794 -0.6477)
			(stroke
				(width 0)
				(type default)
			)
			(fill no)
			(layer "B.CrtYd")
		)
		(fp_rect
			(start 0.2794 0.6477)
			(end -0.2794 -0.6477)
			(stroke
				(width 0)
				(type default)
			)
			(fill no)
			(layer "B.Fab")
		)
		(pad "1" smd custom
			(at 0 -0.2794 90)
			(size 0.0762 0.0762)
			(layers "B.Cu" "B.Mask" "B.Paste")
			(net "HM40ADC_VDDA")
			(options
				(clearance outline)
				(anchor circle)
			)
			(primitives
				(gr_poly
					(pts
						(arc
							(start 0.1524 0.127)
							(mid 0.137521 0.162921)
							(end 0.1016 0.1778)
						)
						(arc
							(start -0.1016 0.1778)
							(mid -0.137521 0.162921)
							(end -0.1524 0.127)
						)
						(arc
							(start -0.1524 -0.127)
							(mid -0.137521 -0.162921)
							(end -0.1016 -0.1778)
						)
						(arc
							(start 0.1016 -0.1778)
							(mid 0.137521 -0.162921)
							(end 0.1524 -0.127)
						)
					)
					(width 0)
					(fill yes)
				)
			)
		)
		(pad "2" smd custom
			(at 0 0.2794 90)
			(size 0.0762 0.0762)
			(layers "B.Cu" "B.Mask" "B.Paste")
			(net "GND")
			(options
				(clearance outline)
				(anchor circle)
			)
			(primitives
				(gr_poly
					(pts
						(arc
							(start 0.1524 0.127)
							(mid 0.137521 0.162921)
							(end 0.1016 0.1778)
						)
						(arc
							(start -0.1016 0.1778)
							(mid -0.137521 0.162921)
							(end -0.1524 0.127)
						)
						(arc
							(start -0.1524 -0.127)
							(mid -0.137521 -0.162921)
							(end -0.1016 -0.1778)
						)
						(arc
							(start 0.1016 -0.1778)
							(mid 0.137521 -0.162921)
							(end 0.1524 -0.127)
						)
					)
					(width 0)
					(fill yes)
				)
			)
		)
	)
	(footprint ""
		(layer "B.Cu")
		(at 191.689736 -25.273 -90)
		(property "Reference" "C491"
			(at 0 0 90)
			(layer "B.SilkS")
			(hide yes)
			(effects
				(font
					(size 1.27 1.27)
				)
				(justify mirror)
			)
		)
		(property "Value" "SCD01U16V1KX-GP"
			(at 2.8321 -1.7399 270)
			(unlocked yes)
			(layer "B.Fab")
			(hide yes)
			(effects
				(font
					(size 1.016 1.016)
					(thickness 0.1524)
				)
				(justify mirror)
			)
		)
		(property "Device Type" "C0201H13"
			(at 2.8321 -3.2639 270)
			(unlocked yes)
			(layer "B.Fab")
			(hide yes)
			(effects
				(font
					(size 1.016 1.016)
					(thickness 0.1524)
				)
				(justify mirror)
			)
		)
		(duplicate_pad_numbers_are_jumpers no)
		(fp_rect
			(start 0.2794 0.6477)
			(end -0.2794 -0.6477)
			(stroke
				(width 0)
				(type default)
			)
			(fill no)
			(layer "B.CrtYd")
		)
		(fp_rect
			(start 0.2794 0.6477)
			(end -0.2794 -0.6477)
			(stroke
				(width 0)
				(type default)
			)
			(fill no)
			(layer "B.Fab")
		)
		(pad "1" smd custom
			(at 0 -0.2794 90)
			(size 0.0762 0.0762)
			(layers "B.Cu" "B.Mask" "B.Paste")
			(net "PHY_CON_A_TO_IOC_3_DN")
			(options
				(clearance outline)
				(anchor circle)
			)
			(primitives
				(gr_poly
					(pts
						(arc
							(start 0.1524 0.127)
							(mid 0.137521 0.162921)
							(end 0.1016 0.1778)
						)
						(arc
							(start -0.1016 0.1778)
							(mid -0.137521 0.162921)
							(end -0.1524 0.127)
						)
						(arc
							(start -0.1524 -0.127)
							(mid -0.137521 -0.162921)
							(end -0.1016 -0.1778)
						)
						(arc
							(start 0.1016 -0.1778)
							(mid 0.137521 -0.162921)
							(end 0.1524 -0.127)
						)
					)
					(width 0)
					(fill yes)
				)
			)
		)
		(pad "2" smd custom
			(at 0 0.2794 90)
			(size 0.0762 0.0762)
			(layers "B.Cu" "B.Mask" "B.Paste")
			(net "PHY_CON_A_TO_IOC_3_DN_C")
			(options
				(clearance outline)
				(anchor circle)
			)
			(primitives
				(gr_poly
					(pts
						(arc
							(start 0.1524 0.127)
							(mid 0.137521 0.162921)
							(end 0.1016 0.1778)
						)
						(arc
							(start -0.1016 0.1778)
							(mid -0.137521 0.162921)
							(end -0.1524 0.127)
						)
						(arc
							(start -0.1524 -0.127)
							(mid -0.137521 -0.162921)
							(end -0.1016 -0.1778)
						)
						(arc
							(start 0.1016 -0.1778)
							(mid 0.137521 -0.162921)
							(end 0.1524 -0.127)
						)
					)
					(width 0)
					(fill yes)
				)
			)
		)
	)
	(footprint ""
		(layer "B.Cu")
		(at 179.452524 -152.475946 180)
		(property "Reference" "R466"
			(at 0 0 0)
			(layer "B.SilkS")
			(hide yes)
			(effects
				(font
					(size 1.27 1.27)
				)
				(justify mirror)
			)
		)
		(property "Value" "2D7R3-GP"
			(at 0.0254 -2.5146 180)
			(unlocked yes)
			(layer "B.Fab")
			(hide yes)
			(effects
				(font
					(size 1.016 1.016)
					(thickness 0.1524)
				)
				(justify mirror)
			)
		)
		(property "Device Type" "R603H22"
			(at 0.0254 -4.0386 180)
			(unlocked yes)
			(layer "B.Fab")
			(hide yes)
			(effects
				(font
					(size 1.016 1.016)
					(thickness 0.1524)
				)
				(justify mirror)
			)
		)
		(duplicate_pad_numbers_are_jumpers no)
		(fp_line
			(start 0.4826 0)
			(end 0.2032 0)
			(stroke
				(width 0.2032)
				(type default)
			)
			(layer "B.SilkS")
		)
		(fp_line
			(start -0.2032 0)
			(end -0.4826 0)
			(stroke
				(width 0.2032)
				(type default)
			)
			(layer "B.SilkS")
		)
		(fp_rect
			(start 0.5842 1.3335)
			(end -0.5842 -1.3335)
			(stroke
				(width 0)
				(type default)
			)
			(fill no)
			(layer "B.CrtYd")
		)
		(fp_rect
			(start 0.5842 1.3335)
			(end -0.5842 -1.3335)
			(stroke
				(width 0)
				(type default)
			)
			(fill no)
			(layer "B.Fab")
		)
		(pad "1" smd custom
			(at 0 -0.762)
			(size 0.2159 0.2159)
			(layers "B.Cu" "B.Mask" "B.Paste")
			(net "P5V_VBST")
			(options
				(clearance outline)
				(anchor circle)
			)
			(primitives
				(gr_poly
					(pts
						(arc
							(start -0.3302 0.4318)
							(mid -0.402042 0.402042)
							(end -0.4318 0.3302)
						)
						(arc
							(start -0.4318 -0.3302)
							(mid -0.402042 -0.402042)
							(end -0.3302 -0.4318)
						)
						(arc
							(start 0.3302 -0.4318)
							(mid 0.402042 -0.402042)
							(end 0.4318 -0.3302)
						)
						(arc
							(start 0.4318 0.3302)
							(mid 0.402042 0.402042)
							(end 0.3302 0.4318)
						)
					)
					(width 0)
					(fill yes)
				)
			)
		)
		(pad "2" smd custom
			(at 0 0.762)
			(size 0.2159 0.2159)
			(layers "B.Cu" "B.Mask" "B.Paste")
			(net "P5V_VBST_RC")
			(options
				(clearance outline)
				(anchor circle)
			)
			(primitives
				(gr_poly
					(pts
						(arc
							(start -0.3302 0.4318)
							(mid -0.402042 0.402042)
							(end -0.4318 0.3302)
						)
						(arc
							(start -0.4318 -0.3302)
							(mid -0.402042 -0.402042)
							(end -0.3302 -0.4318)
						)
						(arc
							(start 0.3302 -0.4318)
							(mid 0.402042 -0.402042)
							(end 0.4318 -0.3302)
						)
						(arc
							(start 0.4318 0.3302)
							(mid 0.402042 0.402042)
							(end 0.3302 0.4318)
						)
					)
					(width 0)
					(fill yes)
				)
			)
		)
	)
	(footprint ""
		(layer "B.Cu")
		(at 141.986 -16.4338 -90)
		(property "Reference" "C521"
			(at 0 0 90)
			(layer "B.SilkS")
			(hide yes)
			(effects
				(font
					(size 1.27 1.27)
				)
				(justify mirror)
			)
		)
		(property "Value" "SCD1U16V2KX-3GP"
			(at -1.1811 -2.7051 270)
			(unlocked yes)
			(layer "B.Fab")
			(hide yes)
			(effects
				(font
					(size 1.016 1.016)
					(thickness 0.1524)
				)
				(justify mirror)
			)
		)
		(property "Device Type" "C402H22"
			(at -1.1811 -4.2291 270)
			(unlocked yes)
			(layer "B.Fab")
			(hide yes)
			(effects
				(font
					(size 1.016 1.016)
					(thickness 0.1524)
				)
				(justify mirror)
			)
		)
		(duplicate_pad_numbers_are_jumpers no)
		(fp_rect
			(start 0.4318 0.9525)
			(end -0.4318 -0.9525)
			(stroke
				(width 0)
				(type default)
			)
			(fill no)
			(layer "B.CrtYd")
		)
		(fp_rect
			(start 0.4318 0.9525)
			(end -0.4318 -0.9525)
			(stroke
				(width 0)
				(type default)
			)
			(fill no)
			(layer "B.Fab")
		)
		(pad "1" smd custom
			(at 0 -0.4445 90)
			(size 0.1524 0.1524)
			(layers "B.Cu" "B.Mask" "B.Paste")
			(net "P1V8")
			(options
				(clearance outline)
				(anchor circle)
			)
			(primitives
				(gr_poly
					(pts
						(arc
							(start 0.3048 0.2032)
							(mid 0.275042 0.275042)
							(end 0.2032 0.3048)
						)
						(arc
							(start -0.2032 0.3048)
							(mid -0.275042 0.275042)
							(end -0.3048 0.2032)
						)
						(arc
							(start -0.3048 -0.2032)
							(mid -0.275042 -0.275042)
							(end -0.2032 -0.3048)
						)
						(arc
							(start 0.2032 -0.3048)
							(mid 0.275042 -0.275042)
							(end 0.3048 -0.2032)
						)
					)
					(width 0)
					(fill yes)
				)
			)
		)
		(pad "2" smd custom
			(at 0 0.4445 90)
			(size 0.1524 0.1524)
			(layers "B.Cu" "B.Mask" "B.Paste")
			(net "GND")
			(options
				(clearance outline)
				(anchor circle)
			)
			(primitives
				(gr_poly
					(pts
						(arc
							(start 0.3048 0.2032)
							(mid 0.275042 0.275042)
							(end 0.2032 0.3048)
						)
						(arc
							(start -0.2032 0.3048)
							(mid -0.275042 0.275042)
							(end -0.3048 0.2032)
						)
						(arc
							(start -0.3048 -0.2032)
							(mid -0.275042 -0.275042)
							(end -0.2032 -0.3048)
						)
						(arc
							(start 0.2032 -0.3048)
							(mid 0.275042 -0.275042)
							(end 0.3048 -0.2032)
						)
					)
					(width 0)
					(fill yes)
				)
			)
		)
	)
	(footprint ""
		(layer "B.Cu")
		(at 203.9874 -74.0918)
		(property "Reference" "C378"
			(at 0 0 0)
			(layer "B.SilkS")
			(hide yes)
			(effects
				(font
					(size 1.27 1.27)
				)
				(justify mirror)
			)
		)
		(property "Value" "SCD1U6D3V1KX-GP"
			(at 2.8321 -1.7399 0)
			(unlocked yes)
			(layer "B.Fab")
			(hide yes)
			(effects
				(font
					(size 1.016 1.016)
					(thickness 0.1524)
				)
				(justify mirror)
			)
		)
		(property "Device Type" "C0201H13"
			(at 2.8321 -3.2639 0)
			(unlocked yes)
			(layer "B.Fab")
			(hide yes)
			(effects
				(font
					(size 1.016 1.016)
					(thickness 0.1524)
				)
				(justify mirror)
			)
		)
		(duplicate_pad_numbers_are_jumpers no)
		(fp_rect
			(start 0.2794 0.6477)
			(end -0.2794 -0.6477)
			(stroke
				(width 0)
				(type default)
			)
			(fill no)
			(layer "B.CrtYd")
		)
		(fp_rect
			(start 0.2794 0.6477)
			(end -0.2794 -0.6477)
			(stroke
				(width 0)
				(type default)
			)
			(fill no)
			(layer "B.Fab")
		)
		(pad "1" smd custom
			(at 0 -0.2794 180)
			(size 0.0762 0.0762)
			(layers "B.Cu" "B.Mask" "B.Paste")
			(net "SAS0_AVDD")
			(options
				(clearance outline)
				(anchor circle)
			)
			(primitives
				(gr_poly
					(pts
						(arc
							(start 0.1524 0.127)
							(mid 0.137521 0.162921)
							(end 0.1016 0.1778)
						)
						(arc
							(start -0.1016 0.1778)
							(mid -0.137521 0.162921)
							(end -0.1524 0.127)
						)
						(arc
							(start -0.1524 -0.127)
							(mid -0.137521 -0.162921)
							(end -0.1016 -0.1778)
						)
						(arc
							(start 0.1016 -0.1778)
							(mid 0.137521 -0.162921)
							(end 0.1524 -0.127)
						)
					)
					(width 0)
					(fill yes)
				)
			)
		)
		(pad "2" smd custom
			(at 0 0.2794 180)
			(size 0.0762 0.0762)
			(layers "B.Cu" "B.Mask" "B.Paste")
			(net "GND")
			(options
				(clearance outline)
				(anchor circle)
			)
			(primitives
				(gr_poly
					(pts
						(arc
							(start 0.1524 0.127)
							(mid 0.137521 0.162921)
							(end 0.1016 0.1778)
						)
						(arc
							(start -0.1016 0.1778)
							(mid -0.137521 0.162921)
							(end -0.1524 0.127)
						)
						(arc
							(start -0.1524 -0.127)
							(mid -0.137521 -0.162921)
							(end -0.1016 -0.1778)
						)
						(arc
							(start 0.1016 -0.1778)
							(mid 0.137521 -0.162921)
							(end 0.1524 -0.127)
						)
					)
					(width 0)
					(fill yes)
				)
			)
		)
	)
	(footprint ""
		(layer "B.Cu")
		(at 187.9854 -124.405136 180)
		(property "Reference" "R559"
			(at 0 0 0)
			(layer "B.SilkS")
			(hide yes)
			(effects
				(font
					(size 1.27 1.27)
				)
				(justify mirror)
			)
		)
		(property "Value" "10KR2F-2-GP"
			(at -0.064008 -3.993896 180)
			(unlocked yes)
			(layer "B.Fab")
			(hide yes)
			(effects
				(font
					(size 1.016 1.016)
					(thickness 0.1524)
				)
				(justify mirror)
			)
		)
		(property "Device Type" "R402H16"
			(at -0.064008 -5.517896 180)
			(unlocked yes)
			(layer "B.Fab")
			(hide yes)
			(effects
				(font
					(size 1.016 1.016)
					(thickness 0.1524)
				)
				(justify mirror)
			)
		)
		(duplicate_pad_numbers_are_jumpers no)
		(fp_line
			(start 0.508 -0.9398)
			(end 0.508 0.9398)
			(stroke
				(width 0.1524)
				(type default)
			)
			(layer "B.SilkS")
		)
		(fp_line
			(start -0.508 -0.9398)
			(end 0.508 -0.9398)
			(stroke
				(width 0.1524)
				(type default)
			)
			(layer "B.SilkS")
		)
		(fp_rect
			(start 0.508 0.9398)
			(end -0.508 -0.9398)
			(stroke
				(width 0)
				(type default)
			)
			(fill no)
			(layer "B.CrtYd")
		)
		(fp_rect
			(start 0.508 0.9398)
			(end -0.508 -0.9398)
			(stroke
				(width 0)
				(type default)
			)
			(fill no)
			(layer "B.Fab")
		)
		(pad "1" smd custom
			(at 0 -0.4445)
			(size 0.1397 0.1397)
			(layers "B.Cu" "B.Mask" "B.Paste")
			(net "AGND_P0V975")
			(options
				(clearance outline)
				(anchor circle)
			)
			(primitives
				(gr_poly
					(pts
						(arc
							(start -0.1778 0.2794)
							(mid -0.249642 0.249642)
							(end -0.2794 0.1778)
						)
						(arc
							(start -0.2794 -0.1778)
							(mid -0.249642 -0.249642)
							(end -0.1778 -0.2794)
						)
						(arc
							(start 0.1778 -0.2794)
							(mid 0.249642 -0.249642)
							(end 0.2794 -0.1778)
						)
						(arc
							(start 0.2794 0.1778)
							(mid 0.249642 0.249642)
							(end 0.1778 0.2794)
						)
					)
					(width 0)
					(fill yes)
				)
			)
		)
		(pad "2" smd custom
			(at 0 0.4445)
			(size 0.1397 0.1397)
			(layers "B.Cu" "B.Mask" "B.Paste")
			(net "VT235_IMAX")
			(options
				(clearance outline)
				(anchor circle)
			)
			(primitives
				(gr_poly
					(pts
						(arc
							(start -0.1778 0.2794)
							(mid -0.249642 0.249642)
							(end -0.2794 0.1778)
						)
						(arc
							(start -0.2794 -0.1778)
							(mid -0.249642 -0.249642)
							(end -0.1778 -0.2794)
						)
						(arc
							(start 0.1778 -0.2794)
							(mid 0.249642 -0.249642)
							(end 0.2794 -0.1778)
						)
						(arc
							(start 0.2794 0.1778)
							(mid 0.249642 0.249642)
							(end 0.1778 0.2794)
						)
					)
					(width 0)
					(fill yes)
				)
			)
		)
	)
	(footprint ""
		(layer "B.Cu")
		(at 83.102196 -98.454972 180)
		(property "Reference" "R64"
			(at 0 0 0)
			(layer "B.SilkS")
			(hide yes)
			(effects
				(font
					(size 1.27 1.27)
				)
				(justify mirror)
			)
		)
		(property "Value" "10KR2F-2-GP"
			(at -0.064008 -3.993896 180)
			(unlocked yes)
			(layer "B.Fab")
			(hide yes)
			(effects
				(font
					(size 1.016 1.016)
					(thickness 0.1524)
				)
				(justify mirror)
			)
		)
		(property "Device Type" "R402H16"
			(at -0.064008 -5.517896 180)
			(unlocked yes)
			(layer "B.Fab")
			(hide yes)
			(effects
				(font
					(size 1.016 1.016)
					(thickness 0.1524)
				)
				(justify mirror)
			)
		)
		(duplicate_pad_numbers_are_jumpers no)
		(fp_line
			(start 0.508 -0.9398)
			(end 0.508 0.9398)
			(stroke
				(width 0.1524)
				(type default)
			)
			(layer "B.SilkS")
		)
		(fp_line
			(start -0.508 -0.9398)
			(end 0.508 -0.9398)
			(stroke
				(width 0.1524)
				(type default)
			)
			(layer "B.SilkS")
		)
		(fp_rect
			(start 0.508 0.9398)
			(end -0.508 -0.9398)
			(stroke
				(width 0)
				(type default)
			)
			(fill no)
			(layer "B.CrtYd")
		)
		(fp_rect
			(start 0.508 0.9398)
			(end -0.508 -0.9398)
			(stroke
				(width 0)
				(type default)
			)
			(fill no)
			(layer "B.Fab")
		)
		(pad "1" smd custom
			(at 0 -0.4445)
			(size 0.1397 0.1397)
			(layers "B.Cu" "B.Mask" "B.Paste")
			(net "P3V3_STBY")
			(options
				(clearance outline)
				(anchor circle)
			)
			(primitives
				(gr_poly
					(pts
						(arc
							(start -0.1778 0.2794)
							(mid -0.249642 0.249642)
							(end -0.2794 0.1778)
						)
						(arc
							(start -0.2794 -0.1778)
							(mid -0.249642 -0.249642)
							(end -0.1778 -0.2794)
						)
						(arc
							(start 0.1778 -0.2794)
							(mid 0.249642 -0.249642)
							(end 0.2794 -0.1778)
						)
						(arc
							(start 0.2794 0.1778)
							(mid 0.249642 0.249642)
							(end 0.1778 0.2794)
						)
					)
					(width 0)
					(fill yes)
				)
			)
		)
		(pad "2" smd custom
			(at 0 0.4445)
			(size 0.1397 0.1397)
			(layers "B.Cu" "B.Mask" "B.Paste")
			(net "MEZZ_A_PRSNT_120_N")
			(options
				(clearance outline)
				(anchor circle)
			)
			(primitives
				(gr_poly
					(pts
						(arc
							(start -0.1778 0.2794)
							(mid -0.249642 0.249642)
							(end -0.2794 0.1778)
						)
						(arc
							(start -0.2794 -0.1778)
							(mid -0.249642 -0.249642)
							(end -0.1778 -0.2794)
						)
						(arc
							(start 0.1778 -0.2794)
							(mid 0.249642 -0.249642)
							(end 0.2794 -0.1778)
						)
						(arc
							(start 0.2794 0.1778)
							(mid 0.249642 0.249642)
							(end 0.1778 0.2794)
						)
					)
					(width 0)
					(fill yes)
				)
			)
		)
	)
	(footprint ""
		(layer "B.Cu")
		(at 55.25008 -153.68778 90)
		(property "Reference" "C88"
			(at 0 0 90)
			(layer "B.SilkS")
			(hide yes)
			(effects
				(font
					(size 1.27 1.27)
				)
				(justify mirror)
			)
		)
		(property "Value" "SC100P50V2JN-3GP"
			(at -1.1811 -2.7051 90)
			(unlocked yes)
			(layer "B.Fab")
			(hide yes)
			(effects
				(font
					(size 1.016 1.016)
					(thickness 0.1524)
				)
				(justify mirror)
			)
		)
		(property "Device Type" "C402H22"
			(at -1.1811 -4.2291 90)
			(unlocked yes)
			(layer "B.Fab")
			(hide yes)
			(effects
				(font
					(size 1.016 1.016)
					(thickness 0.1524)
				)
				(justify mirror)
			)
		)
		(duplicate_pad_numbers_are_jumpers no)
		(fp_rect
			(start 0.4318 0.9525)
			(end -0.4318 -0.9525)
			(stroke
				(width 0)
				(type default)
			)
			(fill no)
			(layer "B.CrtYd")
		)
		(fp_rect
			(start 0.4318 0.9525)
			(end -0.4318 -0.9525)
			(stroke
				(width 0)
				(type default)
			)
			(fill no)
			(layer "B.Fab")
		)
		(pad "1" smd custom
			(at 0 -0.4445 270)
			(size 0.1524 0.1524)
			(layers "B.Cu" "B.Mask" "B.Paste")
			(net "ADCAV33")
			(options
				(clearance outline)
				(anchor circle)
			)
			(primitives
				(gr_poly
					(pts
						(arc
							(start 0.3048 0.2032)
							(mid 0.275042 0.275042)
							(end 0.2032 0.3048)
						)
						(arc
							(start -0.2032 0.3048)
							(mid -0.275042 0.275042)
							(end -0.3048 0.2032)
						)
						(arc
							(start -0.3048 -0.2032)
							(mid -0.275042 -0.275042)
							(end -0.2032 -0.3048)
						)
						(arc
							(start 0.2032 -0.3048)
							(mid 0.275042 -0.275042)
							(end 0.3048 -0.2032)
						)
					)
					(width 0)
					(fill yes)
				)
			)
		)
		(pad "2" smd custom
			(at 0 0.4445 270)
			(size 0.1524 0.1524)
			(layers "B.Cu" "B.Mask" "B.Paste")
			(net "GND")
			(options
				(clearance outline)
				(anchor circle)
			)
			(primitives
				(gr_poly
					(pts
						(arc
							(start 0.3048 0.2032)
							(mid 0.275042 0.275042)
							(end 0.2032 0.3048)
						)
						(arc
							(start -0.2032 0.3048)
							(mid -0.275042 0.275042)
							(end -0.3048 0.2032)
						)
						(arc
							(start -0.3048 -0.2032)
							(mid -0.275042 -0.275042)
							(end -0.2032 -0.3048)
						)
						(arc
							(start 0.2032 -0.3048)
							(mid 0.275042 -0.275042)
							(end 0.3048 -0.2032)
						)
					)
					(width 0)
					(fill yes)
				)
			)
		)
	)
	(footprint ""
		(layer "B.Cu")
		(at 188.9252 -70.7644)
		(property "Reference" "TP92"
			(at 0 0 0)
			(layer "B.SilkS")
			(hide yes)
			(effects
				(font
					(size 1.27 1.27)
				)
				(justify mirror)
			)
		)
		(property "Value" "TPAD28-2-GP"
			(at 0.0127 -1.6637 0)
			(unlocked yes)
			(layer "B.Fab")
			(hide yes)
			(effects
				(font
					(size 1.016 1.016)
					(thickness 0.1524)
				)
				(justify mirror)
			)
		)
		(property "Device Type" "TPAD28"
			(at 0.0127 -3.1877 0)
			(unlocked yes)
			(layer "B.Fab")
			(hide yes)
			(effects
				(font
					(size 1.016 1.016)
					(thickness 0.1524)
				)
				(justify mirror)
			)
		)
		(duplicate_pad_numbers_are_jumpers no)
		(fp_poly
			(pts
				(arc
					(start 0.3556 0)
					(mid -0.3556 0)
					(end 0.3556 0)
				)
			)
			(stroke
				(width 0)
				(type default)
			)
			(fill no)
			(layer "B.CrtYd")
		)
		(fp_poly
			(pts
				(arc
					(start 0.6096 0)
					(mid -0.6096 0)
					(end 0.6096 0)
				)
			)
			(stroke
				(width 0)
				(type default)
			)
			(fill no)
			(layer "B.Fab")
		)
		(pad "1" smd circle
			(at 0 0 180)
			(size 0.7112 0.7112)
			(layers "B.Cu" "B.Mask" "B.Paste")
			(net "IOC_GPIO_7")
		)
	)
	(footprint ""
		(layer "B.Cu")
		(at 54.23408 -124.7394 90)
		(property "Reference" "R702"
			(at 0 0 90)
			(layer "B.SilkS")
			(hide yes)
			(effects
				(font
					(size 1.27 1.27)
				)
				(justify mirror)
			)
		)
		(property "Value" "4K7R2F-GP"
			(at -0.064008 -3.993896 90)
			(unlocked yes)
			(layer "B.Fab")
			(hide yes)
			(effects
				(font
					(size 1.016 1.016)
					(thickness 0.1524)
				)
				(justify mirror)
			)
		)
		(property "Device Type" "R402H16"
			(at -0.064008 -5.517896 90)
			(unlocked yes)
			(layer "B.Fab")
			(hide yes)
			(effects
				(font
					(size 1.016 1.016)
					(thickness 0.1524)
				)
				(justify mirror)
			)
		)
		(duplicate_pad_numbers_are_jumpers no)
		(fp_line
			(start 0.508 -0.9398)
			(end 0.508 0.9398)
			(stroke
				(width 0.1524)
				(type default)
			)
			(layer "B.SilkS")
		)
		(fp_line
			(start -0.508 -0.9398)
			(end 0.508 -0.9398)
			(stroke
				(width 0.1524)
				(type default)
			)
			(layer "B.SilkS")
		)
		(fp_rect
			(start 0.508 0.9398)
			(end -0.508 -0.9398)
			(stroke
				(width 0)
				(type default)
			)
			(fill no)
			(layer "B.CrtYd")
		)
		(fp_rect
			(start 0.508 0.9398)
			(end -0.508 -0.9398)
			(stroke
				(width 0)
				(type default)
			)
			(fill no)
			(layer "B.Fab")
		)
		(pad "1" smd custom
			(at 0 -0.4445 270)
			(size 0.1397 0.1397)
			(layers "B.Cu" "B.Mask" "B.Paste")
			(net "P3V3_STBY")
			(options
				(clearance outline)
				(anchor circle)
			)
			(primitives
				(gr_poly
					(pts
						(arc
							(start -0.1778 0.2794)
							(mid -0.249642 0.249642)
							(end -0.2794 0.1778)
						)
						(arc
							(start -0.2794 -0.1778)
							(mid -0.249642 -0.249642)
							(end -0.1778 -0.2794)
						)
						(arc
							(start 0.1778 -0.2794)
							(mid 0.249642 -0.249642)
							(end 0.2794 -0.1778)
						)
						(arc
							(start 0.2794 0.1778)
							(mid 0.249642 0.249642)
							(end 0.1778 0.2794)
						)
					)
					(width 0)
					(fill yes)
				)
			)
		)
		(pad "2" smd custom
			(at 0 0.4445 270)
			(size 0.1397 0.1397)
			(layers "B.Cu" "B.Mask" "B.Paste")
			(net "DEBUG_RST_BTN_N_R")
			(options
				(clearance outline)
				(anchor circle)
			)
			(primitives
				(gr_poly
					(pts
						(arc
							(start -0.1778 0.2794)
							(mid -0.249642 0.249642)
							(end -0.2794 0.1778)
						)
						(arc
							(start -0.2794 -0.1778)
							(mid -0.249642 -0.249642)
							(end -0.1778 -0.2794)
						)
						(arc
							(start 0.1778 -0.2794)
							(mid 0.249642 -0.249642)
							(end 0.2794 -0.1778)
						)
						(arc
							(start 0.2794 0.1778)
							(mid 0.249642 0.249642)
							(end 0.1778 0.2794)
						)
					)
					(width 0)
					(fill yes)
				)
			)
		)
	)
	(footprint ""
		(layer "B.Cu")
		(at 30.38602 -126.8857 -90)
		(property "Reference" "R732"
			(at 0 0 90)
			(layer "B.SilkS")
			(hide yes)
			(effects
				(font
					(size 1.27 1.27)
				)
				(justify mirror)
			)
		)
		(property "Value" "0R2J-2-GP"
			(at -0.064008 -3.993896 270)
			(unlocked yes)
			(layer "B.Fab")
			(hide yes)
			(effects
				(font
					(size 1.016 1.016)
					(thickness 0.1524)
				)
				(justify mirror)
			)
		)
		(property "Device Type" "R402H16"
			(at -0.064008 -5.517896 270)
			(unlocked yes)
			(layer "B.Fab")
			(hide yes)
			(effects
				(font
					(size 1.016 1.016)
					(thickness 0.1524)
				)
				(justify mirror)
			)
		)
		(duplicate_pad_numbers_are_jumpers no)
		(fp_line
			(start -0.508 -0.9398)
			(end 0.508 -0.9398)
			(stroke
				(width 0.1524)
				(type default)
			)
			(layer "B.SilkS")
		)
		(fp_line
			(start 0.508 -0.9398)
			(end 0.508 0.9398)
			(stroke
				(width 0.1524)
				(type default)
			)
			(layer "B.SilkS")
		)
		(fp_rect
			(start 0.508 0.9398)
			(end -0.508 -0.9398)
			(stroke
				(width 0)
				(type default)
			)
			(fill no)
			(layer "B.CrtYd")
		)
		(fp_rect
			(start 0.508 0.9398)
			(end -0.508 -0.9398)
			(stroke
				(width 0)
				(type default)
			)
			(fill no)
			(layer "B.Fab")
		)
		(pad "1" smd custom
			(at 0 -0.4445 90)
			(size 0.1397 0.1397)
			(layers "B.Cu" "B.Mask" "B.Paste")
			(net "U104_EN")
			(options
				(clearance outline)
				(anchor circle)
			)
			(primitives
				(gr_poly
					(pts
						(arc
							(start -0.1778 0.2794)
							(mid -0.249642 0.249642)
							(end -0.2794 0.1778)
						)
						(arc
							(start -0.2794 -0.1778)
							(mid -0.249642 -0.249642)
							(end -0.1778 -0.2794)
						)
						(arc
							(start 0.1778 -0.2794)
							(mid 0.249642 -0.249642)
							(end 0.2794 -0.1778)
						)
						(arc
							(start 0.2794 0.1778)
							(mid 0.249642 0.249642)
							(end 0.1778 0.2794)
						)
					)
					(width 0)
					(fill yes)
				)
			)
		)
		(pad "2" smd custom
			(at 0 0.4445 90)
			(size 0.1397 0.1397)
			(layers "B.Cu" "B.Mask" "B.Paste")
			(net "COMP_PWR_EN")
			(options
				(clearance outline)
				(anchor circle)
			)
			(primitives
				(gr_poly
					(pts
						(arc
							(start -0.1778 0.2794)
							(mid -0.249642 0.249642)
							(end -0.2794 0.1778)
						)
						(arc
							(start -0.2794 -0.1778)
							(mid -0.249642 -0.249642)
							(end -0.1778 -0.2794)
						)
						(arc
							(start 0.1778 -0.2794)
							(mid 0.249642 -0.249642)
							(end 0.2794 -0.1778)
						)
						(arc
							(start 0.2794 0.1778)
							(mid 0.249642 0.249642)
							(end 0.1778 0.2794)
						)
					)
					(width 0)
					(fill yes)
				)
			)
		)
	)
	(footprint ""
		(layer "B.Cu")
		(at 211.836 -84.455 90)
		(property "Reference" "C350"
			(at 0 0 90)
			(layer "B.SilkS")
			(hide yes)
			(effects
				(font
					(size 1.27 1.27)
				)
				(justify mirror)
			)
		)
		(property "Value" "SC22U6D3V3MX-9-GP-U"
			(at 0 -2.8194 90)
			(unlocked yes)
			(layer "B.Fab")
			(hide yes)
			(effects
				(font
					(size 1.016 1.016)
					(thickness 0.1524)
				)
				(justify mirror)
			)
		)
		(property "Device Type" "C603H40"
			(at 0 -4.3434 90)
			(unlocked yes)
			(layer "B.Fab")
			(hide yes)
			(effects
				(font
					(size 1.016 1.016)
					(thickness 0.1524)
				)
				(justify mirror)
			)
		)
		(duplicate_pad_numbers_are_jumpers no)
		(fp_line
			(start -0.508 0)
			(end 0.508 0)
			(stroke
				(width 0.2032)
				(type default)
			)
			(layer "B.SilkS")
		)
		(fp_rect
			(start 0.5842 1.3335)
			(end -0.5842 -1.3335)
			(stroke
				(width 0)
				(type default)
			)
			(fill no)
			(layer "B.CrtYd")
		)
		(fp_rect
			(start 0.5842 1.3335)
			(end -0.5842 -1.3335)
			(stroke
				(width 0)
				(type default)
			)
			(fill no)
			(layer "B.Fab")
		)
		(pad "1" smd custom
			(at 0 -0.762 270)
			(size 0.2159 0.2159)
			(layers "B.Cu" "B.Mask" "B.Paste")
			(net "SAS0_VDDH")
			(options
				(clearance outline)
				(anchor circle)
			)
			(primitives
				(gr_poly
					(pts
						(arc
							(start -0.3302 0.4318)
							(mid -0.402042 0.402042)
							(end -0.4318 0.3302)
						)
						(arc
							(start -0.4318 -0.3302)
							(mid -0.402042 -0.402042)
							(end -0.3302 -0.4318)
						)
						(arc
							(start 0.3302 -0.4318)
							(mid 0.402042 -0.402042)
							(end 0.4318 -0.3302)
						)
						(arc
							(start 0.4318 0.3302)
							(mid 0.402042 0.402042)
							(end 0.3302 0.4318)
						)
					)
					(width 0)
					(fill yes)
				)
			)
		)
		(pad "2" smd custom
			(at 0 0.762 270)
			(size 0.2159 0.2159)
			(layers "B.Cu" "B.Mask" "B.Paste")
			(net "GND")
			(options
				(clearance outline)
				(anchor circle)
			)
			(primitives
				(gr_poly
					(pts
						(arc
							(start -0.3302 0.4318)
							(mid -0.402042 0.402042)
							(end -0.4318 0.3302)
						)
						(arc
							(start -0.4318 -0.3302)
							(mid -0.402042 -0.402042)
							(end -0.3302 -0.4318)
						)
						(arc
							(start 0.3302 -0.4318)
							(mid 0.402042 -0.402042)
							(end 0.4318 -0.3302)
						)
						(arc
							(start 0.4318 0.3302)
							(mid 0.402042 0.402042)
							(end 0.3302 0.4318)
						)
					)
					(width 0)
					(fill yes)
				)
			)
		)
	)
	(footprint ""
		(layer "B.Cu")
		(at 198.530718 -81.153 180)
		(property "Reference" "C294"
			(at 0 0 0)
			(layer "B.SilkS")
			(hide yes)
			(effects
				(font
					(size 1.27 1.27)
				)
				(justify mirror)
			)
		)
		(property "Value" "SCD22U10V1KX-GP"
			(at 2.8321 -1.7399 180)
			(unlocked yes)
			(layer "B.Fab")
			(hide yes)
			(effects
				(font
					(size 1.016 1.016)
					(thickness 0.1524)
				)
				(justify mirror)
			)
		)
		(property "Device Type" "C0201H13"
			(at 2.8321 -3.2639 180)
			(unlocked yes)
			(layer "B.Fab")
			(hide yes)
			(effects
				(font
					(size 1.016 1.016)
					(thickness 0.1524)
				)
				(justify mirror)
			)
		)
		(duplicate_pad_numbers_are_jumpers no)
		(fp_rect
			(start 0.2794 0.6477)
			(end -0.2794 -0.6477)
			(stroke
				(width 0)
				(type default)
			)
			(fill no)
			(layer "B.CrtYd")
		)
		(fp_rect
			(start 0.2794 0.6477)
			(end -0.2794 -0.6477)
			(stroke
				(width 0)
				(type default)
			)
			(fill no)
			(layer "B.Fab")
		)
		(pad "1" smd custom
			(at 0 -0.2794)
			(size 0.0762 0.0762)
			(layers "B.Cu" "B.Mask" "B.Paste")
			(net "PCIE_IOM_TO_COMP_10_DN_C")
			(options
				(clearance outline)
				(anchor circle)
			)
			(primitives
				(gr_poly
					(pts
						(arc
							(start 0.1524 0.127)
							(mid 0.137521 0.162921)
							(end 0.1016 0.1778)
						)
						(arc
							(start -0.1016 0.1778)
							(mid -0.137521 0.162921)
							(end -0.1524 0.127)
						)
						(arc
							(start -0.1524 -0.127)
							(mid -0.137521 -0.162921)
							(end -0.1016 -0.1778)
						)
						(arc
							(start 0.1016 -0.1778)
							(mid 0.137521 -0.162921)
							(end 0.1524 -0.127)
						)
					)
					(width 0)
					(fill yes)
				)
			)
		)
		(pad "2" smd custom
			(at 0 0.2794)
			(size 0.0762 0.0762)
			(layers "B.Cu" "B.Mask" "B.Paste")
			(net "PCIE_IOM_TO_COMP_10_DN")
			(options
				(clearance outline)
				(anchor circle)
			)
			(primitives
				(gr_poly
					(pts
						(arc
							(start 0.1524 0.127)
							(mid 0.137521 0.162921)
							(end 0.1016 0.1778)
						)
						(arc
							(start -0.1016 0.1778)
							(mid -0.137521 0.162921)
							(end -0.1524 0.127)
						)
						(arc
							(start -0.1524 -0.127)
							(mid -0.137521 -0.162921)
							(end -0.1016 -0.1778)
						)
						(arc
							(start 0.1016 -0.1778)
							(mid 0.137521 -0.162921)
							(end 0.1524 -0.127)
						)
					)
					(width 0)
					(fill yes)
				)
			)
		)
	)
	(footprint ""
		(layer "B.Cu")
		(at 50.40884 -152.23236 -90)
		(property "Reference" "R366"
			(at 0 0 90)
			(layer "B.SilkS")
			(hide yes)
			(effects
				(font
					(size 1.27 1.27)
				)
				(justify mirror)
			)
		)
		(property "Value" "49K9R2F-L-GP"
			(at -0.064008 -3.993896 270)
			(unlocked yes)
			(layer "B.Fab")
			(hide yes)
			(effects
				(font
					(size 1.016 1.016)
					(thickness 0.1524)
				)
				(justify mirror)
			)
		)
		(property "Device Type" "R402H16"
			(at -0.064008 -5.517896 270)
			(unlocked yes)
			(layer "B.Fab")
			(hide yes)
			(effects
				(font
					(size 1.016 1.016)
					(thickness 0.1524)
				)
				(justify mirror)
			)
		)
		(duplicate_pad_numbers_are_jumpers no)
		(fp_line
			(start -0.508 -0.9398)
			(end 0.508 -0.9398)
			(stroke
				(width 0.1524)
				(type default)
			)
			(layer "B.SilkS")
		)
		(fp_line
			(start 0.508 -0.9398)
			(end 0.508 0.9398)
			(stroke
				(width 0.1524)
				(type default)
			)
			(layer "B.SilkS")
		)
		(fp_rect
			(start 0.508 0.9398)
			(end -0.508 -0.9398)
			(stroke
				(width 0)
				(type default)
			)
			(fill no)
			(layer "B.CrtYd")
		)
		(fp_rect
			(start 0.508 0.9398)
			(end -0.508 -0.9398)
			(stroke
				(width 0)
				(type default)
			)
			(fill no)
			(layer "B.Fab")
		)
		(pad "1" smd custom
			(at 0 -0.4445 90)
			(size 0.1397 0.1397)
			(layers "B.Cu" "B.Mask" "B.Paste")
			(net "GND")
			(options
				(clearance outline)
				(anchor circle)
			)
			(primitives
				(gr_poly
					(pts
						(arc
							(start -0.1778 0.2794)
							(mid -0.249642 0.249642)
							(end -0.2794 0.1778)
						)
						(arc
							(start -0.2794 -0.1778)
							(mid -0.249642 -0.249642)
							(end -0.1778 -0.2794)
						)
						(arc
							(start 0.1778 -0.2794)
							(mid 0.249642 -0.249642)
							(end 0.2794 -0.1778)
						)
						(arc
							(start 0.2794 0.1778)
							(mid 0.249642 0.249642)
							(end 0.1778 0.2794)
						)
					)
					(width 0)
					(fill yes)
				)
			)
		)
		(pad "2" smd custom
			(at 0 0.4445 90)
			(size 0.1397 0.1397)
			(layers "B.Cu" "B.Mask" "B.Paste")
			(net "ADCVREXT")
			(options
				(clearance outline)
				(anchor circle)
			)
			(primitives
				(gr_poly
					(pts
						(arc
							(start -0.1778 0.2794)
							(mid -0.249642 0.249642)
							(end -0.2794 0.1778)
						)
						(arc
							(start -0.2794 -0.1778)
							(mid -0.249642 -0.249642)
							(end -0.1778 -0.2794)
						)
						(arc
							(start 0.1778 -0.2794)
							(mid 0.249642 -0.249642)
							(end 0.2794 -0.1778)
						)
						(arc
							(start 0.2794 0.1778)
							(mid 0.249642 0.249642)
							(end 0.1778 0.2794)
						)
					)
					(width 0)
					(fill yes)
				)
			)
		)
	)
	(footprint ""
		(layer "B.Cu")
		(at 191.68999 -21.209 -90)
		(property "Reference" "C489"
			(at 0 0 90)
			(layer "B.SilkS")
			(hide yes)
			(effects
				(font
					(size 1.27 1.27)
				)
				(justify mirror)
			)
		)
		(property "Value" "SCD01U16V1KX-GP"
			(at 2.8321 -1.7399 270)
			(unlocked yes)
			(layer "B.Fab")
			(hide yes)
			(effects
				(font
					(size 1.016 1.016)
					(thickness 0.1524)
				)
				(justify mirror)
			)
		)
		(property "Device Type" "C0201H13"
			(at 2.8321 -3.2639 270)
			(unlocked yes)
			(layer "B.Fab")
			(hide yes)
			(effects
				(font
					(size 1.016 1.016)
					(thickness 0.1524)
				)
				(justify mirror)
			)
		)
		(duplicate_pad_numbers_are_jumpers no)
		(fp_rect
			(start 0.2794 0.6477)
			(end -0.2794 -0.6477)
			(stroke
				(width 0)
				(type default)
			)
			(fill no)
			(layer "B.CrtYd")
		)
		(fp_rect
			(start 0.2794 0.6477)
			(end -0.2794 -0.6477)
			(stroke
				(width 0)
				(type default)
			)
			(fill no)
			(layer "B.Fab")
		)
		(pad "1" smd custom
			(at 0 -0.2794 90)
			(size 0.0762 0.0762)
			(layers "B.Cu" "B.Mask" "B.Paste")
			(net "PHY_CON_A_TO_IOC_1_DN")
			(options
				(clearance outline)
				(anchor circle)
			)
			(primitives
				(gr_poly
					(pts
						(arc
							(start 0.1524 0.127)
							(mid 0.137521 0.162921)
							(end 0.1016 0.1778)
						)
						(arc
							(start -0.1016 0.1778)
							(mid -0.137521 0.162921)
							(end -0.1524 0.127)
						)
						(arc
							(start -0.1524 -0.127)
							(mid -0.137521 -0.162921)
							(end -0.1016 -0.1778)
						)
						(arc
							(start 0.1016 -0.1778)
							(mid 0.137521 -0.162921)
							(end 0.1524 -0.127)
						)
					)
					(width 0)
					(fill yes)
				)
			)
		)
		(pad "2" smd custom
			(at 0 0.2794 90)
			(size 0.0762 0.0762)
			(layers "B.Cu" "B.Mask" "B.Paste")
			(net "PHY_CON_A_TO_IOC_1_DN_C")
			(options
				(clearance outline)
				(anchor circle)
			)
			(primitives
				(gr_poly
					(pts
						(arc
							(start 0.1524 0.127)
							(mid 0.137521 0.162921)
							(end 0.1016 0.1778)
						)
						(arc
							(start -0.1016 0.1778)
							(mid -0.137521 0.162921)
							(end -0.1524 0.127)
						)
						(arc
							(start -0.1524 -0.127)
							(mid -0.137521 -0.162921)
							(end -0.1016 -0.1778)
						)
						(arc
							(start 0.1016 -0.1778)
							(mid 0.137521 -0.162921)
							(end 0.1524 -0.127)
						)
					)
					(width 0)
					(fill yes)
				)
			)
		)
	)
	(footprint ""
		(layer "B.Cu")
		(at 209.0674 -57.2516)
		(property "Reference" "TP120"
			(at 0 0 0)
			(layer "B.SilkS")
			(hide yes)
			(effects
				(font
					(size 1.27 1.27)
				)
				(justify mirror)
			)
		)
		(property "Value" "TPAD28-2-GP"
			(at 0.0127 -1.6637 0)
			(unlocked yes)
			(layer "B.Fab")
			(hide yes)
			(effects
				(font
					(size 1.016 1.016)
					(thickness 0.1524)
				)
				(justify mirror)
			)
		)
		(property "Device Type" "TPAD28"
			(at 0.0127 -3.1877 0)
			(unlocked yes)
			(layer "B.Fab")
			(hide yes)
			(effects
				(font
					(size 1.016 1.016)
					(thickness 0.1524)
				)
				(justify mirror)
			)
		)
		(duplicate_pad_numbers_are_jumpers no)
		(fp_poly
			(pts
				(arc
					(start 0.3556 0)
					(mid -0.3556 0)
					(end 0.3556 0)
				)
			)
			(stroke
				(width 0)
				(type default)
			)
			(fill no)
			(layer "B.CrtYd")
		)
		(fp_poly
			(pts
				(arc
					(start 0.6096 0)
					(mid -0.6096 0)
					(end 0.6096 0)
				)
			)
			(stroke
				(width 0)
				(type default)
			)
			(fill no)
			(layer "B.Fab")
		)
		(pad "1" smd circle
			(at 0 0 180)
			(size 0.7112 0.7112)
			(layers "B.Cu" "B.Mask" "B.Paste")
			(net "SIO_CLK_1")
		)
	)
	(footprint ""
		(layer "B.Cu")
		(at 87.8332 -174.625 90)
		(property "Reference" "R418"
			(at 0 0 90)
			(layer "B.SilkS")
			(hide yes)
			(effects
				(font
					(size 1.27 1.27)
				)
				(justify mirror)
			)
		)
		(property "Value" "0R2J-2-GP"
			(at -0.064008 -3.993896 90)
			(unlocked yes)
			(layer "B.Fab")
			(hide yes)
			(effects
				(font
					(size 1.016 1.016)
					(thickness 0.1524)
				)
				(justify mirror)
			)
		)
		(property "Device Type" "R402H16"
			(at -0.064008 -5.517896 90)
			(unlocked yes)
			(layer "B.Fab")
			(hide yes)
			(effects
				(font
					(size 1.016 1.016)
					(thickness 0.1524)
				)
				(justify mirror)
			)
		)
		(duplicate_pad_numbers_are_jumpers no)
		(fp_line
			(start 0.508 -0.9398)
			(end 0.508 0.9398)
			(stroke
				(width 0.1524)
				(type default)
			)
			(layer "B.SilkS")
		)
		(fp_line
			(start -0.508 -0.9398)
			(end 0.508 -0.9398)
			(stroke
				(width 0.1524)
				(type default)
			)
			(layer "B.SilkS")
		)
		(fp_rect
			(start 0.508 0.9398)
			(end -0.508 -0.9398)
			(stroke
				(width 0)
				(type default)
			)
			(fill no)
			(layer "B.CrtYd")
		)
		(fp_rect
			(start 0.508 0.9398)
			(end -0.508 -0.9398)
			(stroke
				(width 0)
				(type default)
			)
			(fill no)
			(layer "B.Fab")
		)
		(pad "1" smd custom
			(at 0 -0.4445 270)
			(size 0.1397 0.1397)
			(layers "B.Cu" "B.Mask" "B.Paste")
			(net "UART_COMP_R_TX")
			(options
				(clearance outline)
				(anchor circle)
			)
			(primitives
				(gr_poly
					(pts
						(arc
							(start -0.1778 0.2794)
							(mid -0.249642 0.249642)
							(end -0.2794 0.1778)
						)
						(arc
							(start -0.2794 -0.1778)
							(mid -0.249642 -0.249642)
							(end -0.1778 -0.2794)
						)
						(arc
							(start 0.1778 -0.2794)
							(mid 0.249642 -0.249642)
							(end 0.2794 -0.1778)
						)
						(arc
							(start 0.2794 0.1778)
							(mid 0.249642 0.249642)
							(end 0.1778 0.2794)
						)
					)
					(width 0)
					(fill yes)
				)
			)
		)
		(pad "2" smd custom
			(at 0 0.4445 270)
			(size 0.1397 0.1397)
			(layers "B.Cu" "B.Mask" "B.Paste")
			(net "UART_COMP_TX")
			(options
				(clearance outline)
				(anchor circle)
			)
			(primitives
				(gr_poly
					(pts
						(arc
							(start -0.1778 0.2794)
							(mid -0.249642 0.249642)
							(end -0.2794 0.1778)
						)
						(arc
							(start -0.2794 -0.1778)
							(mid -0.249642 -0.249642)
							(end -0.1778 -0.2794)
						)
						(arc
							(start 0.1778 -0.2794)
							(mid 0.249642 -0.249642)
							(end 0.2794 -0.1778)
						)
						(arc
							(start 0.2794 0.1778)
							(mid 0.249642 0.249642)
							(end 0.1778 0.2794)
						)
					)
					(width 0)
					(fill yes)
				)
			)
		)
	)
	(footprint ""
		(layer "B.Cu")
		(at 189.8396 -52.959 -90)
		(property "Reference" "R666"
			(at 0 0 90)
			(layer "B.SilkS")
			(hide yes)
			(effects
				(font
					(size 1.27 1.27)
				)
				(justify mirror)
			)
		)
		(property "Value" "10KR2F-2-GP"
			(at -0.064008 -3.993896 270)
			(unlocked yes)
			(layer "B.Fab")
			(hide yes)
			(effects
				(font
					(size 1.016 1.016)
					(thickness 0.1524)
				)
				(justify mirror)
			)
		)
		(property "Device Type" "R402H16"
			(at -0.064008 -5.517896 270)
			(unlocked yes)
			(layer "B.Fab")
			(hide yes)
			(effects
				(font
					(size 1.016 1.016)
					(thickness 0.1524)
				)
				(justify mirror)
			)
		)
		(duplicate_pad_numbers_are_jumpers no)
		(fp_line
			(start -0.508 -0.9398)
			(end 0.508 -0.9398)
			(stroke
				(width 0.1524)
				(type default)
			)
			(layer "B.SilkS")
		)
		(fp_line
			(start 0.508 -0.9398)
			(end 0.508 0.9398)
			(stroke
				(width 0.1524)
				(type default)
			)
			(layer "B.SilkS")
		)
		(fp_rect
			(start 0.508 0.9398)
			(end -0.508 -0.9398)
			(stroke
				(width 0)
				(type default)
			)
			(fill no)
			(layer "B.CrtYd")
		)
		(fp_rect
			(start 0.508 0.9398)
			(end -0.508 -0.9398)
			(stroke
				(width 0)
				(type default)
			)
			(fill no)
			(layer "B.Fab")
		)
		(pad "1" smd custom
			(at 0 -0.4445 90)
			(size 0.1397 0.1397)
			(layers "B.Cu" "B.Mask" "B.Paste")
			(net "P1V8")
			(options
				(clearance outline)
				(anchor circle)
			)
			(primitives
				(gr_poly
					(pts
						(arc
							(start -0.1778 0.2794)
							(mid -0.249642 0.249642)
							(end -0.2794 0.1778)
						)
						(arc
							(start -0.2794 -0.1778)
							(mid -0.249642 -0.249642)
							(end -0.1778 -0.2794)
						)
						(arc
							(start 0.1778 -0.2794)
							(mid 0.249642 -0.249642)
							(end 0.2794 -0.1778)
						)
						(arc
							(start 0.2794 0.1778)
							(mid 0.249642 0.249642)
							(end 0.1778 0.2794)
						)
					)
					(width 0)
					(fill yes)
				)
			)
		)
		(pad "2" smd custom
			(at 0 0.4445 90)
			(size 0.1397 0.1397)
			(layers "B.Cu" "B.Mask" "B.Paste")
			(net "XM_NAND_CS_N")
			(options
				(clearance outline)
				(anchor circle)
			)
			(primitives
				(gr_poly
					(pts
						(arc
							(start -0.1778 0.2794)
							(mid -0.249642 0.249642)
							(end -0.2794 0.1778)
						)
						(arc
							(start -0.2794 -0.1778)
							(mid -0.249642 -0.249642)
							(end -0.1778 -0.2794)
						)
						(arc
							(start 0.1778 -0.2794)
							(mid 0.249642 -0.249642)
							(end 0.2794 -0.1778)
						)
						(arc
							(start 0.2794 0.1778)
							(mid 0.249642 0.249642)
							(end 0.1778 0.2794)
						)
					)
					(width 0)
					(fill yes)
				)
			)
		)
	)
	(footprint ""
		(layer "B.Cu")
		(at 25.3238 -180.8988 -90)
		(property "Reference" "R483"
			(at 0 0 90)
			(layer "B.SilkS")
			(hide yes)
			(effects
				(font
					(size 1.27 1.27)
				)
				(justify mirror)
			)
		)
		(property "Value" "2D2R3J-2-GP"
			(at 0.0254 -2.5146 270)
			(unlocked yes)
			(layer "B.Fab")
			(hide yes)
			(effects
				(font
					(size 1.016 1.016)
					(thickness 0.1524)
				)
				(justify mirror)
			)
		)
		(property "Device Type" "R603H22"
			(at 0.0254 -4.0386 270)
			(unlocked yes)
			(layer "B.Fab")
			(hide yes)
			(effects
				(font
					(size 1.016 1.016)
					(thickness 0.1524)
				)
				(justify mirror)
			)
		)
		(duplicate_pad_numbers_are_jumpers no)
		(fp_line
			(start -0.2032 0)
			(end -0.4826 0)
			(stroke
				(width 0.2032)
				(type default)
			)
			(layer "B.SilkS")
		)
		(fp_line
			(start 0.4826 0)
			(end 0.2032 0)
			(stroke
				(width 0.2032)
				(type default)
			)
			(layer "B.SilkS")
		)
		(fp_rect
			(start 0.5842 1.3335)
			(end -0.5842 -1.3335)
			(stroke
				(width 0)
				(type default)
			)
			(fill no)
			(layer "B.CrtYd")
		)
		(fp_rect
			(start 0.5842 1.3335)
			(end -0.5842 -1.3335)
			(stroke
				(width 0)
				(type default)
			)
			(fill no)
			(layer "B.Fab")
		)
		(pad "1" smd custom
			(at 0 -0.762 90)
			(size 0.2159 0.2159)
			(layers "B.Cu" "B.Mask" "B.Paste")
			(net "P12V_STBY_VDD_PU2")
			(options
				(clearance outline)
				(anchor circle)
			)
			(primitives
				(gr_poly
					(pts
						(arc
							(start -0.3302 0.4318)
							(mid -0.402042 0.402042)
							(end -0.4318 0.3302)
						)
						(arc
							(start -0.4318 -0.3302)
							(mid -0.402042 -0.402042)
							(end -0.3302 -0.4318)
						)
						(arc
							(start 0.3302 -0.4318)
							(mid 0.402042 -0.402042)
							(end 0.4318 -0.3302)
						)
						(arc
							(start 0.4318 0.3302)
							(mid 0.402042 0.402042)
							(end 0.3302 0.4318)
						)
					)
					(width 0)
					(fill yes)
				)
			)
		)
		(pad "2" smd custom
			(at 0 0.762 90)
			(size 0.2159 0.2159)
			(layers "B.Cu" "B.Mask" "B.Paste")
			(net "P12V_STBY")
			(options
				(clearance outline)
				(anchor circle)
			)
			(primitives
				(gr_poly
					(pts
						(arc
							(start -0.3302 0.4318)
							(mid -0.402042 0.402042)
							(end -0.4318 0.3302)
						)
						(arc
							(start -0.4318 -0.3302)
							(mid -0.402042 -0.402042)
							(end -0.3302 -0.4318)
						)
						(arc
							(start 0.3302 -0.4318)
							(mid 0.402042 -0.402042)
							(end 0.4318 -0.3302)
						)
						(arc
							(start 0.4318 0.3302)
							(mid 0.402042 0.402042)
							(end 0.3302 0.4318)
						)
					)
					(width 0)
					(fill yes)
				)
			)
		)
	)
	(footprint ""
		(layer "B.Cu")
		(at 57.1246 -151.6888 -90)
		(property "Reference" "R383"
			(at 0 0 90)
			(layer "B.SilkS")
			(hide yes)
			(effects
				(font
					(size 1.27 1.27)
				)
				(justify mirror)
			)
		)
		(property "Value" "4K7R2F-GP"
			(at -0.064008 -3.993896 270)
			(unlocked yes)
			(layer "B.Fab")
			(hide yes)
			(effects
				(font
					(size 1.016 1.016)
					(thickness 0.1524)
				)
				(justify mirror)
			)
		)
		(property "Device Type" "R402H16"
			(at -0.064008 -5.517896 270)
			(unlocked yes)
			(layer "B.Fab")
			(hide yes)
			(effects
				(font
					(size 1.016 1.016)
					(thickness 0.1524)
				)
				(justify mirror)
			)
		)
		(duplicate_pad_numbers_are_jumpers no)
		(fp_line
			(start -0.508 -0.9398)
			(end 0.508 -0.9398)
			(stroke
				(width 0.1524)
				(type default)
			)
			(layer "B.SilkS")
		)
		(fp_line
			(start 0.508 -0.9398)
			(end 0.508 0.9398)
			(stroke
				(width 0.1524)
				(type default)
			)
			(layer "B.SilkS")
		)
		(fp_rect
			(start 0.508 0.9398)
			(end -0.508 -0.9398)
			(stroke
				(width 0)
				(type default)
			)
			(fill no)
			(layer "B.CrtYd")
		)
		(fp_rect
			(start 0.508 0.9398)
			(end -0.508 -0.9398)
			(stroke
				(width 0)
				(type default)
			)
			(fill no)
			(layer "B.Fab")
		)
		(pad "1" smd custom
			(at 0 -0.4445 90)
			(size 0.1397 0.1397)
			(layers "B.Cu" "B.Mask" "B.Paste")
			(net "P3V3_STBY")
			(options
				(clearance outline)
				(anchor circle)
			)
			(primitives
				(gr_poly
					(pts
						(arc
							(start -0.1778 0.2794)
							(mid -0.249642 0.249642)
							(end -0.2794 0.1778)
						)
						(arc
							(start -0.2794 -0.1778)
							(mid -0.249642 -0.249642)
							(end -0.1778 -0.2794)
						)
						(arc
							(start 0.1778 -0.2794)
							(mid 0.249642 -0.249642)
							(end 0.2794 -0.1778)
						)
						(arc
							(start 0.2794 0.1778)
							(mid 0.249642 0.249642)
							(end 0.1778 0.2794)
						)
					)
					(width 0)
					(fill yes)
				)
			)
		)
		(pad "2" smd custom
			(at 0 0.4445 90)
			(size 0.1397 0.1397)
			(layers "B.Cu" "B.Mask" "B.Paste")
			(net "MAC1_TXD2")
			(options
				(clearance outline)
				(anchor circle)
			)
			(primitives
				(gr_poly
					(pts
						(arc
							(start -0.1778 0.2794)
							(mid -0.249642 0.249642)
							(end -0.2794 0.1778)
						)
						(arc
							(start -0.2794 -0.1778)
							(mid -0.249642 -0.249642)
							(end -0.1778 -0.2794)
						)
						(arc
							(start 0.1778 -0.2794)
							(mid 0.249642 -0.249642)
							(end 0.2794 -0.1778)
						)
						(arc
							(start 0.2794 0.1778)
							(mid 0.249642 0.249642)
							(end 0.1778 0.2794)
						)
					)
					(width 0)
					(fill yes)
				)
			)
		)
	)
	(footprint ""
		(layer "B.Cu")
		(at 207.3656 -59.9186)
		(property "Reference" "TP124"
			(at 0 0 0)
			(layer "B.SilkS")
			(hide yes)
			(effects
				(font
					(size 1.27 1.27)
				)
				(justify mirror)
			)
		)
		(property "Value" "TPAD28-2-GP"
			(at 0.0127 -1.6637 0)
			(unlocked yes)
			(layer "B.Fab")
			(hide yes)
			(effects
				(font
					(size 1.016 1.016)
					(thickness 0.1524)
				)
				(justify mirror)
			)
		)
		(property "Device Type" "TPAD28"
			(at 0.0127 -3.1877 0)
			(unlocked yes)
			(layer "B.Fab")
			(hide yes)
			(effects
				(font
					(size 1.016 1.016)
					(thickness 0.1524)
				)
				(justify mirror)
			)
		)
		(duplicate_pad_numbers_are_jumpers no)
		(fp_poly
			(pts
				(arc
					(start 0.3556 0)
					(mid -0.3556 0)
					(end 0.3556 0)
				)
			)
			(stroke
				(width 0)
				(type default)
			)
			(fill no)
			(layer "B.CrtYd")
		)
		(fp_poly
			(pts
				(arc
					(start 0.6096 0)
					(mid -0.6096 0)
					(end 0.6096 0)
				)
			)
			(stroke
				(width 0)
				(type default)
			)
			(fill no)
			(layer "B.Fab")
		)
		(pad "1" smd circle
			(at 0 0 180)
			(size 0.7112 0.7112)
			(layers "B.Cu" "B.Mask" "B.Paste")
			(net "SIO_DOUT_1")
		)
	)
	(footprint ""
		(layer "B.Cu")
		(at 185.2041 -72.18934 90)
		(property "Reference" "C469"
			(at 0 0 90)
			(layer "B.SilkS")
			(hide yes)
			(effects
				(font
					(size 1.27 1.27)
				)
				(justify mirror)
			)
		)
		(property "Value" "SCD1U16V2KX-3GP"
			(at -1.1811 -2.7051 90)
			(unlocked yes)
			(layer "B.Fab")
			(hide yes)
			(effects
				(font
					(size 1.016 1.016)
					(thickness 0.1524)
				)
				(justify mirror)
			)
		)
		(property "Device Type" "C402H22"
			(at -1.1811 -4.2291 90)
			(unlocked yes)
			(layer "B.Fab")
			(hide yes)
			(effects
				(font
					(size 1.016 1.016)
					(thickness 0.1524)
				)
				(justify mirror)
			)
		)
		(duplicate_pad_numbers_are_jumpers no)
		(fp_rect
			(start 0.4318 0.9525)
			(end -0.4318 -0.9525)
			(stroke
				(width 0)
				(type default)
			)
			(fill no)
			(layer "B.CrtYd")
		)
		(fp_rect
			(start 0.4318 0.9525)
			(end -0.4318 -0.9525)
			(stroke
				(width 0)
				(type default)
			)
			(fill no)
			(layer "B.Fab")
		)
		(pad "1" smd custom
			(at 0 -0.4445 270)
			(size 0.1524 0.1524)
			(layers "B.Cu" "B.Mask" "B.Paste")
			(net "P1V8")
			(options
				(clearance outline)
				(anchor circle)
			)
			(primitives
				(gr_poly
					(pts
						(arc
							(start 0.3048 0.2032)
							(mid 0.275042 0.275042)
							(end 0.2032 0.3048)
						)
						(arc
							(start -0.2032 0.3048)
							(mid -0.275042 0.275042)
							(end -0.3048 0.2032)
						)
						(arc
							(start -0.3048 -0.2032)
							(mid -0.275042 -0.275042)
							(end -0.2032 -0.3048)
						)
						(arc
							(start 0.2032 -0.3048)
							(mid 0.275042 -0.275042)
							(end 0.3048 -0.2032)
						)
					)
					(width 0)
					(fill yes)
				)
			)
		)
		(pad "2" smd custom
			(at 0 0.4445 270)
			(size 0.1524 0.1524)
			(layers "B.Cu" "B.Mask" "B.Paste")
			(net "GND")
			(options
				(clearance outline)
				(anchor circle)
			)
			(primitives
				(gr_poly
					(pts
						(arc
							(start 0.3048 0.2032)
							(mid 0.275042 0.275042)
							(end 0.2032 0.3048)
						)
						(arc
							(start -0.2032 0.3048)
							(mid -0.275042 0.275042)
							(end -0.3048 0.2032)
						)
						(arc
							(start -0.3048 -0.2032)
							(mid -0.275042 -0.275042)
							(end -0.2032 -0.3048)
						)
						(arc
							(start 0.2032 -0.3048)
							(mid 0.275042 -0.275042)
							(end 0.3048 -0.2032)
						)
					)
					(width 0)
					(fill yes)
				)
			)
		)
	)
	(footprint ""
		(layer "B.Cu")
		(at 56.091328 -140.151104 -90)
		(property "Reference" "TP68"
			(at 0 0 90)
			(layer "B.SilkS")
			(hide yes)
			(effects
				(font
					(size 1.27 1.27)
				)
				(justify mirror)
			)
		)
		(property "Value" "TPAD28-2-GP"
			(at 0.0127 -1.6637 270)
			(unlocked yes)
			(layer "B.Fab")
			(hide yes)
			(effects
				(font
					(size 1.016 1.016)
					(thickness 0.1524)
				)
				(justify mirror)
			)
		)
		(property "Device Type" "TPAD28"
			(at 0.0127 -3.1877 270)
			(unlocked yes)
			(layer "B.Fab")
			(hide yes)
			(effects
				(font
					(size 1.016 1.016)
					(thickness 0.1524)
				)
				(justify mirror)
			)
		)
		(duplicate_pad_numbers_are_jumpers no)
		(fp_poly
			(pts
				(arc
					(start 0 -0.3556)
					(mid 0 0.3556)
					(end 0 -0.3556)
				)
			)
			(stroke
				(width 0)
				(type default)
			)
			(fill no)
			(layer "B.CrtYd")
		)
		(fp_poly
			(pts
				(arc
					(start 0 -0.6096)
					(mid 0 0.6096)
					(end 0 -0.6096)
				)
			)
			(stroke
				(width 0)
				(type default)
			)
			(fill no)
			(layer "B.Fab")
		)
		(pad "1" smd circle
			(at 0 0 90)
			(size 0.7112 0.7112)
			(layers "B.Cu" "B.Mask" "B.Paste")
			(net "TP_BMC_GPIOG5")
		)
	)
	(footprint ""
		(layer "B.Cu")
		(at 197.9168 -55.3974 90)
		(property "Reference" "C435"
			(at 0 0 90)
			(layer "B.SilkS")
			(hide yes)
			(effects
				(font
					(size 1.27 1.27)
				)
				(justify mirror)
			)
		)
		(property "Value" "SCD1U16V2KX-3GP"
			(at -1.1811 -2.7051 90)
			(unlocked yes)
			(layer "B.Fab")
			(hide yes)
			(effects
				(font
					(size 1.016 1.016)
					(thickness 0.1524)
				)
				(justify mirror)
			)
		)
		(property "Device Type" "C402H22"
			(at -1.1811 -4.2291 90)
			(unlocked yes)
			(layer "B.Fab")
			(hide yes)
			(effects
				(font
					(size 1.016 1.016)
					(thickness 0.1524)
				)
				(justify mirror)
			)
		)
		(duplicate_pad_numbers_are_jumpers no)
		(fp_rect
			(start 0.4318 0.9525)
			(end -0.4318 -0.9525)
			(stroke
				(width 0)
				(type default)
			)
			(fill no)
			(layer "B.CrtYd")
		)
		(fp_rect
			(start 0.4318 0.9525)
			(end -0.4318 -0.9525)
			(stroke
				(width 0)
				(type default)
			)
			(fill no)
			(layer "B.Fab")
		)
		(pad "1" smd custom
			(at 0 -0.4445 270)
			(size 0.1524 0.1524)
			(layers "B.Cu" "B.Mask" "B.Paste")
			(net "P1V8")
			(options
				(clearance outline)
				(anchor circle)
			)
			(primitives
				(gr_poly
					(pts
						(arc
							(start 0.3048 0.2032)
							(mid 0.275042 0.275042)
							(end 0.2032 0.3048)
						)
						(arc
							(start -0.2032 0.3048)
							(mid -0.275042 0.275042)
							(end -0.3048 0.2032)
						)
						(arc
							(start -0.3048 -0.2032)
							(mid -0.275042 -0.275042)
							(end -0.2032 -0.3048)
						)
						(arc
							(start 0.2032 -0.3048)
							(mid 0.275042 -0.275042)
							(end 0.3048 -0.2032)
						)
					)
					(width 0)
					(fill yes)
				)
			)
		)
		(pad "2" smd custom
			(at 0 0.4445 270)
			(size 0.1524 0.1524)
			(layers "B.Cu" "B.Mask" "B.Paste")
			(net "GND")
			(options
				(clearance outline)
				(anchor circle)
			)
			(primitives
				(gr_poly
					(pts
						(arc
							(start 0.3048 0.2032)
							(mid 0.275042 0.275042)
							(end 0.2032 0.3048)
						)
						(arc
							(start -0.2032 0.3048)
							(mid -0.275042 0.275042)
							(end -0.3048 0.2032)
						)
						(arc
							(start -0.3048 -0.2032)
							(mid -0.275042 -0.275042)
							(end -0.2032 -0.3048)
						)
						(arc
							(start 0.2032 -0.3048)
							(mid 0.275042 -0.275042)
							(end 0.3048 -0.2032)
						)
					)
					(width 0)
					(fill yes)
				)
			)
		)
	)
	(footprint ""
		(layer "B.Cu")
		(at 204.8256 -65.3542)
		(property "Reference" "TP155"
			(at 0 0 0)
			(layer "B.SilkS")
			(hide yes)
			(effects
				(font
					(size 1.27 1.27)
				)
				(justify mirror)
			)
		)
		(property "Value" "TPAD28-2-GP"
			(at 0.0127 -1.6637 0)
			(unlocked yes)
			(layer "B.Fab")
			(hide yes)
			(effects
				(font
					(size 1.016 1.016)
					(thickness 0.1524)
				)
				(justify mirror)
			)
		)
		(property "Device Type" "TPAD28"
			(at 0.0127 -3.1877 0)
			(unlocked yes)
			(layer "B.Fab")
			(hide yes)
			(effects
				(font
					(size 1.016 1.016)
					(thickness 0.1524)
				)
				(justify mirror)
			)
		)
		(duplicate_pad_numbers_are_jumpers no)
		(fp_poly
			(pts
				(arc
					(start 0.3556 0)
					(mid -0.3556 0)
					(end 0.3556 0)
				)
			)
			(stroke
				(width 0)
				(type default)
			)
			(fill no)
			(layer "B.CrtYd")
		)
		(fp_poly
			(pts
				(arc
					(start 0.6096 0)
					(mid -0.6096 0)
					(end 0.6096 0)
				)
			)
			(stroke
				(width 0)
				(type default)
			)
			(fill no)
			(layer "B.Fab")
		)
		(pad "1" smd circle
			(at 0 0 180)
			(size 0.7112 0.7112)
			(layers "B.Cu" "B.Mask" "B.Paste")
			(net "OSC_REF_CLK")
		)
	)
	(footprint ""
		(layer "B.Cu")
		(at 183.2356 -71.12 180)
		(property "Reference" "C468"
			(at 0 0 0)
			(layer "B.SilkS")
			(hide yes)
			(effects
				(font
					(size 1.27 1.27)
				)
				(justify mirror)
			)
		)
		(property "Value" "SCD1U16V2KX-3GP"
			(at -1.1811 -2.7051 180)
			(unlocked yes)
			(layer "B.Fab")
			(hide yes)
			(effects
				(font
					(size 1.016 1.016)
					(thickness 0.1524)
				)
				(justify mirror)
			)
		)
		(property "Device Type" "C402H22"
			(at -1.1811 -4.2291 180)
			(unlocked yes)
			(layer "B.Fab")
			(hide yes)
			(effects
				(font
					(size 1.016 1.016)
					(thickness 0.1524)
				)
				(justify mirror)
			)
		)
		(duplicate_pad_numbers_are_jumpers no)
		(fp_rect
			(start 0.4318 0.9525)
			(end -0.4318 -0.9525)
			(stroke
				(width 0)
				(type default)
			)
			(fill no)
			(layer "B.CrtYd")
		)
		(fp_rect
			(start 0.4318 0.9525)
			(end -0.4318 -0.9525)
			(stroke
				(width 0)
				(type default)
			)
			(fill no)
			(layer "B.Fab")
		)
		(pad "1" smd custom
			(at 0 -0.4445)
			(size 0.1524 0.1524)
			(layers "B.Cu" "B.Mask" "B.Paste")
			(net "P1V8")
			(options
				(clearance outline)
				(anchor circle)
			)
			(primitives
				(gr_poly
					(pts
						(arc
							(start 0.3048 0.2032)
							(mid 0.275042 0.275042)
							(end 0.2032 0.3048)
						)
						(arc
							(start -0.2032 0.3048)
							(mid -0.275042 0.275042)
							(end -0.3048 0.2032)
						)
						(arc
							(start -0.3048 -0.2032)
							(mid -0.275042 -0.275042)
							(end -0.2032 -0.3048)
						)
						(arc
							(start 0.2032 -0.3048)
							(mid 0.275042 -0.275042)
							(end 0.3048 -0.2032)
						)
					)
					(width 0)
					(fill yes)
				)
			)
		)
		(pad "2" smd custom
			(at 0 0.4445)
			(size 0.1524 0.1524)
			(layers "B.Cu" "B.Mask" "B.Paste")
			(net "GND")
			(options
				(clearance outline)
				(anchor circle)
			)
			(primitives
				(gr_poly
					(pts
						(arc
							(start 0.3048 0.2032)
							(mid 0.275042 0.275042)
							(end 0.2032 0.3048)
						)
						(arc
							(start -0.2032 0.3048)
							(mid -0.275042 0.275042)
							(end -0.3048 0.2032)
						)
						(arc
							(start -0.3048 -0.2032)
							(mid -0.275042 -0.275042)
							(end -0.2032 -0.3048)
						)
						(arc
							(start 0.2032 -0.3048)
							(mid 0.275042 -0.275042)
							(end 0.3048 -0.2032)
						)
					)
					(width 0)
					(fill yes)
				)
			)
		)
	)
	(footprint ""
		(layer "B.Cu")
		(at 184.023 -66.6242 90)
		(property "Reference" "C474"
			(at 0 0 90)
			(layer "B.SilkS")
			(hide yes)
			(effects
				(font
					(size 1.27 1.27)
				)
				(justify mirror)
			)
		)
		(property "Value" "SC1KP50V2KX-1GP"
			(at -1.1811 -2.7051 90)
			(unlocked yes)
			(layer "B.Fab")
			(hide yes)
			(effects
				(font
					(size 1.016 1.016)
					(thickness 0.1524)
				)
				(justify mirror)
			)
		)
		(property "Device Type" "C402H22"
			(at -1.1811 -4.2291 90)
			(unlocked yes)
			(layer "B.Fab")
			(hide yes)
			(effects
				(font
					(size 1.016 1.016)
					(thickness 0.1524)
				)
				(justify mirror)
			)
		)
		(duplicate_pad_numbers_are_jumpers no)
		(fp_rect
			(start 0.4318 0.9525)
			(end -0.4318 -0.9525)
			(stroke
				(width 0)
				(type default)
			)
			(fill no)
			(layer "B.CrtYd")
		)
		(fp_rect
			(start 0.4318 0.9525)
			(end -0.4318 -0.9525)
			(stroke
				(width 0)
				(type default)
			)
			(fill no)
			(layer "B.Fab")
		)
		(pad "1" smd custom
			(at 0 -0.4445 270)
			(size 0.1524 0.1524)
			(layers "B.Cu" "B.Mask" "B.Paste")
			(net "P1V8")
			(options
				(clearance outline)
				(anchor circle)
			)
			(primitives
				(gr_poly
					(pts
						(arc
							(start 0.3048 0.2032)
							(mid 0.275042 0.275042)
							(end 0.2032 0.3048)
						)
						(arc
							(start -0.2032 0.3048)
							(mid -0.275042 0.275042)
							(end -0.3048 0.2032)
						)
						(arc
							(start -0.3048 -0.2032)
							(mid -0.275042 -0.275042)
							(end -0.2032 -0.3048)
						)
						(arc
							(start 0.2032 -0.3048)
							(mid 0.275042 -0.275042)
							(end 0.3048 -0.2032)
						)
					)
					(width 0)
					(fill yes)
				)
			)
		)
		(pad "2" smd custom
			(at 0 0.4445 270)
			(size 0.1524 0.1524)
			(layers "B.Cu" "B.Mask" "B.Paste")
			(net "GND")
			(options
				(clearance outline)
				(anchor circle)
			)
			(primitives
				(gr_poly
					(pts
						(arc
							(start 0.3048 0.2032)
							(mid 0.275042 0.275042)
							(end 0.2032 0.3048)
						)
						(arc
							(start -0.2032 0.3048)
							(mid -0.275042 0.275042)
							(end -0.3048 0.2032)
						)
						(arc
							(start -0.3048 -0.2032)
							(mid -0.275042 -0.275042)
							(end -0.2032 -0.3048)
						)
						(arc
							(start 0.2032 -0.3048)
							(mid 0.275042 -0.275042)
							(end 0.3048 -0.2032)
						)
					)
					(width 0)
					(fill yes)
				)
			)
		)
	)
	(footprint ""
		(layer "B.Cu")
		(at 50.75682 -148.19376 -90)
		(property "Reference" "C101"
			(at 0 0 90)
			(layer "B.SilkS")
			(hide yes)
			(effects
				(font
					(size 1.27 1.27)
				)
				(justify mirror)
			)
		)
		(property "Value" "SC1U16V3KX-5GP"
			(at 0 -2.8194 270)
			(unlocked yes)
			(layer "B.Fab")
			(hide yes)
			(effects
				(font
					(size 1.016 1.016)
					(thickness 0.1524)
				)
				(justify mirror)
			)
		)
		(property "Device Type" "C603H36"
			(at 0 -4.3434 270)
			(unlocked yes)
			(layer "B.Fab")
			(hide yes)
			(effects
				(font
					(size 1.016 1.016)
					(thickness 0.1524)
				)
				(justify mirror)
			)
		)
		(duplicate_pad_numbers_are_jumpers no)
		(fp_line
			(start -0.508 0)
			(end 0.508 0)
			(stroke
				(width 0.2032)
				(type default)
			)
			(layer "B.SilkS")
		)
		(fp_rect
			(start 0.5842 1.3335)
			(end -0.5842 -1.3335)
			(stroke
				(width 0)
				(type default)
			)
			(fill no)
			(layer "B.CrtYd")
		)
		(fp_rect
			(start 0.5842 1.3335)
			(end -0.5842 -1.3335)
			(stroke
				(width 0)
				(type default)
			)
			(fill no)
			(layer "B.Fab")
		)
		(pad "1" smd custom
			(at 0 -0.762 90)
			(size 0.2159 0.2159)
			(layers "B.Cu" "B.Mask" "B.Paste")
			(net "P3V3_STBY")
			(options
				(clearance outline)
				(anchor circle)
			)
			(primitives
				(gr_poly
					(pts
						(arc
							(start -0.3302 0.4318)
							(mid -0.402042 0.402042)
							(end -0.4318 0.3302)
						)
						(arc
							(start -0.4318 -0.3302)
							(mid -0.402042 -0.402042)
							(end -0.3302 -0.4318)
						)
						(arc
							(start 0.3302 -0.4318)
							(mid 0.402042 -0.402042)
							(end 0.4318 -0.3302)
						)
						(arc
							(start 0.4318 0.3302)
							(mid 0.402042 0.402042)
							(end 0.3302 0.4318)
						)
					)
					(width 0)
					(fill yes)
				)
			)
		)
		(pad "2" smd custom
			(at 0 0.762 90)
			(size 0.2159 0.2159)
			(layers "B.Cu" "B.Mask" "B.Paste")
			(net "GND")
			(options
				(clearance outline)
				(anchor circle)
			)
			(primitives
				(gr_poly
					(pts
						(arc
							(start -0.3302 0.4318)
							(mid -0.402042 0.402042)
							(end -0.4318 0.3302)
						)
						(arc
							(start -0.4318 -0.3302)
							(mid -0.402042 -0.402042)
							(end -0.3302 -0.4318)
						)
						(arc
							(start 0.3302 -0.4318)
							(mid 0.402042 -0.402042)
							(end 0.4318 -0.3302)
						)
						(arc
							(start 0.4318 0.3302)
							(mid 0.402042 0.402042)
							(end 0.3302 0.4318)
						)
					)
					(width 0)
					(fill yes)
				)
			)
		)
	)
	(footprint ""
		(layer "B.Cu")
		(at 207.3148 -79.9084 90)
		(property "Reference" "R349"
			(at 0 0 90)
			(layer "B.SilkS")
			(hide yes)
			(effects
				(font
					(size 1.27 1.27)
				)
				(justify mirror)
			)
		)
		(property "Value" "0R2J-2-GP"
			(at -0.064008 -3.993896 90)
			(unlocked yes)
			(layer "B.Fab")
			(hide yes)
			(effects
				(font
					(size 1.016 1.016)
					(thickness 0.1524)
				)
				(justify mirror)
			)
		)
		(property "Device Type" "R402H16"
			(at -0.064008 -5.517896 90)
			(unlocked yes)
			(layer "B.Fab")
			(hide yes)
			(effects
				(font
					(size 1.016 1.016)
					(thickness 0.1524)
				)
				(justify mirror)
			)
		)
		(duplicate_pad_numbers_are_jumpers no)
		(fp_line
			(start 0.508 -0.9398)
			(end 0.508 0.9398)
			(stroke
				(width 0.1524)
				(type default)
			)
			(layer "B.SilkS")
		)
		(fp_line
			(start -0.508 -0.9398)
			(end 0.508 -0.9398)
			(stroke
				(width 0.1524)
				(type default)
			)
			(layer "B.SilkS")
		)
		(fp_rect
			(start 0.508 0.9398)
			(end -0.508 -0.9398)
			(stroke
				(width 0)
				(type default)
			)
			(fill no)
			(layer "B.CrtYd")
		)
		(fp_rect
			(start 0.508 0.9398)
			(end -0.508 -0.9398)
			(stroke
				(width 0)
				(type default)
			)
			(fill no)
			(layer "B.Fab")
		)
		(pad "1" smd custom
			(at 0 -0.4445 270)
			(size 0.1397 0.1397)
			(layers "B.Cu" "B.Mask" "B.Paste")
			(net "P0V975")
			(options
				(clearance outline)
				(anchor circle)
			)
			(primitives
				(gr_poly
					(pts
						(arc
							(start -0.1778 0.2794)
							(mid -0.249642 0.249642)
							(end -0.2794 0.1778)
						)
						(arc
							(start -0.2794 -0.1778)
							(mid -0.249642 -0.249642)
							(end -0.1778 -0.2794)
						)
						(arc
							(start 0.1778 -0.2794)
							(mid 0.249642 -0.249642)
							(end 0.2794 -0.1778)
						)
						(arc
							(start 0.2794 0.1778)
							(mid 0.249642 0.249642)
							(end 0.1778 0.2794)
						)
					)
					(width 0)
					(fill yes)
				)
			)
		)
		(pad "2" smd custom
			(at 0 0.4445 270)
			(size 0.1397 0.1397)
			(layers "B.Cu" "B.Mask" "B.Paste")
			(net "P0V975_SEN")
			(options
				(clearance outline)
				(anchor circle)
			)
			(primitives
				(gr_poly
					(pts
						(arc
							(start -0.1778 0.2794)
							(mid -0.249642 0.249642)
							(end -0.2794 0.1778)
						)
						(arc
							(start -0.2794 -0.1778)
							(mid -0.249642 -0.249642)
							(end -0.1778 -0.2794)
						)
						(arc
							(start 0.1778 -0.2794)
							(mid 0.249642 -0.249642)
							(end 0.2794 -0.1778)
						)
						(arc
							(start 0.2794 0.1778)
							(mid 0.249642 0.249642)
							(end 0.1778 0.2794)
						)
					)
					(width 0)
					(fill yes)
				)
			)
		)
	)
	(footprint ""
		(layer "B.Cu")
		(at 81.026 -140.4366 -90)
		(property "Reference" "R720"
			(at 0 0 90)
			(layer "B.SilkS")
			(hide yes)
			(effects
				(font
					(size 1.27 1.27)
				)
				(justify mirror)
			)
		)
		(property "Value" "0R2J-2-GP"
			(at -0.064008 -3.993896 270)
			(unlocked yes)
			(layer "B.Fab")
			(hide yes)
			(effects
				(font
					(size 1.016 1.016)
					(thickness 0.1524)
				)
				(justify mirror)
			)
		)
		(property "Device Type" "R402H16"
			(at -0.064008 -5.517896 270)
			(unlocked yes)
			(layer "B.Fab")
			(hide yes)
			(effects
				(font
					(size 1.016 1.016)
					(thickness 0.1524)
				)
				(justify mirror)
			)
		)
		(duplicate_pad_numbers_are_jumpers no)
		(fp_line
			(start -0.508 -0.9398)
			(end 0.508 -0.9398)
			(stroke
				(width 0.1524)
				(type default)
			)
			(layer "B.SilkS")
		)
		(fp_line
			(start 0.508 -0.9398)
			(end 0.508 0.9398)
			(stroke
				(width 0.1524)
				(type default)
			)
			(layer "B.SilkS")
		)
		(fp_rect
			(start 0.508 0.9398)
			(end -0.508 -0.9398)
			(stroke
				(width 0)
				(type default)
			)
			(fill no)
			(layer "B.CrtYd")
		)
		(fp_rect
			(start 0.508 0.9398)
			(end -0.508 -0.9398)
			(stroke
				(width 0)
				(type default)
			)
			(fill no)
			(layer "B.Fab")
		)
		(pad "1" smd custom
			(at 0 -0.4445 90)
			(size 0.1397 0.1397)
			(layers "B.Cu" "B.Mask" "B.Paste")
			(net "PWRGD_P3V3_STBY_N")
			(options
				(clearance outline)
				(anchor circle)
			)
			(primitives
				(gr_poly
					(pts
						(arc
							(start -0.1778 0.2794)
							(mid -0.249642 0.249642)
							(end -0.2794 0.1778)
						)
						(arc
							(start -0.2794 -0.1778)
							(mid -0.249642 -0.249642)
							(end -0.1778 -0.2794)
						)
						(arc
							(start 0.1778 -0.2794)
							(mid 0.249642 -0.249642)
							(end 0.2794 -0.1778)
						)
						(arc
							(start 0.2794 0.1778)
							(mid 0.249642 0.249642)
							(end 0.1778 0.2794)
						)
					)
					(width 0)
					(fill yes)
				)
			)
		)
		(pad "2" smd custom
			(at 0 0.4445 90)
			(size 0.1397 0.1397)
			(layers "B.Cu" "B.Mask" "B.Paste")
			(net "PWRGD_P3V3_STBY_N_R1")
			(options
				(clearance outline)
				(anchor circle)
			)
			(primitives
				(gr_poly
					(pts
						(arc
							(start -0.1778 0.2794)
							(mid -0.249642 0.249642)
							(end -0.2794 0.1778)
						)
						(arc
							(start -0.2794 -0.1778)
							(mid -0.249642 -0.249642)
							(end -0.1778 -0.2794)
						)
						(arc
							(start 0.1778 -0.2794)
							(mid 0.249642 -0.249642)
							(end 0.2794 -0.1778)
						)
						(arc
							(start 0.2794 0.1778)
							(mid 0.249642 0.249642)
							(end 0.1778 0.2794)
						)
					)
					(width 0)
					(fill yes)
				)
			)
		)
	)
	(footprint ""
		(layer "B.Cu")
		(at 166.79291 -76.242164)
		(property "Reference" "R676"
			(at 0 0 0)
			(layer "B.SilkS")
			(hide yes)
			(effects
				(font
					(size 1.27 1.27)
				)
				(justify mirror)
			)
		)
		(property "Value" "10KR2F-2-GP"
			(at -0.064008 -3.993896 0)
			(unlocked yes)
			(layer "B.Fab")
			(hide yes)
			(effects
				(font
					(size 1.016 1.016)
					(thickness 0.1524)
				)
				(justify mirror)
			)
		)
		(property "Device Type" "R402H16"
			(at -0.064008 -5.517896 0)
			(unlocked yes)
			(layer "B.Fab")
			(hide yes)
			(effects
				(font
					(size 1.016 1.016)
					(thickness 0.1524)
				)
				(justify mirror)
			)
		)
		(duplicate_pad_numbers_are_jumpers no)
		(fp_line
			(start -0.508 -0.9398)
			(end 0.508 -0.9398)
			(stroke
				(width 0.1524)
				(type default)
			)
			(layer "B.SilkS")
		)
		(fp_line
			(start 0.508 -0.9398)
			(end 0.508 0.9398)
			(stroke
				(width 0.1524)
				(type default)
			)
			(layer "B.SilkS")
		)
		(fp_rect
			(start 0.508 0.9398)
			(end -0.508 -0.9398)
			(stroke
				(width 0)
				(type default)
			)
			(fill no)
			(layer "B.CrtYd")
		)
		(fp_rect
			(start 0.508 0.9398)
			(end -0.508 -0.9398)
			(stroke
				(width 0)
				(type default)
			)
			(fill no)
			(layer "B.Fab")
		)
		(pad "1" smd custom
			(at 0 -0.4445 180)
			(size 0.1397 0.1397)
			(layers "B.Cu" "B.Mask" "B.Paste")
			(net "P1V8")
			(options
				(clearance outline)
				(anchor circle)
			)
			(primitives
				(gr_poly
					(pts
						(arc
							(start -0.1778 0.2794)
							(mid -0.249642 0.249642)
							(end -0.2794 0.1778)
						)
						(arc
							(start -0.2794 -0.1778)
							(mid -0.249642 -0.249642)
							(end -0.1778 -0.2794)
						)
						(arc
							(start 0.1778 -0.2794)
							(mid 0.249642 -0.249642)
							(end 0.2794 -0.1778)
						)
						(arc
							(start 0.2794 0.1778)
							(mid 0.249642 0.249642)
							(end 0.1778 0.2794)
						)
					)
					(width 0)
					(fill yes)
				)
			)
		)
		(pad "2" smd custom
			(at 0 0.4445 180)
			(size 0.1397 0.1397)
			(layers "B.Cu" "B.Mask" "B.Paste")
			(net "IOC_WP_N")
			(options
				(clearance outline)
				(anchor circle)
			)
			(primitives
				(gr_poly
					(pts
						(arc
							(start -0.1778 0.2794)
							(mid -0.249642 0.249642)
							(end -0.2794 0.1778)
						)
						(arc
							(start -0.2794 -0.1778)
							(mid -0.249642 -0.249642)
							(end -0.1778 -0.2794)
						)
						(arc
							(start 0.1778 -0.2794)
							(mid 0.249642 -0.249642)
							(end 0.2794 -0.1778)
						)
						(arc
							(start 0.2794 0.1778)
							(mid 0.249642 0.249642)
							(end 0.1778 0.2794)
						)
					)
					(width 0)
					(fill yes)
				)
			)
		)
	)
	(footprint ""
		(layer "B.Cu")
		(at 87.837518 -146.263614 -90)
		(property "Reference" "R424"
			(at 0 0 90)
			(layer "B.SilkS")
			(hide yes)
			(effects
				(font
					(size 1.27 1.27)
				)
				(justify mirror)
			)
		)
		(property "Value" "4K7R2F-GP"
			(at -0.064008 -3.993896 270)
			(unlocked yes)
			(layer "B.Fab")
			(hide yes)
			(effects
				(font
					(size 1.016 1.016)
					(thickness 0.1524)
				)
				(justify mirror)
			)
		)
		(property "Device Type" "R402H16"
			(at -0.064008 -5.517896 270)
			(unlocked yes)
			(layer "B.Fab")
			(hide yes)
			(effects
				(font
					(size 1.016 1.016)
					(thickness 0.1524)
				)
				(justify mirror)
			)
		)
		(duplicate_pad_numbers_are_jumpers no)
		(fp_line
			(start -0.508 -0.9398)
			(end 0.508 -0.9398)
			(stroke
				(width 0.1524)
				(type default)
			)
			(layer "B.SilkS")
		)
		(fp_line
			(start 0.508 -0.9398)
			(end 0.508 0.9398)
			(stroke
				(width 0.1524)
				(type default)
			)
			(layer "B.SilkS")
		)
		(fp_rect
			(start 0.508 0.9398)
			(end -0.508 -0.9398)
			(stroke
				(width 0)
				(type default)
			)
			(fill no)
			(layer "B.CrtYd")
		)
		(fp_rect
			(start 0.508 0.9398)
			(end -0.508 -0.9398)
			(stroke
				(width 0)
				(type default)
			)
			(fill no)
			(layer "B.Fab")
		)
		(pad "1" smd custom
			(at 0 -0.4445 90)
			(size 0.1397 0.1397)
			(layers "B.Cu" "B.Mask" "B.Paste")
			(net "P3V3_STBY")
			(options
				(clearance outline)
				(anchor circle)
			)
			(primitives
				(gr_poly
					(pts
						(arc
							(start -0.1778 0.2794)
							(mid -0.249642 0.249642)
							(end -0.2794 0.1778)
						)
						(arc
							(start -0.2794 -0.1778)
							(mid -0.249642 -0.249642)
							(end -0.1778 -0.2794)
						)
						(arc
							(start 0.1778 -0.2794)
							(mid 0.249642 -0.249642)
							(end 0.2794 -0.1778)
						)
						(arc
							(start 0.2794 0.1778)
							(mid 0.249642 0.249642)
							(end 0.1778 0.2794)
						)
					)
					(width 0)
					(fill yes)
				)
			)
		)
		(pad "2" smd custom
			(at 0 0.4445 90)
			(size 0.1397 0.1397)
			(layers "B.Cu" "B.Mask" "B.Paste")
			(net "TCA9555_A1")
			(options
				(clearance outline)
				(anchor circle)
			)
			(primitives
				(gr_poly
					(pts
						(arc
							(start -0.1778 0.2794)
							(mid -0.249642 0.249642)
							(end -0.2794 0.1778)
						)
						(arc
							(start -0.2794 -0.1778)
							(mid -0.249642 -0.249642)
							(end -0.1778 -0.2794)
						)
						(arc
							(start 0.1778 -0.2794)
							(mid 0.249642 -0.249642)
							(end 0.2794 -0.1778)
						)
						(arc
							(start 0.2794 0.1778)
							(mid 0.249642 0.249642)
							(end 0.1778 0.2794)
						)
					)
					(width 0)
					(fill yes)
				)
			)
		)
	)
	(footprint ""
		(layer "B.Cu")
		(at 45.1485 -153.2255)
		(property "Reference" "TP190"
			(at 0 0 0)
			(layer "B.SilkS")
			(hide yes)
			(effects
				(font
					(size 1.27 1.27)
				)
				(justify mirror)
			)
		)
		(property "Value" "TPAD28-2-GP"
			(at 0.0127 -1.6637 0)
			(unlocked yes)
			(layer "B.Fab")
			(hide yes)
			(effects
				(font
					(size 1.016 1.016)
					(thickness 0.1524)
				)
				(justify mirror)
			)
		)
		(property "Device Type" "TPAD28"
			(at 0.0127 -3.1877 0)
			(unlocked yes)
			(layer "B.Fab")
			(hide yes)
			(effects
				(font
					(size 1.016 1.016)
					(thickness 0.1524)
				)
				(justify mirror)
			)
		)
		(duplicate_pad_numbers_are_jumpers no)
		(fp_poly
			(pts
				(arc
					(start 0.3556 0)
					(mid -0.3556 0)
					(end 0.3556 0)
				)
			)
			(stroke
				(width 0)
				(type default)
			)
			(fill no)
			(layer "B.CrtYd")
		)
		(fp_poly
			(pts
				(arc
					(start 0.6096 0)
					(mid -0.6096 0)
					(end 0.6096 0)
				)
			)
			(stroke
				(width 0)
				(type default)
			)
			(fill no)
			(layer "B.Fab")
		)
		(pad "1" smd circle
			(at 0 0 180)
			(size 0.7112 0.7112)
			(layers "B.Cu" "B.Mask" "B.Paste")
			(net "TP_BMC_GPIOL4")
		)
	)
	(footprint ""
		(layer "B.Cu")
		(at 38.45179 -119.014748 -90)
		(property "Reference" "R285"
			(at 0 0 90)
			(layer "B.SilkS")
			(hide yes)
			(effects
				(font
					(size 1.27 1.27)
				)
				(justify mirror)
			)
		)
		(property "Value" "4K7R2F-GP"
			(at -0.064008 -3.993896 270)
			(unlocked yes)
			(layer "B.Fab")
			(hide yes)
			(effects
				(font
					(size 1.016 1.016)
					(thickness 0.1524)
				)
				(justify mirror)
			)
		)
		(property "Device Type" "R402H16"
			(at -0.064008 -5.517896 270)
			(unlocked yes)
			(layer "B.Fab")
			(hide yes)
			(effects
				(font
					(size 1.016 1.016)
					(thickness 0.1524)
				)
				(justify mirror)
			)
		)
		(duplicate_pad_numbers_are_jumpers no)
		(fp_line
			(start -0.508 -0.9398)
			(end 0.508 -0.9398)
			(stroke
				(width 0.1524)
				(type default)
			)
			(layer "B.SilkS")
		)
		(fp_line
			(start 0.508 -0.9398)
			(end 0.508 0.9398)
			(stroke
				(width 0.1524)
				(type default)
			)
			(layer "B.SilkS")
		)
		(fp_rect
			(start 0.508 0.9398)
			(end -0.508 -0.9398)
			(stroke
				(width 0)
				(type default)
			)
			(fill no)
			(layer "B.CrtYd")
		)
		(fp_rect
			(start 0.508 0.9398)
			(end -0.508 -0.9398)
			(stroke
				(width 0)
				(type default)
			)
			(fill no)
			(layer "B.Fab")
		)
		(pad "1" smd custom
			(at 0 -0.4445 90)
			(size 0.1397 0.1397)
			(layers "B.Cu" "B.Mask" "B.Paste")
			(net "TEMP_3_A1")
			(options
				(clearance outline)
				(anchor circle)
			)
			(primitives
				(gr_poly
					(pts
						(arc
							(start -0.1778 0.2794)
							(mid -0.249642 0.249642)
							(end -0.2794 0.1778)
						)
						(arc
							(start -0.2794 -0.1778)
							(mid -0.249642 -0.249642)
							(end -0.1778 -0.2794)
						)
						(arc
							(start 0.1778 -0.2794)
							(mid 0.249642 -0.249642)
							(end 0.2794 -0.1778)
						)
						(arc
							(start 0.2794 0.1778)
							(mid 0.249642 0.249642)
							(end 0.1778 0.2794)
						)
					)
					(width 0)
					(fill yes)
				)
			)
		)
		(pad "2" smd custom
			(at 0 0.4445 90)
			(size 0.1397 0.1397)
			(layers "B.Cu" "B.Mask" "B.Paste")
			(net "GND")
			(options
				(clearance outline)
				(anchor circle)
			)
			(primitives
				(gr_poly
					(pts
						(arc
							(start -0.1778 0.2794)
							(mid -0.249642 0.249642)
							(end -0.2794 0.1778)
						)
						(arc
							(start -0.2794 -0.1778)
							(mid -0.249642 -0.249642)
							(end -0.1778 -0.2794)
						)
						(arc
							(start 0.1778 -0.2794)
							(mid 0.249642 -0.249642)
							(end 0.2794 -0.1778)
						)
						(arc
							(start 0.2794 0.1778)
							(mid 0.249642 0.249642)
							(end 0.1778 0.2794)
						)
					)
					(width 0)
					(fill yes)
				)
			)
		)
	)
	(footprint ""
		(layer "B.Cu")
		(at 201.177398 -47.807372 -90)
		(property "Reference" "L14"
			(at 0 0 90)
			(layer "B.SilkS")
			(hide yes)
			(effects
				(font
					(size 1.27 1.27)
				)
				(justify mirror)
			)
		)
		(property "Value" "MPZ2012S601AT-GP"
			(at 0 -4.2418 270)
			(unlocked yes)
			(layer "B.Fab")
			(hide yes)
			(effects
				(font
					(size 1.016 1.016)
					(thickness 0.1524)
				)
				(justify mirror)
			)
		)
		(property "Device Type" "L805H42"
			(at 0 -5.7912 270)
			(unlocked yes)
			(layer "B.Fab")
			(hide yes)
			(effects
				(font
					(size 1.016 1.016)
					(thickness 0.1524)
				)
				(justify mirror)
			)
		)
		(duplicate_pad_numbers_are_jumpers no)
		(fp_line
			(start -0.889 1.7018)
			(end 0.889 1.7018)
			(stroke
				(width 0.1524)
				(type default)
			)
			(layer "B.SilkS")
		)
		(fp_line
			(start 0.889 1.7018)
			(end 0.889 -1.7018)
			(stroke
				(width 0.1524)
				(type default)
			)
			(layer "B.SilkS")
		)
		(fp_line
			(start -0.889 -1.7018)
			(end -0.889 1.7018)
			(stroke
				(width 0.1524)
				(type default)
			)
			(layer "B.SilkS")
		)
		(fp_line
			(start 0.889 -1.7018)
			(end -0.889 -1.7018)
			(stroke
				(width 0.1524)
				(type default)
			)
			(layer "B.SilkS")
		)
		(fp_rect
			(start 0.9652 1.778)
			(end -0.9652 -1.778)
			(stroke
				(width 0)
				(type default)
			)
			(fill no)
			(layer "B.CrtYd")
		)
		(fp_rect
			(start 0.9652 1.778)
			(end -0.9652 -1.778)
			(stroke
				(width 0)
				(type default)
			)
			(fill no)
			(layer "B.Fab")
		)
		(pad "1" smd rect
			(at 0 -0.9652 90)
			(size 1.397 1.143)
			(layers "B.Cu" "B.Mask" "B.Paste")
			(net "SYS_PLL_VDD")
		)
		(pad "2" smd rect
			(at 0 0.9652 90)
			(size 1.397 1.143)
			(layers "B.Cu" "B.Mask" "B.Paste")
			(net "P1V8")
		)
	)
	(footprint ""
		(layer "B.Cu")
		(at 189.9412 -66.6369 -90)
		(property "Reference" "C430"
			(at 0 0 90)
			(layer "B.SilkS")
			(hide yes)
			(effects
				(font
					(size 1.27 1.27)
				)
				(justify mirror)
			)
		)
		(property "Value" "SC1KP50V2KX-1GP"
			(at -1.1811 -2.7051 270)
			(unlocked yes)
			(layer "B.Fab")
			(hide yes)
			(effects
				(font
					(size 1.016 1.016)
					(thickness 0.1524)
				)
				(justify mirror)
			)
		)
		(property "Device Type" "C402H22"
			(at -1.1811 -4.2291 270)
			(unlocked yes)
			(layer "B.Fab")
			(hide yes)
			(effects
				(font
					(size 1.016 1.016)
					(thickness 0.1524)
				)
				(justify mirror)
			)
		)
		(duplicate_pad_numbers_are_jumpers no)
		(fp_rect
			(start 0.4318 0.9525)
			(end -0.4318 -0.9525)
			(stroke
				(width 0)
				(type default)
			)
			(fill no)
			(layer "B.CrtYd")
		)
		(fp_rect
			(start 0.4318 0.9525)
			(end -0.4318 -0.9525)
			(stroke
				(width 0)
				(type default)
			)
			(fill no)
			(layer "B.Fab")
		)
		(pad "1" smd custom
			(at 0 -0.4445 90)
			(size 0.1524 0.1524)
			(layers "B.Cu" "B.Mask" "B.Paste")
			(net "P0V975")
			(options
				(clearance outline)
				(anchor circle)
			)
			(primitives
				(gr_poly
					(pts
						(arc
							(start 0.3048 0.2032)
							(mid 0.275042 0.275042)
							(end 0.2032 0.3048)
						)
						(arc
							(start -0.2032 0.3048)
							(mid -0.275042 0.275042)
							(end -0.3048 0.2032)
						)
						(arc
							(start -0.3048 -0.2032)
							(mid -0.275042 -0.275042)
							(end -0.2032 -0.3048)
						)
						(arc
							(start 0.2032 -0.3048)
							(mid 0.275042 -0.275042)
							(end 0.3048 -0.2032)
						)
					)
					(width 0)
					(fill yes)
				)
			)
		)
		(pad "2" smd custom
			(at 0 0.4445 90)
			(size 0.1524 0.1524)
			(layers "B.Cu" "B.Mask" "B.Paste")
			(net "GND")
			(options
				(clearance outline)
				(anchor circle)
			)
			(primitives
				(gr_poly
					(pts
						(arc
							(start 0.3048 0.2032)
							(mid 0.275042 0.275042)
							(end 0.2032 0.3048)
						)
						(arc
							(start -0.2032 0.3048)
							(mid -0.275042 0.275042)
							(end -0.3048 0.2032)
						)
						(arc
							(start -0.3048 -0.2032)
							(mid -0.275042 -0.275042)
							(end -0.2032 -0.3048)
						)
						(arc
							(start 0.2032 -0.3048)
							(mid 0.275042 -0.275042)
							(end 0.3048 -0.2032)
						)
					)
					(width 0)
					(fill yes)
				)
			)
		)
	)
	(footprint ""
		(layer "B.Cu")
		(at 180.213 -78.3336 -90)
		(property "Reference" "TP97"
			(at 0 0 90)
			(layer "B.SilkS")
			(hide yes)
			(effects
				(font
					(size 1.27 1.27)
				)
				(justify mirror)
			)
		)
		(property "Value" "TPAD28-2-GP"
			(at 0.0127 -1.6637 270)
			(unlocked yes)
			(layer "B.Fab")
			(hide yes)
			(effects
				(font
					(size 1.016 1.016)
					(thickness 0.1524)
				)
				(justify mirror)
			)
		)
		(property "Device Type" "TPAD28"
			(at 0.0127 -3.1877 270)
			(unlocked yes)
			(layer "B.Fab")
			(hide yes)
			(effects
				(font
					(size 1.016 1.016)
					(thickness 0.1524)
				)
				(justify mirror)
			)
		)
		(duplicate_pad_numbers_are_jumpers no)
		(fp_poly
			(pts
				(arc
					(start 0 -0.3556)
					(mid 0 0.3556)
					(end 0 -0.3556)
				)
			)
			(stroke
				(width 0)
				(type default)
			)
			(fill no)
			(layer "B.CrtYd")
		)
		(fp_poly
			(pts
				(arc
					(start 0 -0.6096)
					(mid 0 0.6096)
					(end 0 -0.6096)
				)
			)
			(stroke
				(width 0)
				(type default)
			)
			(fill no)
			(layer "B.Fab")
		)
		(pad "1" smd circle
			(at 0 0 90)
			(size 0.7112 0.7112)
			(layers "B.Cu" "B.Mask" "B.Paste")
			(net "IOC_GPIO_12")
		)
	)
	(footprint ""
		(layer "B.Cu")
		(at 201.629518 -81.153 180)
		(property "Reference" "C289"
			(at 0 0 0)
			(layer "B.SilkS")
			(hide yes)
			(effects
				(font
					(size 1.27 1.27)
				)
				(justify mirror)
			)
		)
		(property "Value" "SCD22U10V1KX-GP"
			(at 2.8321 -1.7399 180)
			(unlocked yes)
			(layer "B.Fab")
			(hide yes)
			(effects
				(font
					(size 1.016 1.016)
					(thickness 0.1524)
				)
				(justify mirror)
			)
		)
		(property "Device Type" "C0201H13"
			(at 2.8321 -3.2639 180)
			(unlocked yes)
			(layer "B.Fab")
			(hide yes)
			(effects
				(font
					(size 1.016 1.016)
					(thickness 0.1524)
				)
				(justify mirror)
			)
		)
		(duplicate_pad_numbers_are_jumpers no)
		(fp_rect
			(start 0.2794 0.6477)
			(end -0.2794 -0.6477)
			(stroke
				(width 0)
				(type default)
			)
			(fill no)
			(layer "B.CrtYd")
		)
		(fp_rect
			(start 0.2794 0.6477)
			(end -0.2794 -0.6477)
			(stroke
				(width 0)
				(type default)
			)
			(fill no)
			(layer "B.Fab")
		)
		(pad "1" smd custom
			(at 0 -0.2794)
			(size 0.0762 0.0762)
			(layers "B.Cu" "B.Mask" "B.Paste")
			(net "PCIE_IOM_TO_COMP_8_DP_C")
			(options
				(clearance outline)
				(anchor circle)
			)
			(primitives
				(gr_poly
					(pts
						(arc
							(start 0.1524 0.127)
							(mid 0.137521 0.162921)
							(end 0.1016 0.1778)
						)
						(arc
							(start -0.1016 0.1778)
							(mid -0.137521 0.162921)
							(end -0.1524 0.127)
						)
						(arc
							(start -0.1524 -0.127)
							(mid -0.137521 -0.162921)
							(end -0.1016 -0.1778)
						)
						(arc
							(start 0.1016 -0.1778)
							(mid 0.137521 -0.162921)
							(end 0.1524 -0.127)
						)
					)
					(width 0)
					(fill yes)
				)
			)
		)
		(pad "2" smd custom
			(at 0 0.2794)
			(size 0.0762 0.0762)
			(layers "B.Cu" "B.Mask" "B.Paste")
			(net "PCIE_IOM_TO_COMP_8_DP")
			(options
				(clearance outline)
				(anchor circle)
			)
			(primitives
				(gr_poly
					(pts
						(arc
							(start 0.1524 0.127)
							(mid 0.137521 0.162921)
							(end 0.1016 0.1778)
						)
						(arc
							(start -0.1016 0.1778)
							(mid -0.137521 0.162921)
							(end -0.1524 0.127)
						)
						(arc
							(start -0.1524 -0.127)
							(mid -0.137521 -0.162921)
							(end -0.1016 -0.1778)
						)
						(arc
							(start 0.1016 -0.1778)
							(mid 0.137521 -0.162921)
							(end 0.1524 -0.127)
						)
					)
					(width 0)
					(fill yes)
				)
			)
		)
	)
	(footprint ""
		(layer "B.Cu")
		(at 183.9849 -58.79084 90)
		(property "Reference" "C479"
			(at 0 0 90)
			(layer "B.SilkS")
			(hide yes)
			(effects
				(font
					(size 1.27 1.27)
				)
				(justify mirror)
			)
		)
		(property "Value" "SC1KP50V2KX-1GP"
			(at -1.1811 -2.7051 90)
			(unlocked yes)
			(layer "B.Fab")
			(hide yes)
			(effects
				(font
					(size 1.016 1.016)
					(thickness 0.1524)
				)
				(justify mirror)
			)
		)
		(property "Device Type" "C402H22"
			(at -1.1811 -4.2291 90)
			(unlocked yes)
			(layer "B.Fab")
			(hide yes)
			(effects
				(font
					(size 1.016 1.016)
					(thickness 0.1524)
				)
				(justify mirror)
			)
		)
		(duplicate_pad_numbers_are_jumpers no)
		(fp_rect
			(start 0.4318 0.9525)
			(end -0.4318 -0.9525)
			(stroke
				(width 0)
				(type default)
			)
			(fill no)
			(layer "B.CrtYd")
		)
		(fp_rect
			(start 0.4318 0.9525)
			(end -0.4318 -0.9525)
			(stroke
				(width 0)
				(type default)
			)
			(fill no)
			(layer "B.Fab")
		)
		(pad "1" smd custom
			(at 0 -0.4445 270)
			(size 0.1524 0.1524)
			(layers "B.Cu" "B.Mask" "B.Paste")
			(net "P1V8")
			(options
				(clearance outline)
				(anchor circle)
			)
			(primitives
				(gr_poly
					(pts
						(arc
							(start 0.3048 0.2032)
							(mid 0.275042 0.275042)
							(end 0.2032 0.3048)
						)
						(arc
							(start -0.2032 0.3048)
							(mid -0.275042 0.275042)
							(end -0.3048 0.2032)
						)
						(arc
							(start -0.3048 -0.2032)
							(mid -0.275042 -0.275042)
							(end -0.2032 -0.3048)
						)
						(arc
							(start 0.2032 -0.3048)
							(mid 0.275042 -0.275042)
							(end 0.3048 -0.2032)
						)
					)
					(width 0)
					(fill yes)
				)
			)
		)
		(pad "2" smd custom
			(at 0 0.4445 270)
			(size 0.1524 0.1524)
			(layers "B.Cu" "B.Mask" "B.Paste")
			(net "GND")
			(options
				(clearance outline)
				(anchor circle)
			)
			(primitives
				(gr_poly
					(pts
						(arc
							(start 0.3048 0.2032)
							(mid 0.275042 0.275042)
							(end 0.2032 0.3048)
						)
						(arc
							(start -0.2032 0.3048)
							(mid -0.275042 0.275042)
							(end -0.3048 0.2032)
						)
						(arc
							(start -0.3048 -0.2032)
							(mid -0.275042 -0.275042)
							(end -0.2032 -0.3048)
						)
						(arc
							(start 0.2032 -0.3048)
							(mid 0.275042 -0.275042)
							(end 0.3048 -0.2032)
						)
					)
					(width 0)
					(fill yes)
				)
			)
		)
	)
	(footprint ""
		(layer "B.Cu")
		(at 193.9798 -62.1792 90)
		(property "Reference" "C421"
			(at 0 0 90)
			(layer "B.SilkS")
			(hide yes)
			(effects
				(font
					(size 1.27 1.27)
				)
				(justify mirror)
			)
		)
		(property "Value" "SCD1U6D3V1KX-GP"
			(at 2.8321 -1.7399 90)
			(unlocked yes)
			(layer "B.Fab")
			(hide yes)
			(effects
				(font
					(size 1.016 1.016)
					(thickness 0.1524)
				)
				(justify mirror)
			)
		)
		(property "Device Type" "C0201H13"
			(at 2.8321 -3.2639 90)
			(unlocked yes)
			(layer "B.Fab")
			(hide yes)
			(effects
				(font
					(size 1.016 1.016)
					(thickness 0.1524)
				)
				(justify mirror)
			)
		)
		(duplicate_pad_numbers_are_jumpers no)
		(fp_rect
			(start 0.2794 0.6477)
			(end -0.2794 -0.6477)
			(stroke
				(width 0)
				(type default)
			)
			(fill no)
			(layer "B.CrtYd")
		)
		(fp_rect
			(start 0.2794 0.6477)
			(end -0.2794 -0.6477)
			(stroke
				(width 0)
				(type default)
			)
			(fill no)
			(layer "B.Fab")
		)
		(pad "1" smd custom
			(at 0 -0.2794 270)
			(size 0.0762 0.0762)
			(layers "B.Cu" "B.Mask" "B.Paste")
			(net "P0V975")
			(options
				(clearance outline)
				(anchor circle)
			)
			(primitives
				(gr_poly
					(pts
						(arc
							(start 0.1524 0.127)
							(mid 0.137521 0.162921)
							(end 0.1016 0.1778)
						)
						(arc
							(start -0.1016 0.1778)
							(mid -0.137521 0.162921)
							(end -0.1524 0.127)
						)
						(arc
							(start -0.1524 -0.127)
							(mid -0.137521 -0.162921)
							(end -0.1016 -0.1778)
						)
						(arc
							(start 0.1016 -0.1778)
							(mid 0.137521 -0.162921)
							(end 0.1524 -0.127)
						)
					)
					(width 0)
					(fill yes)
				)
			)
		)
		(pad "2" smd custom
			(at 0 0.2794 270)
			(size 0.0762 0.0762)
			(layers "B.Cu" "B.Mask" "B.Paste")
			(net "GND")
			(options
				(clearance outline)
				(anchor circle)
			)
			(primitives
				(gr_poly
					(pts
						(arc
							(start 0.1524 0.127)
							(mid 0.137521 0.162921)
							(end 0.1016 0.1778)
						)
						(arc
							(start -0.1016 0.1778)
							(mid -0.137521 0.162921)
							(end -0.1524 0.127)
						)
						(arc
							(start -0.1524 -0.127)
							(mid -0.137521 -0.162921)
							(end -0.1016 -0.1778)
						)
						(arc
							(start 0.1016 -0.1778)
							(mid 0.137521 -0.162921)
							(end 0.1524 -0.127)
						)
					)
					(width 0)
					(fill yes)
				)
			)
		)
	)
	(footprint ""
		(layer "B.Cu")
		(at 168.656 -105.029 -90)
		(property "Reference" "C449"
			(at 0 0 90)
			(layer "B.SilkS")
			(hide yes)
			(effects
				(font
					(size 1.27 1.27)
				)
				(justify mirror)
			)
		)
		(property "Value" "SCD1U16V2KX-3GP"
			(at -1.1811 -2.7051 270)
			(unlocked yes)
			(layer "B.Fab")
			(hide yes)
			(effects
				(font
					(size 1.016 1.016)
					(thickness 0.1524)
				)
				(justify mirror)
			)
		)
		(property "Device Type" "C402H22"
			(at -1.1811 -4.2291 270)
			(unlocked yes)
			(layer "B.Fab")
			(hide yes)
			(effects
				(font
					(size 1.016 1.016)
					(thickness 0.1524)
				)
				(justify mirror)
			)
		)
		(duplicate_pad_numbers_are_jumpers no)
		(fp_rect
			(start 0.4318 0.9525)
			(end -0.4318 -0.9525)
			(stroke
				(width 0)
				(type default)
			)
			(fill no)
			(layer "B.CrtYd")
		)
		(fp_rect
			(start 0.4318 0.9525)
			(end -0.4318 -0.9525)
			(stroke
				(width 0)
				(type default)
			)
			(fill no)
			(layer "B.Fab")
		)
		(pad "1" smd custom
			(at 0 -0.4445 90)
			(size 0.1524 0.1524)
			(layers "B.Cu" "B.Mask" "B.Paste")
			(net "P1V8")
			(options
				(clearance outline)
				(anchor circle)
			)
			(primitives
				(gr_poly
					(pts
						(arc
							(start 0.3048 0.2032)
							(mid 0.275042 0.275042)
							(end 0.2032 0.3048)
						)
						(arc
							(start -0.2032 0.3048)
							(mid -0.275042 0.275042)
							(end -0.3048 0.2032)
						)
						(arc
							(start -0.3048 -0.2032)
							(mid -0.275042 -0.275042)
							(end -0.2032 -0.3048)
						)
						(arc
							(start 0.2032 -0.3048)
							(mid 0.275042 -0.275042)
							(end 0.3048 -0.2032)
						)
					)
					(width 0)
					(fill yes)
				)
			)
		)
		(pad "2" smd custom
			(at 0 0.4445 90)
			(size 0.1524 0.1524)
			(layers "B.Cu" "B.Mask" "B.Paste")
			(net "GND")
			(options
				(clearance outline)
				(anchor circle)
			)
			(primitives
				(gr_poly
					(pts
						(arc
							(start 0.3048 0.2032)
							(mid 0.275042 0.275042)
							(end 0.2032 0.3048)
						)
						(arc
							(start -0.2032 0.3048)
							(mid -0.275042 0.275042)
							(end -0.3048 0.2032)
						)
						(arc
							(start -0.3048 -0.2032)
							(mid -0.275042 -0.275042)
							(end -0.2032 -0.3048)
						)
						(arc
							(start 0.2032 -0.3048)
							(mid 0.275042 -0.275042)
							(end 0.3048 -0.2032)
						)
					)
					(width 0)
					(fill yes)
				)
			)
		)
	)
	(footprint ""
		(layer "B.Cu")
		(at 41.0845 -135.89)
		(property "Reference" "TP18"
			(at 0 0 0)
			(layer "B.SilkS")
			(hide yes)
			(effects
				(font
					(size 1.27 1.27)
				)
				(justify mirror)
			)
		)
		(property "Value" "TPAD28-2-GP"
			(at 0.0127 -1.6637 0)
			(unlocked yes)
			(layer "B.Fab")
			(hide yes)
			(effects
				(font
					(size 1.016 1.016)
					(thickness 0.1524)
				)
				(justify mirror)
			)
		)
		(property "Device Type" "TPAD28"
			(at 0.0127 -3.1877 0)
			(unlocked yes)
			(layer "B.Fab")
			(hide yes)
			(effects
				(font
					(size 1.016 1.016)
					(thickness 0.1524)
				)
				(justify mirror)
			)
		)
		(duplicate_pad_numbers_are_jumpers no)
		(fp_poly
			(pts
				(arc
					(start 0.3556 0)
					(mid -0.3556 0)
					(end 0.3556 0)
				)
			)
			(stroke
				(width 0)
				(type default)
			)
			(fill no)
			(layer "B.CrtYd")
		)
		(fp_poly
			(pts
				(arc
					(start 0.6096 0)
					(mid -0.6096 0)
					(end 0.6096 0)
				)
			)
			(stroke
				(width 0)
				(type default)
			)
			(fill no)
			(layer "B.Fab")
		)
		(pad "1" smd circle
			(at 0 0 180)
			(size 0.7112 0.7112)
			(layers "B.Cu" "B.Mask" "B.Paste")
			(net "TP_BMC_GPIOR4")
		)
	)
	(footprint ""
		(layer "B.Cu")
		(at 16.3449 -147.2438 180)
		(property "Reference" "C62"
			(at 0 0 0)
			(layer "B.SilkS")
			(hide yes)
			(effects
				(font
					(size 1.27 1.27)
				)
				(justify mirror)
			)
		)
		(property "Value" "SC1U16V3KX-5GP"
			(at 0 -2.8194 180)
			(unlocked yes)
			(layer "B.Fab")
			(hide yes)
			(effects
				(font
					(size 1.016 1.016)
					(thickness 0.1524)
				)
				(justify mirror)
			)
		)
		(property "Device Type" "C603H36"
			(at 0 -4.3434 180)
			(unlocked yes)
			(layer "B.Fab")
			(hide yes)
			(effects
				(font
					(size 1.016 1.016)
					(thickness 0.1524)
				)
				(justify mirror)
			)
		)
		(duplicate_pad_numbers_are_jumpers no)
		(fp_line
			(start -0.508 0)
			(end 0.508 0)
			(stroke
				(width 0.2032)
				(type default)
			)
			(layer "B.SilkS")
		)
		(fp_rect
			(start 0.5842 1.3335)
			(end -0.5842 -1.3335)
			(stroke
				(width 0)
				(type default)
			)
			(fill no)
			(layer "B.CrtYd")
		)
		(fp_rect
			(start 0.5842 1.3335)
			(end -0.5842 -1.3335)
			(stroke
				(width 0)
				(type default)
			)
			(fill no)
			(layer "B.Fab")
		)
		(pad "1" smd custom
			(at 0 -0.762)
			(size 0.2159 0.2159)
			(layers "B.Cu" "B.Mask" "B.Paste")
			(net "P1V2_STBY")
			(options
				(clearance outline)
				(anchor circle)
			)
			(primitives
				(gr_poly
					(pts
						(arc
							(start -0.3302 0.4318)
							(mid -0.402042 0.402042)
							(end -0.4318 0.3302)
						)
						(arc
							(start -0.4318 -0.3302)
							(mid -0.402042 -0.402042)
							(end -0.3302 -0.4318)
						)
						(arc
							(start 0.3302 -0.4318)
							(mid 0.402042 -0.402042)
							(end 0.4318 -0.3302)
						)
						(arc
							(start 0.4318 0.3302)
							(mid 0.402042 0.402042)
							(end 0.3302 0.4318)
						)
					)
					(width 0)
					(fill yes)
				)
			)
		)
		(pad "2" smd custom
			(at 0 0.762)
			(size 0.2159 0.2159)
			(layers "B.Cu" "B.Mask" "B.Paste")
			(net "GND")
			(options
				(clearance outline)
				(anchor circle)
			)
			(primitives
				(gr_poly
					(pts
						(arc
							(start -0.3302 0.4318)
							(mid -0.402042 0.402042)
							(end -0.4318 0.3302)
						)
						(arc
							(start -0.4318 -0.3302)
							(mid -0.402042 -0.402042)
							(end -0.3302 -0.4318)
						)
						(arc
							(start 0.3302 -0.4318)
							(mid 0.402042 -0.402042)
							(end 0.4318 -0.3302)
						)
						(arc
							(start 0.4318 0.3302)
							(mid 0.402042 0.402042)
							(end 0.3302 0.4318)
						)
					)
					(width 0)
					(fill yes)
				)
			)
		)
	)
	(footprint ""
		(layer "B.Cu")
		(at 183.01462 -79.30134)
		(property "Reference" "TP85"
			(at 0 0 0)
			(layer "B.SilkS")
			(hide yes)
			(effects
				(font
					(size 1.27 1.27)
				)
				(justify mirror)
			)
		)
		(property "Value" "TPAD28-2-GP"
			(at 0.0127 -1.6637 0)
			(unlocked yes)
			(layer "B.Fab")
			(hide yes)
			(effects
				(font
					(size 1.016 1.016)
					(thickness 0.1524)
				)
				(justify mirror)
			)
		)
		(property "Device Type" "TPAD28"
			(at 0.0127 -3.1877 0)
			(unlocked yes)
			(layer "B.Fab")
			(hide yes)
			(effects
				(font
					(size 1.016 1.016)
					(thickness 0.1524)
				)
				(justify mirror)
			)
		)
		(duplicate_pad_numbers_are_jumpers no)
		(fp_poly
			(pts
				(arc
					(start 0.3556 0)
					(mid -0.3556 0)
					(end 0.3556 0)
				)
			)
			(stroke
				(width 0)
				(type default)
			)
			(fill no)
			(layer "B.CrtYd")
		)
		(fp_poly
			(pts
				(arc
					(start 0.6096 0)
					(mid -0.6096 0)
					(end 0.6096 0)
				)
			)
			(stroke
				(width 0)
				(type default)
			)
			(fill no)
			(layer "B.Fab")
		)
		(pad "1" smd circle
			(at 0 0 180)
			(size 0.7112 0.7112)
			(layers "B.Cu" "B.Mask" "B.Paste")
			(net "IOC_GPIO_1")
		)
	)
	(footprint ""
		(layer "B.Cu")
		(at 124.839476 -8.75157 90)
		(property "Reference" "R449"
			(at 0 0 90)
			(layer "B.SilkS")
			(hide yes)
			(effects
				(font
					(size 1.27 1.27)
				)
				(justify mirror)
			)
		)
		(property "Value" "1KR2J-1-GP"
			(at -0.064008 -3.993896 90)
			(unlocked yes)
			(layer "B.Fab")
			(hide yes)
			(effects
				(font
					(size 1.016 1.016)
					(thickness 0.1524)
				)
				(justify mirror)
			)
		)
		(property "Device Type" "R402H16"
			(at -0.064008 -5.517896 90)
			(unlocked yes)
			(layer "B.Fab")
			(hide yes)
			(effects
				(font
					(size 1.016 1.016)
					(thickness 0.1524)
				)
				(justify mirror)
			)
		)
		(duplicate_pad_numbers_are_jumpers no)
		(fp_line
			(start 0.508 -0.9398)
			(end 0.508 0.9398)
			(stroke
				(width 0.1524)
				(type default)
			)
			(layer "B.SilkS")
		)
		(fp_line
			(start -0.508 -0.9398)
			(end 0.508 -0.9398)
			(stroke
				(width 0.1524)
				(type default)
			)
			(layer "B.SilkS")
		)
		(fp_rect
			(start 0.508 0.9398)
			(end -0.508 -0.9398)
			(stroke
				(width 0)
				(type default)
			)
			(fill no)
			(layer "B.CrtYd")
		)
		(fp_rect
			(start 0.508 0.9398)
			(end -0.508 -0.9398)
			(stroke
				(width 0)
				(type default)
			)
			(fill no)
			(layer "B.Fab")
		)
		(pad "1" smd custom
			(at 0 -0.4445 270)
			(size 0.1397 0.1397)
			(layers "B.Cu" "B.Mask" "B.Paste")
			(net "MB0_CM_VOUT_R")
			(options
				(clearance outline)
				(anchor circle)
			)
			(primitives
				(gr_poly
					(pts
						(arc
							(start -0.1778 0.2794)
							(mid -0.249642 0.249642)
							(end -0.2794 0.1778)
						)
						(arc
							(start -0.2794 -0.1778)
							(mid -0.249642 -0.249642)
							(end -0.1778 -0.2794)
						)
						(arc
							(start 0.1778 -0.2794)
							(mid 0.249642 -0.249642)
							(end 0.2794 -0.1778)
						)
						(arc
							(start 0.2794 0.1778)
							(mid 0.249642 0.249642)
							(end 0.1778 0.2794)
						)
					)
					(width 0)
					(fill yes)
				)
			)
		)
		(pad "2" smd custom
			(at 0 0.4445 270)
			(size 0.1397 0.1397)
			(layers "B.Cu" "B.Mask" "B.Paste")
			(net "P12V_STBY")
			(options
				(clearance outline)
				(anchor circle)
			)
			(primitives
				(gr_poly
					(pts
						(arc
							(start -0.1778 0.2794)
							(mid -0.249642 0.249642)
							(end -0.2794 0.1778)
						)
						(arc
							(start -0.2794 -0.1778)
							(mid -0.249642 -0.249642)
							(end -0.1778 -0.2794)
						)
						(arc
							(start 0.1778 -0.2794)
							(mid 0.249642 -0.249642)
							(end 0.2794 -0.1778)
						)
						(arc
							(start 0.2794 0.1778)
							(mid 0.249642 0.249642)
							(end 0.1778 0.2794)
						)
					)
					(width 0)
					(fill yes)
				)
			)
		)
	)
	(footprint ""
		(layer "B.Cu")
		(at 187.185808 -79.093314)
		(property "Reference" "TP91"
			(at 0 0 0)
			(layer "B.SilkS")
			(hide yes)
			(effects
				(font
					(size 1.27 1.27)
				)
				(justify mirror)
			)
		)
		(property "Value" "TPAD28-2-GP"
			(at 0.0127 -1.6637 0)
			(unlocked yes)
			(layer "B.Fab")
			(hide yes)
			(effects
				(font
					(size 1.016 1.016)
					(thickness 0.1524)
				)
				(justify mirror)
			)
		)
		(property "Device Type" "TPAD28"
			(at 0.0127 -3.1877 0)
			(unlocked yes)
			(layer "B.Fab")
			(hide yes)
			(effects
				(font
					(size 1.016 1.016)
					(thickness 0.1524)
				)
				(justify mirror)
			)
		)
		(duplicate_pad_numbers_are_jumpers no)
		(fp_poly
			(pts
				(arc
					(start 0.3556 0)
					(mid -0.3556 0)
					(end 0.3556 0)
				)
			)
			(stroke
				(width 0)
				(type default)
			)
			(fill no)
			(layer "B.CrtYd")
		)
		(fp_poly
			(pts
				(arc
					(start 0.6096 0)
					(mid -0.6096 0)
					(end 0.6096 0)
				)
			)
			(stroke
				(width 0)
				(type default)
			)
			(fill no)
			(layer "B.Fab")
		)
		(pad "1" smd circle
			(at 0 0 180)
			(size 0.7112 0.7112)
			(layers "B.Cu" "B.Mask" "B.Paste")
			(net "IOC_GPIO_6")
		)
	)
	(footprint ""
		(layer "B.Cu")
		(at 48.514 -135.7122)
		(property "Reference" "R142"
			(at 0 0 0)
			(layer "B.SilkS")
			(hide yes)
			(effects
				(font
					(size 1.27 1.27)
				)
				(justify mirror)
			)
		)
		(property "Value" "200R2F-L-GP"
			(at -0.064008 -3.993896 0)
			(unlocked yes)
			(layer "B.Fab")
			(hide yes)
			(effects
				(font
					(size 1.016 1.016)
					(thickness 0.1524)
				)
				(justify mirror)
			)
		)
		(property "Device Type" "R402H16"
			(at -0.064008 -5.517896 0)
			(unlocked yes)
			(layer "B.Fab")
			(hide yes)
			(effects
				(font
					(size 1.016 1.016)
					(thickness 0.1524)
				)
				(justify mirror)
			)
		)
		(duplicate_pad_numbers_are_jumpers no)
		(fp_line
			(start -0.508 -0.9398)
			(end 0.508 -0.9398)
			(stroke
				(width 0.1524)
				(type default)
			)
			(layer "B.SilkS")
		)
		(fp_line
			(start 0.508 -0.9398)
			(end 0.508 0.9398)
			(stroke
				(width 0.1524)
				(type default)
			)
			(layer "B.SilkS")
		)
		(fp_rect
			(start 0.508 0.9398)
			(end -0.508 -0.9398)
			(stroke
				(width 0)
				(type default)
			)
			(fill no)
			(layer "B.CrtYd")
		)
		(fp_rect
			(start 0.508 0.9398)
			(end -0.508 -0.9398)
			(stroke
				(width 0)
				(type default)
			)
			(fill no)
			(layer "B.Fab")
		)
		(pad "1" smd custom
			(at 0 -0.4445 180)
			(size 0.1397 0.1397)
			(layers "B.Cu" "B.Mask" "B.Paste")
			(net "BMC_PEREXT")
			(options
				(clearance outline)
				(anchor circle)
			)
			(primitives
				(gr_poly
					(pts
						(arc
							(start -0.1778 0.2794)
							(mid -0.249642 0.249642)
							(end -0.2794 0.1778)
						)
						(arc
							(start -0.2794 -0.1778)
							(mid -0.249642 -0.249642)
							(end -0.1778 -0.2794)
						)
						(arc
							(start 0.1778 -0.2794)
							(mid 0.249642 -0.249642)
							(end 0.2794 -0.1778)
						)
						(arc
							(start 0.2794 0.1778)
							(mid 0.249642 0.249642)
							(end 0.1778 0.2794)
						)
					)
					(width 0)
					(fill yes)
				)
			)
		)
		(pad "2" smd custom
			(at 0 0.4445 180)
			(size 0.1397 0.1397)
			(layers "B.Cu" "B.Mask" "B.Paste")
			(net "GND")
			(options
				(clearance outline)
				(anchor circle)
			)
			(primitives
				(gr_poly
					(pts
						(arc
							(start -0.1778 0.2794)
							(mid -0.249642 0.249642)
							(end -0.2794 0.1778)
						)
						(arc
							(start -0.2794 -0.1778)
							(mid -0.249642 -0.249642)
							(end -0.1778 -0.2794)
						)
						(arc
							(start 0.1778 -0.2794)
							(mid 0.249642 -0.249642)
							(end 0.2794 -0.1778)
						)
						(arc
							(start 0.2794 0.1778)
							(mid 0.249642 0.249642)
							(end 0.1778 0.2794)
						)
					)
					(width 0)
					(fill yes)
				)
			)
		)
	)
	(footprint ""
		(layer "B.Cu")
		(at 57.386728 -139.262104)
		(property "Reference" "TP76"
			(at 0 0 0)
			(layer "B.SilkS")
			(hide yes)
			(effects
				(font
					(size 1.27 1.27)
				)
				(justify mirror)
			)
		)
		(property "Value" "TPAD28-2-GP"
			(at 0.0127 -1.6637 0)
			(unlocked yes)
			(layer "B.Fab")
			(hide yes)
			(effects
				(font
					(size 1.016 1.016)
					(thickness 0.1524)
				)
				(justify mirror)
			)
		)
		(property "Device Type" "TPAD28"
			(at 0.0127 -3.1877 0)
			(unlocked yes)
			(layer "B.Fab")
			(hide yes)
			(effects
				(font
					(size 1.016 1.016)
					(thickness 0.1524)
				)
				(justify mirror)
			)
		)
		(duplicate_pad_numbers_are_jumpers no)
		(fp_poly
			(pts
				(arc
					(start 0.3556 0)
					(mid -0.3556 0)
					(end 0.3556 0)
				)
			)
			(stroke
				(width 0)
				(type default)
			)
			(fill no)
			(layer "B.CrtYd")
		)
		(fp_poly
			(pts
				(arc
					(start 0.6096 0)
					(mid -0.6096 0)
					(end 0.6096 0)
				)
			)
			(stroke
				(width 0)
				(type default)
			)
			(fill no)
			(layer "B.Fab")
		)
		(pad "1" smd circle
			(at 0 0 180)
			(size 0.7112 0.7112)
			(layers "B.Cu" "B.Mask" "B.Paste")
			(net "TP_BMC_GPIOI3")
		)
	)
	(footprint ""
		(layer "B.Cu")
		(at 32.4612 -156.5656 180)
		(property "Reference" "R782"
			(at 0 0 0)
			(layer "B.SilkS")
			(hide yes)
			(effects
				(font
					(size 1.27 1.27)
				)
				(justify mirror)
			)
		)
		(property "Value" "4K7R2F-GP"
			(at -0.064008 -3.993896 180)
			(unlocked yes)
			(layer "B.Fab")
			(hide yes)
			(effects
				(font
					(size 1.016 1.016)
					(thickness 0.1524)
				)
				(justify mirror)
			)
		)
		(property "Device Type" "R402H16"
			(at -0.064008 -5.517896 180)
			(unlocked yes)
			(layer "B.Fab")
			(hide yes)
			(effects
				(font
					(size 1.016 1.016)
					(thickness 0.1524)
				)
				(justify mirror)
			)
		)
		(duplicate_pad_numbers_are_jumpers no)
		(fp_line
			(start 0.508 -0.9398)
			(end 0.508 0.9398)
			(stroke
				(width 0.1524)
				(type default)
			)
			(layer "B.SilkS")
		)
		(fp_line
			(start -0.508 -0.9398)
			(end 0.508 -0.9398)
			(stroke
				(width 0.1524)
				(type default)
			)
			(layer "B.SilkS")
		)
		(fp_rect
			(start 0.508 0.9398)
			(end -0.508 -0.9398)
			(stroke
				(width 0)
				(type default)
			)
			(fill no)
			(layer "B.CrtYd")
		)
		(fp_rect
			(start 0.508 0.9398)
			(end -0.508 -0.9398)
			(stroke
				(width 0)
				(type default)
			)
			(fill no)
			(layer "B.Fab")
		)
		(pad "1" smd custom
			(at 0 -0.4445)
			(size 0.1397 0.1397)
			(layers "B.Cu" "B.Mask" "B.Paste")
			(net "COMP_FAST_THROTTLE_N")
			(options
				(clearance outline)
				(anchor circle)
			)
			(primitives
				(gr_poly
					(pts
						(arc
							(start -0.1778 0.2794)
							(mid -0.249642 0.249642)
							(end -0.2794 0.1778)
						)
						(arc
							(start -0.2794 -0.1778)
							(mid -0.249642 -0.249642)
							(end -0.1778 -0.2794)
						)
						(arc
							(start 0.1778 -0.2794)
							(mid 0.249642 -0.249642)
							(end 0.2794 -0.1778)
						)
						(arc
							(start 0.2794 0.1778)
							(mid 0.249642 0.249642)
							(end 0.1778 0.2794)
						)
					)
					(width 0)
					(fill yes)
				)
			)
		)
		(pad "2" smd custom
			(at 0 0.4445)
			(size 0.1397 0.1397)
			(layers "B.Cu" "B.Mask" "B.Paste")
			(net "GND")
			(options
				(clearance outline)
				(anchor circle)
			)
			(primitives
				(gr_poly
					(pts
						(arc
							(start -0.1778 0.2794)
							(mid -0.249642 0.249642)
							(end -0.2794 0.1778)
						)
						(arc
							(start -0.2794 -0.1778)
							(mid -0.249642 -0.249642)
							(end -0.1778 -0.2794)
						)
						(arc
							(start 0.1778 -0.2794)
							(mid 0.249642 -0.249642)
							(end 0.2794 -0.1778)
						)
						(arc
							(start 0.2794 0.1778)
							(mid 0.249642 0.249642)
							(end 0.1778 0.2794)
						)
					)
					(width 0)
					(fill yes)
				)
			)
		)
	)
	(footprint ""
		(layer "B.Cu")
		(at 175.710596 -73.397618)
		(property "Reference" "TP108"
			(at 0 0 0)
			(layer "B.SilkS")
			(hide yes)
			(effects
				(font
					(size 1.27 1.27)
				)
				(justify mirror)
			)
		)
		(property "Value" "TPAD28-2-GP"
			(at 0.0127 -1.6637 0)
			(unlocked yes)
			(layer "B.Fab")
			(hide yes)
			(effects
				(font
					(size 1.016 1.016)
					(thickness 0.1524)
				)
				(justify mirror)
			)
		)
		(property "Device Type" "TPAD28"
			(at 0.0127 -3.1877 0)
			(unlocked yes)
			(layer "B.Fab")
			(hide yes)
			(effects
				(font
					(size 1.016 1.016)
					(thickness 0.1524)
				)
				(justify mirror)
			)
		)
		(duplicate_pad_numbers_are_jumpers no)
		(fp_poly
			(pts
				(arc
					(start 0.3556 0)
					(mid -0.3556 0)
					(end 0.3556 0)
				)
			)
			(stroke
				(width 0)
				(type default)
			)
			(fill no)
			(layer "B.CrtYd")
		)
		(fp_poly
			(pts
				(arc
					(start 0.6096 0)
					(mid -0.6096 0)
					(end 0.6096 0)
				)
			)
			(stroke
				(width 0)
				(type default)
			)
			(fill no)
			(layer "B.Fab")
		)
		(pad "1" smd circle
			(at 0 0 180)
			(size 0.7112 0.7112)
			(layers "B.Cu" "B.Mask" "B.Paste")
			(net "IOC_GPIO_23")
		)
	)
	(footprint ""
		(layer "B.Cu")
		(at 198.50354 -70.10908 90)
		(property "Reference" "C368"
			(at 0 0 90)
			(layer "B.SilkS")
			(hide yes)
			(effects
				(font
					(size 1.27 1.27)
				)
				(justify mirror)
			)
		)
		(property "Value" "SCD1U6D3V1KX-GP"
			(at 2.8321 -1.7399 90)
			(unlocked yes)
			(layer "B.Fab")
			(hide yes)
			(effects
				(font
					(size 1.016 1.016)
					(thickness 0.1524)
				)
				(justify mirror)
			)
		)
		(property "Device Type" "C0201H13"
			(at 2.8321 -3.2639 90)
			(unlocked yes)
			(layer "B.Fab")
			(hide yes)
			(effects
				(font
					(size 1.016 1.016)
					(thickness 0.1524)
				)
				(justify mirror)
			)
		)
		(duplicate_pad_numbers_are_jumpers no)
		(fp_rect
			(start 0.2794 0.6477)
			(end -0.2794 -0.6477)
			(stroke
				(width 0)
				(type default)
			)
			(fill no)
			(layer "B.CrtYd")
		)
		(fp_rect
			(start 0.2794 0.6477)
			(end -0.2794 -0.6477)
			(stroke
				(width 0)
				(type default)
			)
			(fill no)
			(layer "B.Fab")
		)
		(pad "1" smd custom
			(at 0 -0.2794 270)
			(size 0.0762 0.0762)
			(layers "B.Cu" "B.Mask" "B.Paste")
			(net "PCE_AVDD")
			(options
				(clearance outline)
				(anchor circle)
			)
			(primitives
				(gr_poly
					(pts
						(arc
							(start 0.1524 0.127)
							(mid 0.137521 0.162921)
							(end 0.1016 0.1778)
						)
						(arc
							(start -0.1016 0.1778)
							(mid -0.137521 0.162921)
							(end -0.1524 0.127)
						)
						(arc
							(start -0.1524 -0.127)
							(mid -0.137521 -0.162921)
							(end -0.1016 -0.1778)
						)
						(arc
							(start 0.1016 -0.1778)
							(mid 0.137521 -0.162921)
							(end 0.1524 -0.127)
						)
					)
					(width 0)
					(fill yes)
				)
			)
		)
		(pad "2" smd custom
			(at 0 0.2794 270)
			(size 0.0762 0.0762)
			(layers "B.Cu" "B.Mask" "B.Paste")
			(net "GND")
			(options
				(clearance outline)
				(anchor circle)
			)
			(primitives
				(gr_poly
					(pts
						(arc
							(start 0.1524 0.127)
							(mid 0.137521 0.162921)
							(end 0.1016 0.1778)
						)
						(arc
							(start -0.1016 0.1778)
							(mid -0.137521 0.162921)
							(end -0.1524 0.127)
						)
						(arc
							(start -0.1524 -0.127)
							(mid -0.137521 -0.162921)
							(end -0.1016 -0.1778)
						)
						(arc
							(start 0.1016 -0.1778)
							(mid 0.137521 -0.162921)
							(end 0.1524 -0.127)
						)
					)
					(width 0)
					(fill yes)
				)
			)
		)
	)
	(footprint ""
		(layer "B.Cu")
		(at 188.3791 -58.8772)
		(property "Reference" "C389"
			(at 0 0 0)
			(layer "B.SilkS")
			(hide yes)
			(effects
				(font
					(size 1.27 1.27)
				)
				(justify mirror)
			)
		)
		(property "Value" "SC10U6D3V5KX-4GP"
			(at 0.0762 -6.1214 0)
			(unlocked yes)
			(layer "B.Fab")
			(hide yes)
			(effects
				(font
					(size 1.016 1.016)
					(thickness 0.1524)
				)
				(justify mirror)
			)
		)
		(property "Device Type" "C805H58"
			(at 0.0762 -8.1534 0)
			(unlocked yes)
			(layer "B.Fab")
			(hide yes)
			(effects
				(font
					(size 1.016 1.016)
					(thickness 0.1524)
				)
				(justify mirror)
			)
		)
		(duplicate_pad_numbers_are_jumpers no)
		(fp_line
			(start -0.635 0)
			(end 0.635 0)
			(stroke
				(width 0.508)
				(type default)
			)
			(layer "B.SilkS")
		)
		(fp_rect
			(start 0.9652 1.778)
			(end -0.9652 -1.778)
			(stroke
				(width 0)
				(type default)
			)
			(fill no)
			(layer "B.CrtYd")
		)
		(fp_poly
			(pts
				(xy 0.9652 -1.778) (xy -0.9652 -1.778) (xy -0.9652 1.778) (xy 0.9652 1.778)
			)
			(stroke
				(width 0)
				(type default)
			)
			(fill no)
			(layer "B.Fab")
		)
		(pad "1" smd rect
			(at 0 -0.9652 180)
			(size 1.397 1.143)
			(layers "B.Cu" "B.Mask" "B.Paste")
			(net "P0V975")
		)
		(pad "2" smd rect
			(at 0 0.9652 180)
			(size 1.397 1.143)
			(layers "B.Cu" "B.Mask" "B.Paste")
			(net "GND")
		)
	)
	(footprint ""
		(layer "B.Cu")
		(at 191.008 -72.9234)
		(property "Reference" "C359"
			(at 0 0 0)
			(layer "B.SilkS")
			(hide yes)
			(effects
				(font
					(size 1.27 1.27)
				)
				(justify mirror)
			)
		)
		(property "Value" "SCD1U6D3V1KX-GP"
			(at 2.8321 -1.7399 0)
			(unlocked yes)
			(layer "B.Fab")
			(hide yes)
			(effects
				(font
					(size 1.016 1.016)
					(thickness 0.1524)
				)
				(justify mirror)
			)
		)
		(property "Device Type" "C0201H13"
			(at 2.8321 -3.2639 0)
			(unlocked yes)
			(layer "B.Fab")
			(hide yes)
			(effects
				(font
					(size 1.016 1.016)
					(thickness 0.1524)
				)
				(justify mirror)
			)
		)
		(duplicate_pad_numbers_are_jumpers no)
		(fp_rect
			(start 0.2794 0.6477)
			(end -0.2794 -0.6477)
			(stroke
				(width 0)
				(type default)
			)
			(fill no)
			(layer "B.CrtYd")
		)
		(fp_rect
			(start 0.2794 0.6477)
			(end -0.2794 -0.6477)
			(stroke
				(width 0)
				(type default)
			)
			(fill no)
			(layer "B.Fab")
		)
		(pad "1" smd custom
			(at 0 -0.2794 180)
			(size 0.0762 0.0762)
			(layers "B.Cu" "B.Mask" "B.Paste")
			(net "PCE_VDDH")
			(options
				(clearance outline)
				(anchor circle)
			)
			(primitives
				(gr_poly
					(pts
						(arc
							(start 0.1524 0.127)
							(mid 0.137521 0.162921)
							(end 0.1016 0.1778)
						)
						(arc
							(start -0.1016 0.1778)
							(mid -0.137521 0.162921)
							(end -0.1524 0.127)
						)
						(arc
							(start -0.1524 -0.127)
							(mid -0.137521 -0.162921)
							(end -0.1016 -0.1778)
						)
						(arc
							(start 0.1016 -0.1778)
							(mid 0.137521 -0.162921)
							(end 0.1524 -0.127)
						)
					)
					(width 0)
					(fill yes)
				)
			)
		)
		(pad "2" smd custom
			(at 0 0.2794 180)
			(size 0.0762 0.0762)
			(layers "B.Cu" "B.Mask" "B.Paste")
			(net "GND")
			(options
				(clearance outline)
				(anchor circle)
			)
			(primitives
				(gr_poly
					(pts
						(arc
							(start 0.1524 0.127)
							(mid 0.137521 0.162921)
							(end 0.1016 0.1778)
						)
						(arc
							(start -0.1016 0.1778)
							(mid -0.137521 0.162921)
							(end -0.1524 0.127)
						)
						(arc
							(start -0.1524 -0.127)
							(mid -0.137521 -0.162921)
							(end -0.1016 -0.1778)
						)
						(arc
							(start 0.1016 -0.1778)
							(mid 0.137521 -0.162921)
							(end 0.1524 -0.127)
						)
					)
					(width 0)
					(fill yes)
				)
			)
		)
	)
	(footprint ""
		(layer "B.Cu")
		(at 84.582 -130.048 90)
		(property "Reference" "R718"
			(at 0 0 90)
			(layer "B.SilkS")
			(hide yes)
			(effects
				(font
					(size 1.27 1.27)
				)
				(justify mirror)
			)
		)
		(property "Value" "0R2J-2-GP"
			(at -0.064008 -3.993896 90)
			(unlocked yes)
			(layer "B.Fab")
			(hide yes)
			(effects
				(font
					(size 1.016 1.016)
					(thickness 0.1524)
				)
				(justify mirror)
			)
		)
		(property "Device Type" "R402H16"
			(at -0.064008 -5.517896 90)
			(unlocked yes)
			(layer "B.Fab")
			(hide yes)
			(effects
				(font
					(size 1.016 1.016)
					(thickness 0.1524)
				)
				(justify mirror)
			)
		)
		(duplicate_pad_numbers_are_jumpers no)
		(fp_line
			(start 0.508 -0.9398)
			(end 0.508 0.9398)
			(stroke
				(width 0.1524)
				(type default)
			)
			(layer "B.SilkS")
		)
		(fp_line
			(start -0.508 -0.9398)
			(end 0.508 -0.9398)
			(stroke
				(width 0.1524)
				(type default)
			)
			(layer "B.SilkS")
		)
		(fp_rect
			(start 0.508 0.9398)
			(end -0.508 -0.9398)
			(stroke
				(width 0)
				(type default)
			)
			(fill no)
			(layer "B.CrtYd")
		)
		(fp_rect
			(start 0.508 0.9398)
			(end -0.508 -0.9398)
			(stroke
				(width 0)
				(type default)
			)
			(fill no)
			(layer "B.Fab")
		)
		(pad "1" smd custom
			(at 0 -0.4445 270)
			(size 0.1397 0.1397)
			(layers "B.Cu" "B.Mask" "B.Paste")
			(net "BMC_TO_EXP_RESET_OUT_R")
			(options
				(clearance outline)
				(anchor circle)
			)
			(primitives
				(gr_poly
					(pts
						(arc
							(start -0.1778 0.2794)
							(mid -0.249642 0.249642)
							(end -0.2794 0.1778)
						)
						(arc
							(start -0.2794 -0.1778)
							(mid -0.249642 -0.249642)
							(end -0.1778 -0.2794)
						)
						(arc
							(start 0.1778 -0.2794)
							(mid 0.249642 -0.249642)
							(end 0.2794 -0.1778)
						)
						(arc
							(start 0.2794 0.1778)
							(mid 0.249642 0.249642)
							(end 0.1778 0.2794)
						)
					)
					(width 0)
					(fill yes)
				)
			)
		)
		(pad "2" smd custom
			(at 0 0.4445 270)
			(size 0.1397 0.1397)
			(layers "B.Cu" "B.Mask" "B.Paste")
			(net "BMC_TO_EXP_RESET_OUT")
			(options
				(clearance outline)
				(anchor circle)
			)
			(primitives
				(gr_poly
					(pts
						(arc
							(start -0.1778 0.2794)
							(mid -0.249642 0.249642)
							(end -0.2794 0.1778)
						)
						(arc
							(start -0.2794 -0.1778)
							(mid -0.249642 -0.249642)
							(end -0.1778 -0.2794)
						)
						(arc
							(start 0.1778 -0.2794)
							(mid 0.249642 -0.249642)
							(end 0.2794 -0.1778)
						)
						(arc
							(start 0.2794 0.1778)
							(mid 0.249642 0.249642)
							(end 0.1778 0.2794)
						)
					)
					(width 0)
					(fill yes)
				)
			)
		)
	)
	(footprint ""
		(layer "B.Cu")
		(at 56.690768 -144.018)
		(property "Reference" "TP79"
			(at 0 0 0)
			(layer "B.SilkS")
			(hide yes)
			(effects
				(font
					(size 1.27 1.27)
				)
				(justify mirror)
			)
		)
		(property "Value" "TPAD28-2-GP"
			(at 0.0127 -1.6637 0)
			(unlocked yes)
			(layer "B.Fab")
			(hide yes)
			(effects
				(font
					(size 1.016 1.016)
					(thickness 0.1524)
				)
				(justify mirror)
			)
		)
		(property "Device Type" "TPAD28"
			(at 0.0127 -3.1877 0)
			(unlocked yes)
			(layer "B.Fab")
			(hide yes)
			(effects
				(font
					(size 1.016 1.016)
					(thickness 0.1524)
				)
				(justify mirror)
			)
		)
		(duplicate_pad_numbers_are_jumpers no)
		(fp_poly
			(pts
				(arc
					(start 0.3556 0)
					(mid -0.3556 0)
					(end 0.3556 0)
				)
			)
			(stroke
				(width 0)
				(type default)
			)
			(fill no)
			(layer "B.CrtYd")
		)
		(fp_poly
			(pts
				(arc
					(start 0.6096 0)
					(mid -0.6096 0)
					(end 0.6096 0)
				)
			)
			(stroke
				(width 0)
				(type default)
			)
			(fill no)
			(layer "B.Fab")
		)
		(pad "1" smd circle
			(at 0 0 180)
			(size 0.7112 0.7112)
			(layers "B.Cu" "B.Mask" "B.Paste")
			(net "JTAG_BMC_TDI")
		)
	)
	(footprint ""
		(layer "B.Cu")
		(at 201.092308 -52.969668 -90)
		(property "Reference" "C337"
			(at 0 0 90)
			(layer "B.SilkS")
			(hide yes)
			(effects
				(font
					(size 1.27 1.27)
				)
				(justify mirror)
			)
		)
		(property "Value" "SC1U6D3V1MX-GP"
			(at -1.9177 2.0193 270)
			(unlocked yes)
			(layer "B.Fab")
			(hide yes)
			(effects
				(font
					(size 1.016 1.016)
					(thickness 0.1524)
				)
				(justify mirror)
			)
		)
		(property "Device Type" "C0201H14"
			(at -1.9177 0.4953 270)
			(unlocked yes)
			(layer "B.Fab")
			(hide yes)
			(effects
				(font
					(size 1.016 1.016)
					(thickness 0.1524)
				)
				(justify mirror)
			)
		)
		(duplicate_pad_numbers_are_jumpers no)
		(fp_rect
			(start 0.1524 0.3048)
			(end -0.1524 -0.3048)
			(stroke
				(width 0)
				(type default)
			)
			(fill no)
			(layer "B.CrtYd")
		)
		(fp_poly
			(pts
				(xy 0.2794 0.6477) (xy 0.2794 -0.6477) (xy -0.2794 -0.6477) (xy -0.2794 -0.1905) (xy -0.1524 -0.1905)
				(xy -0.1524 -0.3048) (xy 0.1524 -0.3048) (xy 0.1524 0.3048) (xy -0.1524 0.3048) (xy -0.1524 -0.1778)
				(xy -0.2794 -0.1778) (xy -0.2794 0.6477)
			)
			(stroke
				(width 0)
				(type default)
			)
			(fill no)
			(layer "B.CrtYd")
		)
		(fp_rect
			(start 0.2794 0.6477)
			(end -0.2794 -0.6477)
			(stroke
				(width 0)
				(type default)
			)
			(fill no)
			(layer "B.Fab")
		)
		(pad "1" smd custom
			(at 0 -0.2794 90)
			(size 0.0762 0.0762)
			(layers "B.Cu" "B.Mask" "B.Paste")
			(net "SYS_PLL_VDD")
			(options
				(clearance outline)
				(anchor circle)
			)
			(primitives
				(gr_poly
					(pts
						(arc
							(start 0.1524 0.127)
							(mid 0.137521 0.162921)
							(end 0.1016 0.1778)
						)
						(arc
							(start -0.1016 0.1778)
							(mid -0.137521 0.162921)
							(end -0.1524 0.127)
						)
						(arc
							(start -0.1524 -0.127)
							(mid -0.137521 -0.162921)
							(end -0.1016 -0.1778)
						)
						(arc
							(start 0.1016 -0.1778)
							(mid 0.137521 -0.162921)
							(end 0.1524 -0.127)
						)
					)
					(width 0)
					(fill yes)
				)
			)
		)
		(pad "2" smd custom
			(at 0 0.2794 90)
			(size 0.0762 0.0762)
			(layers "B.Cu" "B.Mask" "B.Paste")
			(net "GND")
			(options
				(clearance outline)
				(anchor circle)
			)
			(primitives
				(gr_poly
					(pts
						(arc
							(start 0.1524 0.127)
							(mid 0.137521 0.162921)
							(end 0.1016 0.1778)
						)
						(arc
							(start -0.1016 0.1778)
							(mid -0.137521 0.162921)
							(end -0.1524 0.127)
						)
						(arc
							(start -0.1524 -0.127)
							(mid -0.137521 -0.162921)
							(end -0.1016 -0.1778)
						)
						(arc
							(start 0.1016 -0.1778)
							(mid 0.137521 -0.162921)
							(end 0.1524 -0.127)
						)
					)
					(width 0)
					(fill yes)
				)
			)
		)
	)
	(footprint ""
		(layer "B.Cu")
		(at 192.942718 -81.153 180)
		(property "Reference" "C298"
			(at 0 0 0)
			(layer "B.SilkS")
			(hide yes)
			(effects
				(font
					(size 1.27 1.27)
				)
				(justify mirror)
			)
		)
		(property "Value" "SCD22U10V1KX-GP"
			(at 2.8321 -1.7399 180)
			(unlocked yes)
			(layer "B.Fab")
			(hide yes)
			(effects
				(font
					(size 1.016 1.016)
					(thickness 0.1524)
				)
				(justify mirror)
			)
		)
		(property "Device Type" "C0201H13"
			(at 2.8321 -3.2639 180)
			(unlocked yes)
			(layer "B.Fab")
			(hide yes)
			(effects
				(font
					(size 1.016 1.016)
					(thickness 0.1524)
				)
				(justify mirror)
			)
		)
		(duplicate_pad_numbers_are_jumpers no)
		(fp_rect
			(start 0.2794 0.6477)
			(end -0.2794 -0.6477)
			(stroke
				(width 0)
				(type default)
			)
			(fill no)
			(layer "B.CrtYd")
		)
		(fp_rect
			(start 0.2794 0.6477)
			(end -0.2794 -0.6477)
			(stroke
				(width 0)
				(type default)
			)
			(fill no)
			(layer "B.Fab")
		)
		(pad "1" smd custom
			(at 0 -0.2794)
			(size 0.0762 0.0762)
			(layers "B.Cu" "B.Mask" "B.Paste")
			(net "PCIE_IOM_TO_COMP_12_DN_C")
			(options
				(clearance outline)
				(anchor circle)
			)
			(primitives
				(gr_poly
					(pts
						(arc
							(start 0.1524 0.127)
							(mid 0.137521 0.162921)
							(end 0.1016 0.1778)
						)
						(arc
							(start -0.1016 0.1778)
							(mid -0.137521 0.162921)
							(end -0.1524 0.127)
						)
						(arc
							(start -0.1524 -0.127)
							(mid -0.137521 -0.162921)
							(end -0.1016 -0.1778)
						)
						(arc
							(start 0.1016 -0.1778)
							(mid 0.137521 -0.162921)
							(end 0.1524 -0.127)
						)
					)
					(width 0)
					(fill yes)
				)
			)
		)
		(pad "2" smd custom
			(at 0 0.2794)
			(size 0.0762 0.0762)
			(layers "B.Cu" "B.Mask" "B.Paste")
			(net "PCIE_IOM_TO_COMP_12_DN")
			(options
				(clearance outline)
				(anchor circle)
			)
			(primitives
				(gr_poly
					(pts
						(arc
							(start 0.1524 0.127)
							(mid 0.137521 0.162921)
							(end 0.1016 0.1778)
						)
						(arc
							(start -0.1016 0.1778)
							(mid -0.137521 0.162921)
							(end -0.1524 0.127)
						)
						(arc
							(start -0.1524 -0.127)
							(mid -0.137521 -0.162921)
							(end -0.1016 -0.1778)
						)
						(arc
							(start 0.1016 -0.1778)
							(mid 0.137521 -0.162921)
							(end 0.1524 -0.127)
						)
					)
					(width 0)
					(fill yes)
				)
			)
		)
	)
	(footprint ""
		(layer "B.Cu")
		(at 10.20445 -133.85673 90)
		(property "Reference" "R242"
			(at 0 0 90)
			(layer "B.SilkS")
			(hide yes)
			(effects
				(font
					(size 1.27 1.27)
				)
				(justify mirror)
			)
		)
		(property "Value" "120R2F-GP"
			(at -0.064008 -3.993896 90)
			(unlocked yes)
			(layer "B.Fab")
			(hide yes)
			(effects
				(font
					(size 1.016 1.016)
					(thickness 0.1524)
				)
				(justify mirror)
			)
		)
		(property "Device Type" "R402H16"
			(at -0.064008 -5.517896 90)
			(unlocked yes)
			(layer "B.Fab")
			(hide yes)
			(effects
				(font
					(size 1.016 1.016)
					(thickness 0.1524)
				)
				(justify mirror)
			)
		)
		(duplicate_pad_numbers_are_jumpers no)
		(fp_line
			(start 0.508 -0.9398)
			(end 0.508 0.9398)
			(stroke
				(width 0.1524)
				(type default)
			)
			(layer "B.SilkS")
		)
		(fp_line
			(start -0.508 -0.9398)
			(end 0.508 -0.9398)
			(stroke
				(width 0.1524)
				(type default)
			)
			(layer "B.SilkS")
		)
		(fp_rect
			(start 0.508 0.9398)
			(end -0.508 -0.9398)
			(stroke
				(width 0)
				(type default)
			)
			(fill no)
			(layer "B.CrtYd")
		)
		(fp_rect
			(start 0.508 0.9398)
			(end -0.508 -0.9398)
			(stroke
				(width 0)
				(type default)
			)
			(fill no)
			(layer "B.Fab")
		)
		(pad "1" smd custom
			(at 0 -0.4445 270)
			(size 0.1397 0.1397)
			(layers "B.Cu" "B.Mask" "B.Paste")
			(net "GND")
			(options
				(clearance outline)
				(anchor circle)
			)
			(primitives
				(gr_poly
					(pts
						(arc
							(start -0.1778 0.2794)
							(mid -0.249642 0.249642)
							(end -0.2794 0.1778)
						)
						(arc
							(start -0.2794 -0.1778)
							(mid -0.249642 -0.249642)
							(end -0.1778 -0.2794)
						)
						(arc
							(start 0.1778 -0.2794)
							(mid 0.249642 -0.249642)
							(end 0.2794 -0.1778)
						)
						(arc
							(start 0.2794 0.1778)
							(mid 0.249642 0.249642)
							(end 0.1778 0.2794)
						)
					)
					(width 0)
					(fill yes)
				)
			)
		)
		(pad "2" smd custom
			(at 0 0.4445 270)
			(size 0.1397 0.1397)
			(layers "B.Cu" "B.Mask" "B.Paste")
			(net "MEMA_4")
			(options
				(clearance outline)
				(anchor circle)
			)
			(primitives
				(gr_poly
					(pts
						(arc
							(start -0.1778 0.2794)
							(mid -0.249642 0.249642)
							(end -0.2794 0.1778)
						)
						(arc
							(start -0.2794 -0.1778)
							(mid -0.249642 -0.249642)
							(end -0.1778 -0.2794)
						)
						(arc
							(start 0.1778 -0.2794)
							(mid 0.249642 -0.249642)
							(end 0.2794 -0.1778)
						)
						(arc
							(start 0.2794 0.1778)
							(mid 0.249642 0.249642)
							(end 0.1778 0.2794)
						)
					)
					(width 0)
					(fill yes)
				)
			)
		)
	)
	(footprint ""
		(layer "B.Cu")
		(at 68.820538 -145.974816 180)
		(property "Reference" "R193"
			(at 0 0 0)
			(layer "B.SilkS")
			(hide yes)
			(effects
				(font
					(size 1.27 1.27)
				)
				(justify mirror)
			)
		)
		(property "Value" "20KR2F-L-GP"
			(at -0.064008 -3.993896 180)
			(unlocked yes)
			(layer "B.Fab")
			(hide yes)
			(effects
				(font
					(size 1.016 1.016)
					(thickness 0.1524)
				)
				(justify mirror)
			)
		)
		(property "Device Type" "R402H16"
			(at -0.064008 -5.517896 180)
			(unlocked yes)
			(layer "B.Fab")
			(hide yes)
			(effects
				(font
					(size 1.016 1.016)
					(thickness 0.1524)
				)
				(justify mirror)
			)
		)
		(duplicate_pad_numbers_are_jumpers no)
		(fp_line
			(start 0.508 -0.9398)
			(end 0.508 0.9398)
			(stroke
				(width 0.1524)
				(type default)
			)
			(layer "B.SilkS")
		)
		(fp_line
			(start -0.508 -0.9398)
			(end 0.508 -0.9398)
			(stroke
				(width 0.1524)
				(type default)
			)
			(layer "B.SilkS")
		)
		(fp_rect
			(start 0.508 0.9398)
			(end -0.508 -0.9398)
			(stroke
				(width 0)
				(type default)
			)
			(fill no)
			(layer "B.CrtYd")
		)
		(fp_rect
			(start 0.508 0.9398)
			(end -0.508 -0.9398)
			(stroke
				(width 0)
				(type default)
			)
			(fill no)
			(layer "B.Fab")
		)
		(pad "1" smd custom
			(at 0 -0.4445)
			(size 0.1397 0.1397)
			(layers "B.Cu" "B.Mask" "B.Paste")
			(net "P3V3_STBY")
			(options
				(clearance outline)
				(anchor circle)
			)
			(primitives
				(gr_poly
					(pts
						(arc
							(start -0.1778 0.2794)
							(mid -0.249642 0.249642)
							(end -0.2794 0.1778)
						)
						(arc
							(start -0.2794 -0.1778)
							(mid -0.249642 -0.249642)
							(end -0.1778 -0.2794)
						)
						(arc
							(start 0.1778 -0.2794)
							(mid 0.249642 -0.249642)
							(end 0.2794 -0.1778)
						)
						(arc
							(start 0.2794 0.1778)
							(mid 0.249642 0.249642)
							(end 0.1778 0.2794)
						)
					)
					(width 0)
					(fill yes)
				)
			)
		)
		(pad "2" smd custom
			(at 0 0.4445)
			(size 0.1397 0.1397)
			(layers "B.Cu" "B.Mask" "B.Paste")
			(net "I2C_DEBUG_SCL_L")
			(options
				(clearance outline)
				(anchor circle)
			)
			(primitives
				(gr_poly
					(pts
						(arc
							(start -0.1778 0.2794)
							(mid -0.249642 0.249642)
							(end -0.2794 0.1778)
						)
						(arc
							(start -0.2794 -0.1778)
							(mid -0.249642 -0.249642)
							(end -0.1778 -0.2794)
						)
						(arc
							(start 0.1778 -0.2794)
							(mid 0.249642 -0.249642)
							(end 0.2794 -0.1778)
						)
						(arc
							(start 0.2794 0.1778)
							(mid 0.249642 0.249642)
							(end 0.1778 0.2794)
						)
					)
					(width 0)
					(fill yes)
				)
			)
		)
	)
	(footprint ""
		(layer "B.Cu")
		(at 85.6996 -169.6974 90)
		(property "Reference" "U32"
			(at 0 0 90)
			(layer "B.SilkS")
			(hide yes)
			(effects
				(font
					(size 1.27 1.27)
				)
				(justify mirror)
			)
		)
		(property "Value" "SN74LVC126APWR-1-GP"
			(at 0 -10.6172 90)
			(unlocked yes)
			(layer "B.Fab")
			(hide yes)
			(effects
				(font
					(size 1.016 1.016)
					(thickness 0.1524)
				)
				(justify mirror)
			)
		)
		(property "Device Type" "SSOIC14-1H48"
			(at 0 -12.1412 90)
			(unlocked yes)
			(layer "B.Fab")
			(hide yes)
			(effects
				(font
					(size 1.016 1.016)
					(thickness 0.1524)
				)
				(justify mirror)
			)
		)
		(duplicate_pad_numbers_are_jumpers no)
		(fp_line
			(start 2.2352 -1.8415)
			(end -2.2352 -1.8415)
			(stroke
				(width 0.0254)
				(type default)
			)
			(layer "B.SilkS")
		)
		(fp_line
			(start -2.2352 -1.8415)
			(end -2.2352 1.8415)
			(stroke
				(width 0.0254)
				(type default)
			)
			(layer "B.SilkS")
		)
		(fp_line
			(start 2.2352 -1.8288)
			(end -2.2225 -1.8288)
			(stroke
				(width 0.0254)
				(type default)
			)
			(layer "B.SilkS")
		)
		(fp_line
			(start -2.23266 -1.8161)
			(end 2.2352 -1.8161)
			(stroke
				(width 0.0254)
				(type default)
			)
			(layer "B.SilkS")
		)
		(fp_line
			(start 2.2352 -1.8034)
			(end -2.2225 -1.8034)
			(stroke
				(width 0.0254)
				(type default)
			)
			(layer "B.SilkS")
		)
		(fp_line
			(start -2.23266 -1.7907)
			(end 2.2352 -1.7907)
			(stroke
				(width 0.0254)
				(type default)
			)
			(layer "B.SilkS")
		)
		(fp_line
			(start 2.2352 -1.778)
			(end -2.2225 -1.778)
			(stroke
				(width 0.0254)
				(type default)
			)
			(layer "B.SilkS")
		)
		(fp_line
			(start -2.23266 -1.7653)
			(end 2.2352 -1.7653)
			(stroke
				(width 0.0254)
				(type default)
			)
			(layer "B.SilkS")
		)
		(fp_line
			(start 2.2352 -1.7526)
			(end -2.2225 -1.7526)
			(stroke
				(width 0.0254)
				(type default)
			)
			(layer "B.SilkS")
		)
		(fp_line
			(start -2.23266 -1.7399)
			(end 2.2352 -1.7399)
			(stroke
				(width 0.0254)
				(type default)
			)
			(layer "B.SilkS")
		)
		(fp_line
			(start 2.2352 -1.7272)
			(end -2.2225 -1.7272)
			(stroke
				(width 0.0254)
				(type default)
			)
			(layer "B.SilkS")
		)
		(fp_line
			(start -2.23266 -1.7145)
			(end 2.2352 -1.7145)
			(stroke
				(width 0.0254)
				(type default)
			)
			(layer "B.SilkS")
		)
		(fp_line
			(start 2.2352 -1.7018)
			(end -2.2225 -1.7018)
			(stroke
				(width 0.0254)
				(type default)
			)
			(layer "B.SilkS")
		)
		(fp_line
			(start -2.23266 -1.6891)
			(end 2.2352 -1.6891)
			(stroke
				(width 0.0254)
				(type default)
			)
			(layer "B.SilkS")
		)
		(fp_line
			(start 2.2352 -1.6764)
			(end -2.2225 -1.6764)
			(stroke
				(width 0.0254)
				(type default)
			)
			(layer "B.SilkS")
		)
		(fp_line
			(start -2.23266 -1.6637)
			(end 2.2352 -1.6637)
			(stroke
				(width 0.0254)
				(type default)
			)
			(layer "B.SilkS")
		)
		(fp_line
			(start 2.794 -1.651)
			(end -2.159 -1.651)
			(stroke
				(width 0.2032)
				(type default)
			)
			(layer "B.SilkS")
		)
		(fp_line
			(start 2.794 -1.651)
			(end 2.794 4.064)
			(stroke
				(width 0.2032)
				(type default)
			)
			(layer "B.SilkS")
		)
		(fp_line
			(start 2.2352 -1.651)
			(end -2.2225 -1.651)
			(stroke
				(width 0.0254)
				(type default)
			)
			(layer "B.SilkS")
		)
		(fp_line
			(start -2.159 -1.651)
			(end -2.159 1.651)
			(stroke
				(width 0.2032)
				(type default)
			)
			(layer "B.SilkS")
		)
		(fp_line
			(start -2.23266 -1.6383)
			(end 2.2352 -1.6383)
			(stroke
				(width 0.0254)
				(type default)
			)
			(layer "B.SilkS")
		)
		(fp_line
			(start 2.2352 -1.6256)
			(end -2.2225 -1.6256)
			(stroke
				(width 0.0254)
				(type default)
			)
			(layer "B.SilkS")
		)
		(fp_line
			(start -2.23266 -1.6129)
			(end 2.2352 -1.6129)
			(stroke
				(width 0.0254)
				(type default)
			)
			(layer "B.SilkS")
		)
		(fp_line
			(start 2.2352 -1.6002)
			(end -2.2225 -1.6002)
			(stroke
				(width 0.0254)
				(type default)
			)
			(layer "B.SilkS")
		)
		(fp_line
			(start -2.23266 -1.5875)
			(end 2.2352 -1.5875)
			(stroke
				(width 0.0254)
				(type default)
			)
			(layer "B.SilkS")
		)
		(fp_line
			(start 2.2352 -1.5748)
			(end -2.2225 -1.5748)
			(stroke
				(width 0.0254)
				(type default)
			)
			(layer "B.SilkS")
		)
		(fp_line
			(start -2.23266 -1.5621)
			(end 2.2352 -1.5621)
			(stroke
				(width 0.0254)
				(type default)
			)
			(layer "B.SilkS")
		)
		(fp_line
			(start 2.2352 -1.5494)
			(end -2.2225 -1.5494)
			(stroke
				(width 0.0254)
				(type default)
			)
			(layer "B.SilkS")
		)
		(fp_line
			(start -2.23266 -1.5367)
			(end 2.2352 -1.5367)
			(stroke
				(width 0.0254)
				(type default)
			)
			(layer "B.SilkS")
		)
		(fp_line
			(start 2.2352 -1.524)
			(end -2.2225 -1.524)
			(stroke
				(width 0.0254)
				(type default)
			)
			(layer "B.SilkS")
		)
		(fp_line
			(start -2.23266 -1.5113)
			(end 2.2352 -1.5113)
			(stroke
				(width 0.0254)
				(type default)
			)
			(layer "B.SilkS")
		)
		(fp_line
			(start 2.2352 -1.4986)
			(end -2.2225 -1.4986)
			(stroke
				(width 0.0254)
				(type default)
			)
			(layer "B.SilkS")
		)
		(fp_line
			(start -2.23266 -1.4859)
			(end 2.2352 -1.4859)
			(stroke
				(width 0.0254)
				(type default)
			)
			(layer "B.SilkS")
		)
		(fp_line
			(start 2.2352 -1.4732)
			(end -2.2225 -1.4732)
			(stroke
				(width 0.0254)
				(type default)
			)
			(layer "B.SilkS")
		)
		(fp_line
			(start -2.23266 -1.4605)
			(end 2.2352 -1.4605)
			(stroke
				(width 0.0254)
				(type default)
			)
			(layer "B.SilkS")
		)
		(fp_line
			(start 2.2352 -1.4478)
			(end -2.2225 -1.4478)
			(stroke
				(width 0.0254)
				(type default)
			)
			(layer "B.SilkS")
		)
		(fp_line
			(start -2.23266 -1.4351)
			(end 2.2352 -1.4351)
			(stroke
				(width 0.0254)
				(type default)
			)
			(layer "B.SilkS")
		)
		(fp_line
			(start 2.2352 -1.4224)
			(end -2.2225 -1.4224)
			(stroke
				(width 0.0254)
				(type default)
			)
			(layer "B.SilkS")
		)
		(fp_line
			(start -2.23266 -1.4097)
			(end 2.2352 -1.4097)
			(stroke
				(width 0.0254)
				(type default)
			)
			(layer "B.SilkS")
		)
		(fp_line
			(start 2.2352 -1.397)
			(end -2.2225 -1.397)
			(stroke
				(width 0.0254)
				(type default)
			)
			(layer "B.SilkS")
		)
		(fp_line
			(start -2.23266 -1.3843)
			(end 2.2352 -1.3843)
			(stroke
				(width 0.0254)
				(type default)
			)
			(layer "B.SilkS")
		)
		(fp_line
			(start 2.2352 -1.3716)
			(end -2.2225 -1.3716)
			(stroke
				(width 0.0254)
				(type default)
			)
			(layer "B.SilkS")
		)
		(fp_line
			(start -2.23266 -1.3589)
			(end 2.2352 -1.3589)
			(stroke
				(width 0.0254)
				(type default)
			)
			(layer "B.SilkS")
		)
		(fp_line
			(start 2.2352 -1.3462)
			(end -2.2225 -1.3462)
			(stroke
				(width 0.0254)
				(type default)
			)
			(layer "B.SilkS")
		)
		(fp_line
			(start -2.23266 -1.3335)
			(end 2.2352 -1.3335)
			(stroke
				(width 0.0254)
				(type default)
			)
			(layer "B.SilkS")
		)
		(fp_line
			(start 2.2352 -1.3208)
			(end -2.2225 -1.3208)
			(stroke
				(width 0.0254)
				(type default)
			)
			(layer "B.SilkS")
		)
		(fp_line
			(start -2.23266 -1.3081)
			(end 2.2352 -1.3081)
			(stroke
				(width 0.0254)
				(type default)
			)
			(layer "B.SilkS")
		)
		(fp_line
			(start 2.2352 -1.2954)
			(end -2.2225 -1.2954)
			(stroke
				(width 0.0254)
				(type default)
			)
			(layer "B.SilkS")
		)
		(fp_line
			(start -2.23266 -1.2827)
			(end 2.2352 -1.2827)
			(stroke
				(width 0.0254)
				(type default)
			)
			(layer "B.SilkS")
		)
		(fp_line
			(start 2.2352 -1.27)
			(end -2.2225 -1.27)
			(stroke
				(width 0.0254)
				(type default)
			)
			(layer "B.SilkS")
		)
		(fp_line
			(start -2.23266 -1.2573)
			(end 2.2352 -1.2573)
			(stroke
				(width 0.0254)
				(type default)
			)
			(layer "B.SilkS")
		)
		(fp_line
			(start 2.2352 -1.2446)
			(end -2.2225 -1.2446)
			(stroke
				(width 0.0254)
				(type default)
			)
			(layer "B.SilkS")
		)
		(fp_line
			(start -2.23266 -1.2319)
			(end 2.2352 -1.2319)
			(stroke
				(width 0.0254)
				(type default)
			)
			(layer "B.SilkS")
		)
		(fp_line
			(start 2.2352 -1.2192)
			(end -2.2225 -1.2192)
			(stroke
				(width 0.0254)
				(type default)
			)
			(layer "B.SilkS")
		)
		(fp_line
			(start -2.23266 -1.2065)
			(end 2.2352 -1.2065)
			(stroke
				(width 0.0254)
				(type default)
			)
			(layer "B.SilkS")
		)
		(fp_line
			(start 2.2352 -1.1938)
			(end -2.2225 -1.1938)
			(stroke
				(width 0.0254)
				(type default)
			)
			(layer "B.SilkS")
		)
		(fp_line
			(start -2.23266 -1.1811)
			(end 2.2352 -1.1811)
			(stroke
				(width 0.0254)
				(type default)
			)
			(layer "B.SilkS")
		)
		(fp_line
			(start 2.2352 -1.1684)
			(end -2.2225 -1.1684)
			(stroke
				(width 0.0254)
				(type default)
			)
			(layer "B.SilkS")
		)
		(fp_line
			(start -2.23266 -1.1557)
			(end 2.2352 -1.1557)
			(stroke
				(width 0.0254)
				(type default)
			)
			(layer "B.SilkS")
		)
		(fp_line
			(start 2.2352 -1.143)
			(end -2.2225 -1.143)
			(stroke
				(width 0.0254)
				(type default)
			)
			(layer "B.SilkS")
		)
		(fp_line
			(start -2.23266 -1.1303)
			(end 2.2352 -1.1303)
			(stroke
				(width 0.0254)
				(type default)
			)
			(layer "B.SilkS")
		)
		(fp_line
			(start 2.2352 -1.1176)
			(end -2.2225 -1.1176)
			(stroke
				(width 0.0254)
				(type default)
			)
			(layer "B.SilkS")
		)
		(fp_line
			(start -2.23266 -1.1049)
			(end 2.2352 -1.1049)
			(stroke
				(width 0.0254)
				(type default)
			)
			(layer "B.SilkS")
		)
		(fp_line
			(start 2.2352 -1.0922)
			(end -2.2225 -1.0922)
			(stroke
				(width 0.0254)
				(type default)
			)
			(layer "B.SilkS")
		)
		(fp_line
			(start -2.23266 -1.0795)
			(end 2.2352 -1.0795)
			(stroke
				(width 0.0254)
				(type default)
			)
			(layer "B.SilkS")
		)
		(fp_line
			(start 2.2352 -1.0668)
			(end -2.2225 -1.0668)
			(stroke
				(width 0.0254)
				(type default)
			)
			(layer "B.SilkS")
		)
		(fp_line
			(start -2.23266 -1.0541)
			(end 2.2352 -1.0541)
			(stroke
				(width 0.0254)
				(type default)
			)
			(layer "B.SilkS")
		)
		(fp_line
			(start 2.2352 -1.0414)
			(end -2.2225 -1.0414)
			(stroke
				(width 0.0254)
				(type default)
			)
			(layer "B.SilkS")
		)
		(fp_line
			(start -2.23266 -1.0287)
			(end 2.2352 -1.0287)
			(stroke
				(width 0.0254)
				(type default)
			)
			(layer "B.SilkS")
		)
		(fp_line
			(start 2.2352 -1.016)
			(end -2.2225 -1.016)
			(stroke
				(width 0.0254)
				(type default)
			)
			(layer "B.SilkS")
		)
		(fp_line
			(start -2.23266 -1.0033)
			(end 2.2352 -1.0033)
			(stroke
				(width 0.0254)
				(type default)
			)
			(layer "B.SilkS")
		)
		(fp_line
			(start 2.2352 -0.9906)
			(end -2.2225 -0.9906)
			(stroke
				(width 0.0254)
				(type default)
			)
			(layer "B.SilkS")
		)
		(fp_line
			(start -2.23266 -0.9779)
			(end 2.2352 -0.9779)
			(stroke
				(width 0.0254)
				(type default)
			)
			(layer "B.SilkS")
		)
		(fp_line
			(start 2.2352 -0.9652)
			(end -2.2225 -0.9652)
			(stroke
				(width 0.0254)
				(type default)
			)
			(layer "B.SilkS")
		)
		(fp_line
			(start -2.23266 -0.9525)
			(end 2.2352 -0.9525)
			(stroke
				(width 0.0254)
				(type default)
			)
			(layer "B.SilkS")
		)
		(fp_line
			(start 2.2352 -0.9398)
			(end -2.2225 -0.9398)
			(stroke
				(width 0.0254)
				(type default)
			)
			(layer "B.SilkS")
		)
		(fp_line
			(start -2.23266 -0.9271)
			(end 2.2352 -0.9271)
			(stroke
				(width 0.0254)
				(type default)
			)
			(layer "B.SilkS")
		)
		(fp_line
			(start 2.2352 -0.9144)
			(end -2.2225 -0.9144)
			(stroke
				(width 0.0254)
				(type default)
			)
			(layer "B.SilkS")
		)
		(fp_line
			(start -2.23266 -0.9017)
			(end 2.2352 -0.9017)
			(stroke
				(width 0.0254)
				(type default)
			)
			(layer "B.SilkS")
		)
		(fp_line
			(start 2.2352 -0.889)
			(end -2.2225 -0.889)
			(stroke
				(width 0.0254)
				(type default)
			)
			(layer "B.SilkS")
		)
		(fp_line
			(start -2.23266 -0.8763)
			(end 2.2352 -0.8763)
			(stroke
				(width 0.0254)
				(type default)
			)
			(layer "B.SilkS")
		)
		(fp_line
			(start 2.2352 -0.8636)
			(end -2.2225 -0.8636)
			(stroke
				(width 0.0254)
				(type default)
			)
			(layer "B.SilkS")
		)
		(fp_line
			(start -2.23266 -0.8509)
			(end 2.2352 -0.8509)
			(stroke
				(width 0.0254)
				(type default)
			)
			(layer "B.SilkS")
		)
		(fp_line
			(start 2.2352 -0.8382)
			(end -2.2225 -0.8382)
			(stroke
				(width 0.0254)
				(type default)
			)
			(layer "B.SilkS")
		)
		(fp_line
			(start -2.23266 -0.8255)
			(end 2.2352 -0.8255)
			(stroke
				(width 0.0254)
				(type default)
			)
			(layer "B.SilkS")
		)
		(fp_line
			(start 2.2352 -0.8128)
			(end -2.2225 -0.8128)
			(stroke
				(width 0.0254)
				(type default)
			)
			(layer "B.SilkS")
		)
		(fp_line
			(start -2.23266 -0.8001)
			(end 2.2352 -0.8001)
			(stroke
				(width 0.0254)
				(type default)
			)
			(layer "B.SilkS")
		)
		(fp_line
			(start 2.2352 -0.7874)
			(end -2.2225 -0.7874)
			(stroke
				(width 0.0254)
				(type default)
			)
			(layer "B.SilkS")
		)
		(fp_line
			(start -2.23266 -0.7747)
			(end 2.2352 -0.7747)
			(stroke
				(width 0.0254)
				(type default)
			)
			(layer "B.SilkS")
		)
		(fp_line
			(start 2.2352 -0.762)
			(end -2.2225 -0.762)
			(stroke
				(width 0.0254)
				(type default)
			)
			(layer "B.SilkS")
		)
		(fp_line
			(start -2.23266 -0.7493)
			(end 2.2352 -0.7493)
			(stroke
				(width 0.0254)
				(type default)
			)
			(layer "B.SilkS")
		)
		(fp_line
			(start 2.2352 -0.7366)
			(end -2.2225 -0.7366)
			(stroke
				(width 0.0254)
				(type default)
			)
			(layer "B.SilkS")
		)
		(fp_line
			(start -2.23266 -0.7239)
			(end 2.2352 -0.7239)
			(stroke
				(width 0.0254)
				(type default)
			)
			(layer "B.SilkS")
		)
		(fp_line
			(start 2.2352 -0.7112)
			(end -2.2225 -0.7112)
			(stroke
				(width 0.0254)
				(type default)
			)
			(layer "B.SilkS")
		)
		(fp_line
			(start -2.23266 -0.6985)
			(end 2.2352 -0.6985)
			(stroke
				(width 0.0254)
				(type default)
			)
			(layer "B.SilkS")
		)
		(fp_line
			(start 2.2352 -0.6858)
			(end -2.2225 -0.6858)
			(stroke
				(width 0.0254)
				(type default)
			)
			(layer "B.SilkS")
		)
		(fp_line
			(start -2.23266 -0.6731)
			(end 2.2352 -0.6731)
			(stroke
				(width 0.0254)
				(type default)
			)
			(layer "B.SilkS")
		)
		(fp_line
			(start 2.2352 -0.6604)
			(end -2.2225 -0.6604)
			(stroke
				(width 0.0254)
				(type default)
			)
			(layer "B.SilkS")
		)
		(fp_line
			(start -2.23266 -0.6477)
			(end 2.2352 -0.6477)
			(stroke
				(width 0.0254)
				(type default)
			)
			(layer "B.SilkS")
		)
		(fp_line
			(start 2.2352 -0.635)
			(end -2.2225 -0.635)
			(stroke
				(width 0.0254)
				(type default)
			)
			(layer "B.SilkS")
		)
		(fp_line
			(start -2.23266 -0.6223)
			(end 2.2352 -0.6223)
			(stroke
				(width 0.0254)
				(type default)
			)
			(layer "B.SilkS")
		)
		(fp_line
			(start 2.2352 -0.6096)
			(end -2.2225 -0.6096)
			(stroke
				(width 0.0254)
				(type default)
			)
			(layer "B.SilkS")
		)
		(fp_line
			(start -2.23266 -0.5969)
			(end 2.2352 -0.5969)
			(stroke
				(width 0.0254)
				(type default)
			)
			(layer "B.SilkS")
		)
		(fp_line
			(start 2.2352 -0.5842)
			(end -2.2225 -0.5842)
			(stroke
				(width 0.0254)
				(type default)
			)
			(layer "B.SilkS")
		)
		(fp_line
			(start -2.23266 -0.5715)
			(end 2.2352 -0.5715)
			(stroke
				(width 0.0254)
				(type default)
			)
			(layer "B.SilkS")
		)
		(fp_line
			(start 2.2352 -0.5588)
			(end -2.2225 -0.5588)
			(stroke
				(width 0.0254)
				(type default)
			)
			(layer "B.SilkS")
		)
		(fp_line
			(start -2.23266 -0.5461)
			(end 2.2352 -0.5461)
			(stroke
				(width 0.0254)
				(type default)
			)
			(layer "B.SilkS")
		)
		(fp_line
			(start 2.2352 -0.5334)
			(end -2.2225 -0.5334)
			(stroke
				(width 0.0254)
				(type default)
			)
			(layer "B.SilkS")
		)
		(fp_line
			(start -2.23266 -0.5207)
			(end 2.2352 -0.5207)
			(stroke
				(width 0.0254)
				(type default)
			)
			(layer "B.SilkS")
		)
		(fp_line
			(start 2.2352 -0.508)
			(end -2.2225 -0.508)
			(stroke
				(width 0.0254)
				(type default)
			)
			(layer "B.SilkS")
		)
		(fp_line
			(start -2.23266 -0.4953)
			(end 2.2352 -0.4953)
			(stroke
				(width 0.0254)
				(type default)
			)
			(layer "B.SilkS")
		)
		(fp_line
			(start 2.2352 -0.4826)
			(end -2.2225 -0.4826)
			(stroke
				(width 0.0254)
				(type default)
			)
			(layer "B.SilkS")
		)
		(fp_line
			(start -2.23266 -0.4699)
			(end 2.2352 -0.4699)
			(stroke
				(width 0.0254)
				(type default)
			)
			(layer "B.SilkS")
		)
		(fp_line
			(start 2.2352 -0.4572)
			(end -2.2225 -0.4572)
			(stroke
				(width 0.0254)
				(type default)
			)
			(layer "B.SilkS")
		)
		(fp_line
			(start -2.23266 -0.4445)
			(end 2.2352 -0.4445)
			(stroke
				(width 0.0254)
				(type default)
			)
			(layer "B.SilkS")
		)
		(fp_line
			(start 2.2352 -0.4318)
			(end -2.2225 -0.4318)
			(stroke
				(width 0.0254)
				(type default)
			)
			(layer "B.SilkS")
		)
		(fp_line
			(start -2.23266 -0.4191)
			(end 2.2352 -0.4191)
			(stroke
				(width 0.0254)
				(type default)
			)
			(layer "B.SilkS")
		)
		(fp_line
			(start 2.2352 -0.4064)
			(end -2.2225 -0.4064)
			(stroke
				(width 0.0254)
				(type default)
			)
			(layer "B.SilkS")
		)
		(fp_line
			(start -2.23266 -0.3937)
			(end 2.2352 -0.3937)
			(stroke
				(width 0.0254)
				(type default)
			)
			(layer "B.SilkS")
		)
		(fp_line
			(start 2.2352 -0.381)
			(end -2.2225 -0.381)
			(stroke
				(width 0.0254)
				(type default)
			)
			(layer "B.SilkS")
		)
		(fp_line
			(start -2.23266 -0.3683)
			(end 2.2352 -0.3683)
			(stroke
				(width 0.0254)
				(type default)
			)
			(layer "B.SilkS")
		)
		(fp_line
			(start 2.2352 -0.3556)
			(end -2.2225 -0.3556)
			(stroke
				(width 0.0254)
				(type default)
			)
			(layer "B.SilkS")
		)
		(fp_line
			(start -2.23266 -0.3429)
			(end 2.2352 -0.3429)
			(stroke
				(width 0.0254)
				(type default)
			)
			(layer "B.SilkS")
		)
		(fp_line
			(start 2.2352 -0.3302)
			(end -2.2225 -0.3302)
			(stroke
				(width 0.0254)
				(type default)
			)
			(layer "B.SilkS")
		)
		(fp_line
			(start -2.23266 -0.3175)
			(end 2.2352 -0.3175)
			(stroke
				(width 0.0254)
				(type default)
			)
			(layer "B.SilkS")
		)
		(fp_line
			(start 2.2352 -0.3048)
			(end -2.2225 -0.3048)
			(stroke
				(width 0.0254)
				(type default)
			)
			(layer "B.SilkS")
		)
		(fp_line
			(start -2.23266 -0.2921)
			(end 2.2352 -0.2921)
			(stroke
				(width 0.0254)
				(type default)
			)
			(layer "B.SilkS")
		)
		(fp_line
			(start 2.2352 -0.2794)
			(end -2.2225 -0.2794)
			(stroke
				(width 0.0254)
				(type default)
			)
			(layer "B.SilkS")
		)
		(fp_line
			(start -2.23266 -0.2667)
			(end 2.2352 -0.2667)
			(stroke
				(width 0.0254)
				(type default)
			)
			(layer "B.SilkS")
		)
		(fp_line
			(start 2.2352 -0.254)
			(end -2.2225 -0.254)
			(stroke
				(width 0.0254)
				(type default)
			)
			(layer "B.SilkS")
		)
		(fp_line
			(start -2.23266 -0.2413)
			(end 2.2352 -0.2413)
			(stroke
				(width 0.0254)
				(type default)
			)
			(layer "B.SilkS")
		)
		(fp_line
			(start 2.2352 -0.2286)
			(end -2.2225 -0.2286)
			(stroke
				(width 0.0254)
				(type default)
			)
			(layer "B.SilkS")
		)
		(fp_line
			(start -2.23266 -0.2159)
			(end 2.2352 -0.2159)
			(stroke
				(width 0.0254)
				(type default)
			)
			(layer "B.SilkS")
		)
		(fp_line
			(start 2.2352 -0.2032)
			(end -2.2225 -0.2032)
			(stroke
				(width 0.0254)
				(type default)
			)
			(layer "B.SilkS")
		)
		(fp_line
			(start -2.23266 -0.1905)
			(end 2.2352 -0.1905)
			(stroke
				(width 0.0254)
				(type default)
			)
			(layer "B.SilkS")
		)
		(fp_line
			(start 2.2352 -0.1778)
			(end -2.2225 -0.1778)
			(stroke
				(width 0.0254)
				(type default)
			)
			(layer "B.SilkS")
		)
		(fp_line
			(start -2.23266 -0.1651)
			(end 2.2352 -0.1651)
			(stroke
				(width 0.0254)
				(type default)
			)
			(layer "B.SilkS")
		)
		(fp_line
			(start 2.2352 -0.1524)
			(end -2.2225 -0.1524)
			(stroke
				(width 0.0254)
				(type default)
			)
			(layer "B.SilkS")
		)
		(fp_line
			(start -2.23266 -0.1397)
			(end 2.2352 -0.1397)
			(stroke
				(width 0.0254)
				(type default)
			)
			(layer "B.SilkS")
		)
		(fp_line
			(start 2.2352 -0.127)
			(end -2.2225 -0.127)
			(stroke
				(width 0.0254)
				(type default)
			)
			(layer "B.SilkS")
		)
		(fp_line
			(start -2.23266 -0.1143)
			(end 2.2352 -0.1143)
			(stroke
				(width 0.0254)
				(type default)
			)
			(layer "B.SilkS")
		)
		(fp_line
			(start 2.2352 -0.1016)
			(end -2.2225 -0.1016)
			(stroke
				(width 0.0254)
				(type default)
			)
			(layer "B.SilkS")
		)
		(fp_line
			(start -2.23266 -0.0889)
			(end 2.2352 -0.0889)
			(stroke
				(width 0.0254)
				(type default)
			)
			(layer "B.SilkS")
		)
		(fp_line
			(start 2.2352 -0.0762)
			(end -2.2225 -0.0762)
			(stroke
				(width 0.0254)
				(type default)
			)
			(layer "B.SilkS")
		)
		(fp_line
			(start -2.23266 -0.0635)
			(end 2.2352 -0.0635)
			(stroke
				(width 0.0254)
				(type default)
			)
			(layer "B.SilkS")
		)
		(fp_line
			(start 2.2352 -0.0508)
			(end -2.2225 -0.0508)
			(stroke
				(width 0.0254)
				(type default)
			)
			(layer "B.SilkS")
		)
		(fp_line
			(start -2.23266 -0.0381)
			(end 2.2352 -0.0381)
			(stroke
				(width 0.0254)
				(type default)
			)
			(layer "B.SilkS")
		)
		(fp_line
			(start 2.2352 -0.0254)
			(end -2.2225 -0.0254)
			(stroke
				(width 0.0254)
				(type default)
			)
			(layer "B.SilkS")
		)
		(fp_line
			(start -2.23266 -0.0127)
			(end 2.2352 -0.0127)
			(stroke
				(width 0.0254)
				(type default)
			)
			(layer "B.SilkS")
		)
		(fp_line
			(start 2.2352 0)
			(end -2.2225 0)
			(stroke
				(width 0.0254)
				(type default)
			)
			(layer "B.SilkS")
		)
		(fp_line
			(start 2.032 0)
			(end 2.794 -0.762)
			(stroke
				(width 0.2032)
				(type default)
			)
			(layer "B.SilkS")
		)
		(fp_line
			(start 2.032 0)
			(end 2.794 0.762)
			(stroke
				(width 0.2032)
				(type default)
			)
			(layer "B.SilkS")
		)
		(fp_line
			(start 1.016 0)
			(end -1.016 0)
			(stroke
				(width 0.1)
				(type default)
			)
			(layer "B.SilkS")
		)
		(fp_line
			(start -2.23266 0.0127)
			(end 2.2352 0.0127)
			(stroke
				(width 0.0254)
				(type default)
			)
			(layer "B.SilkS")
		)
		(fp_line
			(start 2.2352 0.0254)
			(end -2.2225 0.0254)
			(stroke
				(width 0.0254)
				(type default)
			)
			(layer "B.SilkS")
		)
		(fp_line
			(start -2.23266 0.0381)
			(end 2.2352 0.0381)
			(stroke
				(width 0.0254)
				(type default)
			)
			(layer "B.SilkS")
		)
		(fp_line
			(start 2.2352 0.0508)
			(end -2.2225 0.0508)
			(stroke
				(width 0.0254)
				(type default)
			)
			(layer "B.SilkS")
		)
		(fp_line
			(start -2.23266 0.0635)
			(end 2.2352 0.0635)
			(stroke
				(width 0.0254)
				(type default)
			)
			(layer "B.SilkS")
		)
		(fp_line
			(start 2.2352 0.0762)
			(end -2.2225 0.0762)
			(stroke
				(width 0.0254)
				(type default)
			)
			(layer "B.SilkS")
		)
		(fp_line
			(start -2.23266 0.0889)
			(end 2.2352 0.0889)
			(stroke
				(width 0.0254)
				(type default)
			)
			(layer "B.SilkS")
		)
		(fp_line
			(start 2.2352 0.1016)
			(end -2.2225 0.1016)
			(stroke
				(width 0.0254)
				(type default)
			)
			(layer "B.SilkS")
		)
		(fp_line
			(start -2.23266 0.1143)
			(end 2.2352 0.1143)
			(stroke
				(width 0.0254)
				(type default)
			)
			(layer "B.SilkS")
		)
		(fp_line
			(start 2.2352 0.127)
			(end -2.2225 0.127)
			(stroke
				(width 0.0254)
				(type default)
			)
			(layer "B.SilkS")
		)
		(fp_line
			(start -2.23266 0.1397)
			(end 2.2352 0.1397)
			(stroke
				(width 0.0254)
				(type default)
			)
			(layer "B.SilkS")
		)
		(fp_line
			(start 2.2352 0.1524)
			(end -2.2225 0.1524)
			(stroke
				(width 0.0254)
				(type default)
			)
			(layer "B.SilkS")
		)
		(fp_line
			(start -2.23266 0.1651)
			(end 2.2352 0.1651)
			(stroke
				(width 0.0254)
				(type default)
			)
			(layer "B.SilkS")
		)
		(fp_line
			(start 2.2352 0.1778)
			(end -2.2225 0.1778)
			(stroke
				(width 0.0254)
				(type default)
			)
			(layer "B.SilkS")
		)
		(fp_line
			(start -2.23266 0.1905)
			(end 2.2352 0.1905)
			(stroke
				(width 0.0254)
				(type default)
			)
			(layer "B.SilkS")
		)
		(fp_line
			(start 2.2352 0.2032)
			(end -2.2225 0.2032)
			(stroke
				(width 0.0254)
				(type default)
			)
			(layer "B.SilkS")
		)
		(fp_line
			(start -2.23266 0.2159)
			(end 2.2352 0.2159)
			(stroke
				(width 0.0254)
				(type default)
			)
			(layer "B.SilkS")
		)
		(fp_line
			(start 2.2352 0.2286)
			(end -2.2225 0.2286)
			(stroke
				(width 0.0254)
				(type default)
			)
			(layer "B.SilkS")
		)
		(fp_line
			(start -2.23266 0.2413)
			(end 2.2352 0.2413)
			(stroke
				(width 0.0254)
				(type default)
			)
			(layer "B.SilkS")
		)
		(fp_line
			(start 2.2352 0.254)
			(end -2.2225 0.254)
			(stroke
				(width 0.0254)
				(type default)
			)
			(layer "B.SilkS")
		)
		(fp_line
			(start -2.23266 0.2667)
			(end 2.2352 0.2667)
			(stroke
				(width 0.0254)
				(type default)
			)
			(layer "B.SilkS")
		)
		(fp_line
			(start 2.2352 0.2794)
			(end -2.2225 0.2794)
			(stroke
				(width 0.0254)
				(type default)
			)
			(layer "B.SilkS")
		)
		(fp_line
			(start -2.23266 0.2921)
			(end 2.2352 0.2921)
			(stroke
				(width 0.0254)
				(type default)
			)
			(layer "B.SilkS")
		)
		(fp_line
			(start 2.2352 0.3048)
			(end -2.2225 0.3048)
			(stroke
				(width 0.0254)
				(type default)
			)
			(layer "B.SilkS")
		)
		(fp_line
			(start -2.23266 0.3175)
			(end 2.2352 0.3175)
			(stroke
				(width 0.0254)
				(type default)
			)
			(layer "B.SilkS")
		)
		(fp_line
			(start 2.2352 0.3302)
			(end -2.2225 0.3302)
			(stroke
				(width 0.0254)
				(type default)
			)
			(layer "B.SilkS")
		)
		(fp_line
			(start -2.23266 0.3429)
			(end 2.2352 0.3429)
			(stroke
				(width 0.0254)
				(type default)
			)
			(layer "B.SilkS")
		)
		(fp_line
			(start 2.2352 0.3556)
			(end -2.2225 0.3556)
			(stroke
				(width 0.0254)
				(type default)
			)
			(layer "B.SilkS")
		)
		(fp_line
			(start -2.23266 0.3683)
			(end 2.2352 0.3683)
			(stroke
				(width 0.0254)
				(type default)
			)
			(layer "B.SilkS")
		)
		(fp_line
			(start 2.2352 0.381)
			(end -2.2225 0.381)
			(stroke
				(width 0.0254)
				(type default)
			)
			(layer "B.SilkS")
		)
		(fp_line
			(start -2.23266 0.3937)
			(end 2.2352 0.3937)
			(stroke
				(width 0.0254)
				(type default)
			)
			(layer "B.SilkS")
		)
		(fp_line
			(start 2.2352 0.4064)
			(end -2.2225 0.4064)
			(stroke
				(width 0.0254)
				(type default)
			)
			(layer "B.SilkS")
		)
		(fp_line
			(start -2.23266 0.4191)
			(end 2.2352 0.4191)
			(stroke
				(width 0.0254)
				(type default)
			)
			(layer "B.SilkS")
		)
		(fp_line
			(start 2.2352 0.4318)
			(end -2.2225 0.4318)
			(stroke
				(width 0.0254)
				(type default)
			)
			(layer "B.SilkS")
		)
		(fp_line
			(start -2.23266 0.4445)
			(end 2.2352 0.4445)
			(stroke
				(width 0.0254)
				(type default)
			)
			(layer "B.SilkS")
		)
		(fp_line
			(start 2.2352 0.4572)
			(end -2.2225 0.4572)
			(stroke
				(width 0.0254)
				(type default)
			)
			(layer "B.SilkS")
		)
		(fp_line
			(start -2.23266 0.4699)
			(end 2.2352 0.4699)
			(stroke
				(width 0.0254)
				(type default)
			)
			(layer "B.SilkS")
		)
		(fp_line
			(start 2.2352 0.4826)
			(end -2.2225 0.4826)
			(stroke
				(width 0.0254)
				(type default)
			)
			(layer "B.SilkS")
		)
		(fp_line
			(start -2.23266 0.4953)
			(end 2.2352 0.4953)
			(stroke
				(width 0.0254)
				(type default)
			)
			(layer "B.SilkS")
		)
		(fp_line
			(start 2.2352 0.508)
			(end -2.2225 0.508)
			(stroke
				(width 0.0254)
				(type default)
			)
			(layer "B.SilkS")
		)
		(fp_line
			(start -2.23266 0.5207)
			(end 2.2352 0.5207)
			(stroke
				(width 0.0254)
				(type default)
			)
			(layer "B.SilkS")
		)
		(fp_line
			(start 2.2352 0.5334)
			(end -2.2225 0.5334)
			(stroke
				(width 0.0254)
				(type default)
			)
			(layer "B.SilkS")
		)
		(fp_line
			(start -2.23266 0.5461)
			(end 2.2352 0.5461)
			(stroke
				(width 0.0254)
				(type default)
			)
			(layer "B.SilkS")
		)
		(fp_line
			(start 2.2352 0.5588)
			(end -2.2225 0.5588)
			(stroke
				(width 0.0254)
				(type default)
			)
			(layer "B.SilkS")
		)
		(fp_line
			(start -2.23266 0.5715)
			(end 2.2352 0.5715)
			(stroke
				(width 0.0254)
				(type default)
			)
			(layer "B.SilkS")
		)
		(fp_line
			(start 2.2352 0.5842)
			(end -2.2225 0.5842)
			(stroke
				(width 0.0254)
				(type default)
			)
			(layer "B.SilkS")
		)
		(fp_line
			(start -2.23266 0.5969)
			(end 2.2352 0.5969)
			(stroke
				(width 0.0254)
				(type default)
			)
			(layer "B.SilkS")
		)
		(fp_line
			(start 2.2352 0.6096)
			(end -2.2225 0.6096)
			(stroke
				(width 0.0254)
				(type default)
			)
			(layer "B.SilkS")
		)
		(fp_line
			(start -2.23266 0.6223)
			(end 2.2352 0.6223)
			(stroke
				(width 0.0254)
				(type default)
			)
			(layer "B.SilkS")
		)
		(fp_line
			(start 2.2352 0.635)
			(end -2.2225 0.635)
			(stroke
				(width 0.0254)
				(type default)
			)
			(layer "B.SilkS")
		)
		(fp_line
			(start -2.23266 0.6477)
			(end 2.2352 0.6477)
			(stroke
				(width 0.0254)
				(type default)
			)
			(layer "B.SilkS")
		)
		(fp_line
			(start 2.2352 0.6604)
			(end -2.2225 0.6604)
			(stroke
				(width 0.0254)
				(type default)
			)
			(layer "B.SilkS")
		)
		(fp_line
			(start -2.23266 0.6731)
			(end 2.2352 0.6731)
			(stroke
				(width 0.0254)
				(type default)
			)
			(layer "B.SilkS")
		)
		(fp_line
			(start 2.2352 0.6858)
			(end -2.2225 0.6858)
			(stroke
				(width 0.0254)
				(type default)
			)
			(layer "B.SilkS")
		)
		(fp_line
			(start -2.23266 0.6985)
			(end 2.2352 0.6985)
			(stroke
				(width 0.0254)
				(type default)
			)
			(layer "B.SilkS")
		)
		(fp_line
			(start 2.2352 0.7112)
			(end -2.2225 0.7112)
			(stroke
				(width 0.0254)
				(type default)
			)
			(layer "B.SilkS")
		)
		(fp_line
			(start -2.23266 0.7239)
			(end 2.2352 0.7239)
			(stroke
				(width 0.0254)
				(type default)
			)
			(layer "B.SilkS")
		)
		(fp_line
			(start 2.2352 0.7366)
			(end -2.2225 0.7366)
			(stroke
				(width 0.0254)
				(type default)
			)
			(layer "B.SilkS")
		)
		(fp_line
			(start -2.23266 0.7493)
			(end 2.2352 0.7493)
			(stroke
				(width 0.0254)
				(type default)
			)
			(layer "B.SilkS")
		)
		(fp_line
			(start 2.2352 0.762)
			(end -2.2225 0.762)
			(stroke
				(width 0.0254)
				(type default)
			)
			(layer "B.SilkS")
		)
		(fp_line
			(start -2.23266 0.7747)
			(end 2.2352 0.7747)
			(stroke
				(width 0.0254)
				(type default)
			)
			(layer "B.SilkS")
		)
		(fp_line
			(start 2.2352 0.7874)
			(end -2.2225 0.7874)
			(stroke
				(width 0.0254)
				(type default)
			)
			(layer "B.SilkS")
		)
		(fp_line
			(start -2.23266 0.8001)
			(end 2.2352 0.8001)
			(stroke
				(width 0.0254)
				(type default)
			)
			(layer "B.SilkS")
		)
		(fp_line
			(start 2.2352 0.8128)
			(end -2.2225 0.8128)
			(stroke
				(width 0.0254)
				(type default)
			)
			(layer "B.SilkS")
		)
		(fp_line
			(start -2.23266 0.8255)
			(end 2.2352 0.8255)
			(stroke
				(width 0.0254)
				(type default)
			)
			(layer "B.SilkS")
		)
		(fp_line
			(start 2.2352 0.8382)
			(end -2.2225 0.8382)
			(stroke
				(width 0.0254)
				(type default)
			)
			(layer "B.SilkS")
		)
		(fp_line
			(start -2.23266 0.8509)
			(end 2.2352 0.8509)
			(stroke
				(width 0.0254)
				(type default)
			)
			(layer "B.SilkS")
		)
		(fp_line
			(start 2.2352 0.8636)
			(end -2.2225 0.8636)
			(stroke
				(width 0.0254)
				(type default)
			)
			(layer "B.SilkS")
		)
		(fp_line
			(start -2.23266 0.8763)
			(end 2.2352 0.8763)
			(stroke
				(width 0.0254)
				(type default)
			)
			(layer "B.SilkS")
		)
		(fp_line
			(start 2.2352 0.889)
			(end -2.2225 0.889)
			(stroke
				(width 0.0254)
				(type default)
			)
			(layer "B.SilkS")
		)
		(fp_line
			(start -2.23266 0.9017)
			(end 2.2352 0.9017)
			(stroke
				(width 0.0254)
				(type default)
			)
			(layer "B.SilkS")
		)
		(fp_line
			(start 2.2352 0.9144)
			(end -2.2225 0.9144)
			(stroke
				(width 0.0254)
				(type default)
			)
			(layer "B.SilkS")
		)
		(fp_line
			(start -2.23266 0.9271)
			(end 2.2352 0.9271)
			(stroke
				(width 0.0254)
				(type default)
			)
			(layer "B.SilkS")
		)
		(fp_line
			(start 2.2352 0.9398)
			(end -2.2225 0.9398)
			(stroke
				(width 0.0254)
				(type default)
			)
			(layer "B.SilkS")
		)
		(fp_line
			(start -2.23266 0.9525)
			(end 2.2352 0.9525)
			(stroke
				(width 0.0254)
				(type default)
			)
			(layer "B.SilkS")
		)
		(fp_line
			(start 2.2352 0.9652)
			(end -2.2225 0.9652)
			(stroke
				(width 0.0254)
				(type default)
			)
			(layer "B.SilkS")
		)
		(fp_line
			(start -2.23266 0.9779)
			(end 2.2352 0.9779)
			(stroke
				(width 0.0254)
				(type default)
			)
			(layer "B.SilkS")
		)
		(fp_line
			(start 2.2352 0.9906)
			(end -2.2225 0.9906)
			(stroke
				(width 0.0254)
				(type default)
			)
			(layer "B.SilkS")
		)
		(fp_line
			(start -2.23266 1.0033)
			(end 2.2352 1.0033)
			(stroke
				(width 0.0254)
				(type default)
			)
			(layer "B.SilkS")
		)
		(fp_line
			(start 2.2352 1.016)
			(end -2.2225 1.016)
			(stroke
				(width 0.0254)
				(type default)
			)
			(layer "B.SilkS")
		)
		(fp_line
			(start 0 1.016)
			(end 0 -1.016)
			(stroke
				(width 0.1)
				(type default)
			)
			(layer "B.SilkS")
		)
		(fp_line
			(start -2.23266 1.0287)
			(end 2.2352 1.0287)
			(stroke
				(width 0.0254)
				(type default)
			)
			(layer "B.SilkS")
		)
		(fp_line
			(start 2.2352 1.0414)
			(end -2.2225 1.0414)
			(stroke
				(width 0.0254)
				(type default)
			)
			(layer "B.SilkS")
		)
		(fp_line
			(start -2.23266 1.0541)
			(end 2.2352 1.0541)
			(stroke
				(width 0.0254)
				(type default)
			)
			(layer "B.SilkS")
		)
		(fp_line
			(start 2.2352 1.0668)
			(end -2.2225 1.0668)
			(stroke
				(width 0.0254)
				(type default)
			)
			(layer "B.SilkS")
		)
		(fp_line
			(start -2.23266 1.0795)
			(end 2.2352 1.0795)
			(stroke
				(width 0.0254)
				(type default)
			)
			(layer "B.SilkS")
		)
		(fp_line
			(start 2.2352 1.0922)
			(end -2.2225 1.0922)
			(stroke
				(width 0.0254)
				(type default)
			)
			(layer "B.SilkS")
		)
		(fp_line
			(start -2.23266 1.1049)
			(end 2.2352 1.1049)
			(stroke
				(width 0.0254)
				(type default)
			)
			(layer "B.SilkS")
		)
		(fp_line
			(start 2.2352 1.1176)
			(end -2.2225 1.1176)
			(stroke
				(width 0.0254)
				(type default)
			)
			(layer "B.SilkS")
		)
		(fp_line
			(start -2.23266 1.1303)
			(end 2.2352 1.1303)
			(stroke
				(width 0.0254)
				(type default)
			)
			(layer "B.SilkS")
		)
		(fp_line
			(start 2.2352 1.143)
			(end -2.2225 1.143)
			(stroke
				(width 0.0254)
				(type default)
			)
			(layer "B.SilkS")
		)
		(fp_line
			(start -2.23266 1.1557)
			(end 2.2352 1.1557)
			(stroke
				(width 0.0254)
				(type default)
			)
			(layer "B.SilkS")
		)
		(fp_line
			(start 2.2352 1.1684)
			(end -2.2225 1.1684)
			(stroke
				(width 0.0254)
				(type default)
			)
			(layer "B.SilkS")
		)
		(fp_line
			(start -2.23266 1.1811)
			(end 2.2352 1.1811)
			(stroke
				(width 0.0254)
				(type default)
			)
			(layer "B.SilkS")
		)
		(fp_line
			(start 2.2352 1.1938)
			(end -2.2225 1.1938)
			(stroke
				(width 0.0254)
				(type default)
			)
			(layer "B.SilkS")
		)
		(fp_line
			(start -2.23266 1.2065)
			(end 2.2352 1.2065)
			(stroke
				(width 0.0254)
				(type default)
			)
			(layer "B.SilkS")
		)
		(fp_line
			(start 2.2352 1.2192)
			(end -2.2225 1.2192)
			(stroke
				(width 0.0254)
				(type default)
			)
			(layer "B.SilkS")
		)
		(fp_line
			(start -2.23266 1.2319)
			(end 2.2352 1.2319)
			(stroke
				(width 0.0254)
				(type default)
			)
			(layer "B.SilkS")
		)
		(fp_line
			(start 2.2352 1.2446)
			(end -2.2225 1.2446)
			(stroke
				(width 0.0254)
				(type default)
			)
			(layer "B.SilkS")
		)
		(fp_line
			(start -2.23266 1.2573)
			(end 2.2352 1.2573)
			(stroke
				(width 0.0254)
				(type default)
			)
			(layer "B.SilkS")
		)
		(fp_line
			(start 2.2352 1.27)
			(end -2.2225 1.27)
			(stroke
				(width 0.0254)
				(type default)
			)
			(layer "B.SilkS")
		)
		(fp_line
			(start -2.23266 1.2827)
			(end 2.2352 1.2827)
			(stroke
				(width 0.0254)
				(type default)
			)
			(layer "B.SilkS")
		)
		(fp_line
			(start 2.2352 1.2954)
			(end -2.2225 1.2954)
			(stroke
				(width 0.0254)
				(type default)
			)
			(layer "B.SilkS")
		)
		(fp_line
			(start -2.23266 1.3081)
			(end 2.2352 1.3081)
			(stroke
				(width 0.0254)
				(type default)
			)
			(layer "B.SilkS")
		)
		(fp_line
			(start 2.2352 1.3208)
			(end -2.2225 1.3208)
			(stroke
				(width 0.0254)
				(type default)
			)
			(layer "B.SilkS")
		)
		(fp_line
			(start -2.23266 1.3335)
			(end 2.2352 1.3335)
			(stroke
				(width 0.0254)
				(type default)
			)
			(layer "B.SilkS")
		)
		(fp_line
			(start 2.2352 1.3462)
			(end -2.2225 1.3462)
			(stroke
				(width 0.0254)
				(type default)
			)
			(layer "B.SilkS")
		)
		(fp_line
			(start -2.23266 1.3589)
			(end 2.2352 1.3589)
			(stroke
				(width 0.0254)
				(type default)
			)
			(layer "B.SilkS")
		)
		(fp_line
			(start 2.2352 1.3716)
			(end -2.2225 1.3716)
			(stroke
				(width 0.0254)
				(type default)
			)
			(layer "B.SilkS")
		)
		(fp_line
			(start -2.23266 1.3843)
			(end 2.2352 1.3843)
			(stroke
				(width 0.0254)
				(type default)
			)
			(layer "B.SilkS")
		)
		(fp_line
			(start 2.2352 1.397)
			(end -2.2225 1.397)
			(stroke
				(width 0.0254)
				(type default)
			)
			(layer "B.SilkS")
		)
		(fp_line
			(start -2.23266 1.4097)
			(end 2.2352 1.4097)
			(stroke
				(width 0.0254)
				(type default)
			)
			(layer "B.SilkS")
		)
		(fp_line
			(start 2.2352 1.4224)
			(end -2.2225 1.4224)
			(stroke
				(width 0.0254)
				(type default)
			)
			(layer "B.SilkS")
		)
		(fp_line
			(start -2.23266 1.4351)
			(end 2.2352 1.4351)
			(stroke
				(width 0.0254)
				(type default)
			)
			(layer "B.SilkS")
		)
		(fp_line
			(start 2.2352 1.4478)
			(end -2.2225 1.4478)
			(stroke
				(width 0.0254)
				(type default)
			)
			(layer "B.SilkS")
		)
		(fp_line
			(start -2.23266 1.4605)
			(end 2.2352 1.4605)
			(stroke
				(width 0.0254)
				(type default)
			)
			(layer "B.SilkS")
		)
		(fp_line
			(start 2.2352 1.4732)
			(end -2.2225 1.4732)
			(stroke
				(width 0.0254)
				(type default)
			)
			(layer "B.SilkS")
		)
		(fp_line
			(start -2.23266 1.4859)
			(end 2.2352 1.4859)
			(stroke
				(width 0.0254)
				(type default)
			)
			(layer "B.SilkS")
		)
		(fp_line
			(start 2.2352 1.4986)
			(end -2.2225 1.4986)
			(stroke
				(width 0.0254)
				(type default)
			)
			(layer "B.SilkS")
		)
		(fp_line
			(start -2.23266 1.5113)
			(end 2.2352 1.5113)
			(stroke
				(width 0.0254)
				(type default)
			)
			(layer "B.SilkS")
		)
		(fp_line
			(start 2.2352 1.524)
			(end -2.2225 1.524)
			(stroke
				(width 0.0254)
				(type default)
			)
			(layer "B.SilkS")
		)
		(fp_line
			(start -2.23266 1.5367)
			(end 2.2352 1.5367)
			(stroke
				(width 0.0254)
				(type default)
			)
			(layer "B.SilkS")
		)
		(fp_line
			(start 2.2352 1.5494)
			(end -2.2225 1.5494)
			(stroke
				(width 0.0254)
				(type default)
			)
			(layer "B.SilkS")
		)
		(fp_line
			(start -2.23266 1.5621)
			(end 2.2352 1.5621)
			(stroke
				(width 0.0254)
				(type default)
			)
			(layer "B.SilkS")
		)
		(fp_line
			(start 2.2352 1.5748)
			(end -2.2225 1.5748)
			(stroke
				(width 0.0254)
				(type default)
			)
			(layer "B.SilkS")
		)
		(fp_line
			(start -2.23266 1.5875)
			(end 2.2352 1.5875)
			(stroke
				(width 0.0254)
				(type default)
			)
			(layer "B.SilkS")
		)
		(fp_line
			(start 2.2352 1.6002)
			(end -2.2225 1.6002)
			(stroke
				(width 0.0254)
				(type default)
			)
			(layer "B.SilkS")
		)
		(fp_line
			(start -2.23266 1.6129)
			(end 2.2352 1.6129)
			(stroke
				(width 0.0254)
				(type default)
			)
			(layer "B.SilkS")
		)
		(fp_line
			(start 2.2352 1.6256)
			(end -2.2225 1.6256)
			(stroke
				(width 0.0254)
				(type default)
			)
			(layer "B.SilkS")
		)
		(fp_line
			(start -2.23266 1.6383)
			(end 2.2352 1.6383)
			(stroke
				(width 0.0254)
				(type default)
			)
			(layer "B.SilkS")
		)
		(fp_line
			(start 2.2352 1.651)
			(end -2.2225 1.651)
			(stroke
				(width 0.0254)
				(type default)
			)
			(layer "B.SilkS")
		)
		(fp_line
			(start -2.159 1.651)
			(end 2.794 1.651)
			(stroke
				(width 0.2032)
				(type default)
			)
			(layer "B.SilkS")
		)
		(fp_line
			(start -2.23266 1.6637)
			(end 2.2352 1.6637)
			(stroke
				(width 0.0254)
				(type default)
			)
			(layer "B.SilkS")
		)
		(fp_line
			(start 2.2352 1.6764)
			(end -2.2225 1.6764)
			(stroke
				(width 0.0254)
				(type default)
			)
			(layer "B.SilkS")
		)
		(fp_line
			(start -2.23266 1.6891)
			(end 2.2352 1.6891)
			(stroke
				(width 0.0254)
				(type default)
			)
			(layer "B.SilkS")
		)
		(fp_line
			(start 2.2352 1.7018)
			(end -2.2225 1.7018)
			(stroke
				(width 0.0254)
				(type default)
			)
			(layer "B.SilkS")
		)
		(fp_line
			(start -2.23266 1.7145)
			(end 2.2352 1.7145)
			(stroke
				(width 0.0254)
				(type default)
			)
			(layer "B.SilkS")
		)
		(fp_line
			(start 2.2352 1.7272)
			(end -2.2225 1.7272)
			(stroke
				(width 0.0254)
				(type default)
			)
			(layer "B.SilkS")
		)
		(fp_line
			(start -2.23266 1.7399)
			(end 2.2352 1.7399)
			(stroke
				(width 0.0254)
				(type default)
			)
			(layer "B.SilkS")
		)
		(fp_line
			(start 2.2352 1.7526)
			(end -2.2225 1.7526)
			(stroke
				(width 0.0254)
				(type default)
			)
			(layer "B.SilkS")
		)
		(fp_line
			(start -2.23266 1.7653)
			(end 2.2352 1.7653)
			(stroke
				(width 0.0254)
				(type default)
			)
			(layer "B.SilkS")
		)
		(fp_line
			(start 2.2352 1.778)
			(end -2.2225 1.778)
			(stroke
				(width 0.0254)
				(type default)
			)
			(layer "B.SilkS")
		)
		(fp_line
			(start -2.23266 1.7907)
			(end 2.2352 1.7907)
			(stroke
				(width 0.0254)
				(type default)
			)
			(layer "B.SilkS")
		)
		(fp_line
			(start 2.2352 1.8034)
			(end -2.2225 1.8034)
			(stroke
				(width 0.0254)
				(type default)
			)
			(layer "B.SilkS")
		)
		(fp_line
			(start -2.23266 1.8161)
			(end 2.2352 1.8161)
			(stroke
				(width 0.0254)
				(type default)
			)
			(layer "B.SilkS")
		)
		(fp_line
			(start -2.23266 1.8288)
			(end 2.2352 1.8288)
			(stroke
				(width 0.0254)
				(type default)
			)
			(layer "B.SilkS")
		)
		(fp_line
			(start 2.2352 1.8415)
			(end 2.2352 -1.8415)
			(stroke
				(width 0.0254)
				(type default)
			)
			(layer "B.SilkS")
		)
		(fp_line
			(start -2.2352 1.8415)
			(end 2.2352 1.8415)
			(stroke
				(width 0.0254)
				(type default)
			)
			(layer "B.SilkS")
		)
		(fp_line
			(start 2.794 4.064)
			(end 2.794 1.651)
			(stroke
				(width 0.508)
				(type default)
			)
			(layer "B.SilkS")
		)
		(fp_poly
			(pts
				(xy 2.794 3.81) (xy -2.794 3.81) (xy -2.794 -3.81) (xy 2.794 -3.81)
			)
			(stroke
				(width 0)
				(type default)
			)
			(fill no)
			(layer "B.CrtYd")
		)
		(fp_poly
			(pts
				(xy 2.794 -3.81) (xy -2.794 -3.81) (xy -2.794 3.81) (xy 2.794 3.81)
			)
			(stroke
				(width 0)
				(type default)
			)
			(fill no)
			(layer "B.Fab")
		)
		(pad "1" smd rect
			(at 1.95072 2.8194 270)
			(size 0.3556 1.524)
			(layers "B.Cu" "B.Mask" "B.Paste")
			(net "PCIE_RST_R_N")
		)
		(pad "2" smd rect
			(at 1.30048 2.8194 270)
			(size 0.3556 1.524)
			(layers "B.Cu" "B.Mask" "B.Paste")
			(net "UART_COMP_R_TX")
		)
		(pad "3" smd rect
			(at 0.65024 2.8194 270)
			(size 0.3556 1.524)
			(layers "B.Cu" "B.Mask" "B.Paste")
			(net "UART_COMP_OUT_TX")
		)
		(pad "4" smd rect
			(at 0 2.8194 270)
			(size 0.3556 1.524)
			(layers "B.Cu" "B.Mask" "B.Paste")
			(net "PCIE_RST_R_N")
		)
		(pad "5" smd rect
			(at -0.65024 2.8194 270)
			(size 0.3556 1.524)
			(layers "B.Cu" "B.Mask" "B.Paste")
			(net "UART_COMP_IN_RX_AND_R")
		)
		(pad "6" smd rect
			(at -1.30048 2.8194 270)
			(size 0.3556 1.524)
			(layers "B.Cu" "B.Mask" "B.Paste")
			(net "UART_COMP_R_RX")
		)
		(pad "7" smd rect
			(at -1.95072 2.8194 270)
			(size 0.3556 1.524)
			(layers "B.Cu" "B.Mask" "B.Paste")
			(net "GND")
		)
		(pad "8" smd rect
			(at -1.95072 -2.8194 270)
			(size 0.3556 1.524)
			(layers "B.Cu" "B.Mask" "B.Paste")
			(net "UART_EXP_BMC_TX")
		)
		(pad "9" smd rect
			(at -1.30048 -2.8194 270)
			(size 0.3556 1.524)
			(layers "B.Cu" "B.Mask" "B.Paste")
			(net "UART_SDB_TX_R")
		)
		(pad "10" smd rect
			(at -0.65024 -2.8194 270)
			(size 0.3556 1.524)
			(layers "B.Cu" "B.Mask" "B.Paste")
			(net "EXP_UART_EN_R")
		)
		(pad "11" smd rect
			(at 0 -2.8194 270)
			(size 0.3556 1.524)
			(layers "B.Cu" "B.Mask" "B.Paste")
			(net "UART_SDB_RX")
		)
		(pad "12" smd rect
			(at 0.65024 -2.8194 270)
			(size 0.3556 1.524)
			(layers "B.Cu" "B.Mask" "B.Paste")
			(net "UART_EXP_BMC_RX")
		)
		(pad "13" smd rect
			(at 1.30048 -2.8194 270)
			(size 0.3556 1.524)
			(layers "B.Cu" "B.Mask" "B.Paste")
			(net "EXP_UART_EN_R")
		)
		(pad "14" smd rect
			(at 1.95072 -2.8194 270)
			(size 0.3556 1.524)
			(layers "B.Cu" "B.Mask" "B.Paste")
			(net "P3V3_STBY")
		)
	)
	(footprint ""
		(layer "B.Cu")
		(at 39.37 -126.5174)
		(property "Reference" "R314"
			(at 0 0 0)
			(layer "B.SilkS")
			(hide yes)
			(effects
				(font
					(size 1.27 1.27)
				)
				(justify mirror)
			)
		)
		(property "Value" "0R2J-2-GP"
			(at -0.064008 -3.993896 0)
			(unlocked yes)
			(layer "B.Fab")
			(hide yes)
			(effects
				(font
					(size 1.016 1.016)
					(thickness 0.1524)
				)
				(justify mirror)
			)
		)
		(property "Device Type" "R402H16"
			(at -0.064008 -5.517896 0)
			(unlocked yes)
			(layer "B.Fab")
			(hide yes)
			(effects
				(font
					(size 1.016 1.016)
					(thickness 0.1524)
				)
				(justify mirror)
			)
		)
		(duplicate_pad_numbers_are_jumpers no)
		(fp_line
			(start -0.508 -0.9398)
			(end 0.508 -0.9398)
			(stroke
				(width 0.1524)
				(type default)
			)
			(layer "B.SilkS")
		)
		(fp_line
			(start 0.508 -0.9398)
			(end 0.508 0.9398)
			(stroke
				(width 0.1524)
				(type default)
			)
			(layer "B.SilkS")
		)
		(fp_rect
			(start 0.508 0.9398)
			(end -0.508 -0.9398)
			(stroke
				(width 0)
				(type default)
			)
			(fill no)
			(layer "B.CrtYd")
		)
		(fp_rect
			(start 0.508 0.9398)
			(end -0.508 -0.9398)
			(stroke
				(width 0)
				(type default)
			)
			(fill no)
			(layer "B.Fab")
		)
		(pad "1" smd custom
			(at 0 -0.4445 180)
			(size 0.1397 0.1397)
			(layers "B.Cu" "B.Mask" "B.Paste")
			(net "BMC_EXTRST_N")
			(options
				(clearance outline)
				(anchor circle)
			)
			(primitives
				(gr_poly
					(pts
						(arc
							(start -0.1778 0.2794)
							(mid -0.249642 0.249642)
							(end -0.2794 0.1778)
						)
						(arc
							(start -0.2794 -0.1778)
							(mid -0.249642 -0.249642)
							(end -0.1778 -0.2794)
						)
						(arc
							(start 0.1778 -0.2794)
							(mid 0.249642 -0.249642)
							(end 0.2794 -0.1778)
						)
						(arc
							(start 0.2794 0.1778)
							(mid 0.249642 0.249642)
							(end 0.1778 0.2794)
						)
					)
					(width 0)
					(fill yes)
				)
			)
		)
		(pad "2" smd custom
			(at 0 0.4445 180)
			(size 0.1397 0.1397)
			(layers "B.Cu" "B.Mask" "B.Paste")
			(net "RST_BMC_EXTRST_N")
			(options
				(clearance outline)
				(anchor circle)
			)
			(primitives
				(gr_poly
					(pts
						(arc
							(start -0.1778 0.2794)
							(mid -0.249642 0.249642)
							(end -0.2794 0.1778)
						)
						(arc
							(start -0.2794 -0.1778)
							(mid -0.249642 -0.249642)
							(end -0.1778 -0.2794)
						)
						(arc
							(start 0.1778 -0.2794)
							(mid 0.249642 -0.249642)
							(end 0.2794 -0.1778)
						)
						(arc
							(start 0.2794 0.1778)
							(mid 0.249642 0.249642)
							(end 0.1778 0.2794)
						)
					)
					(width 0)
					(fill yes)
				)
			)
		)
	)
	(footprint ""
		(layer "B.Cu")
		(at 87.691976 -148.73224 180)
		(property "Reference" "R429"
			(at 0 0 0)
			(layer "B.SilkS")
			(hide yes)
			(effects
				(font
					(size 1.27 1.27)
				)
				(justify mirror)
			)
		)
		(property "Value" "4K7R2F-GP"
			(at -0.064008 -3.993896 180)
			(unlocked yes)
			(layer "B.Fab")
			(hide yes)
			(effects
				(font
					(size 1.016 1.016)
					(thickness 0.1524)
				)
				(justify mirror)
			)
		)
		(property "Device Type" "R402H16"
			(at -0.064008 -5.517896 180)
			(unlocked yes)
			(layer "B.Fab")
			(hide yes)
			(effects
				(font
					(size 1.016 1.016)
					(thickness 0.1524)
				)
				(justify mirror)
			)
		)
		(duplicate_pad_numbers_are_jumpers no)
		(fp_line
			(start 0.508 -0.9398)
			(end 0.508 0.9398)
			(stroke
				(width 0.1524)
				(type default)
			)
			(layer "B.SilkS")
		)
		(fp_line
			(start -0.508 -0.9398)
			(end 0.508 -0.9398)
			(stroke
				(width 0.1524)
				(type default)
			)
			(layer "B.SilkS")
		)
		(fp_rect
			(start 0.508 0.9398)
			(end -0.508 -0.9398)
			(stroke
				(width 0)
				(type default)
			)
			(fill no)
			(layer "B.CrtYd")
		)
		(fp_rect
			(start 0.508 0.9398)
			(end -0.508 -0.9398)
			(stroke
				(width 0)
				(type default)
			)
			(fill no)
			(layer "B.Fab")
		)
		(pad "1" smd custom
			(at 0 -0.4445)
			(size 0.1397 0.1397)
			(layers "B.Cu" "B.Mask" "B.Paste")
			(net "TCA9555_A1")
			(options
				(clearance outline)
				(anchor circle)
			)
			(primitives
				(gr_poly
					(pts
						(arc
							(start -0.1778 0.2794)
							(mid -0.249642 0.249642)
							(end -0.2794 0.1778)
						)
						(arc
							(start -0.2794 -0.1778)
							(mid -0.249642 -0.249642)
							(end -0.1778 -0.2794)
						)
						(arc
							(start 0.1778 -0.2794)
							(mid 0.249642 -0.249642)
							(end 0.2794 -0.1778)
						)
						(arc
							(start 0.2794 0.1778)
							(mid 0.249642 0.249642)
							(end 0.1778 0.2794)
						)
					)
					(width 0)
					(fill yes)
				)
			)
		)
		(pad "2" smd custom
			(at 0 0.4445)
			(size 0.1397 0.1397)
			(layers "B.Cu" "B.Mask" "B.Paste")
			(net "GND")
			(options
				(clearance outline)
				(anchor circle)
			)
			(primitives
				(gr_poly
					(pts
						(arc
							(start -0.1778 0.2794)
							(mid -0.249642 0.249642)
							(end -0.2794 0.1778)
						)
						(arc
							(start -0.2794 -0.1778)
							(mid -0.249642 -0.249642)
							(end -0.1778 -0.2794)
						)
						(arc
							(start 0.1778 -0.2794)
							(mid 0.249642 -0.249642)
							(end 0.2794 -0.1778)
						)
						(arc
							(start 0.2794 0.1778)
							(mid 0.249642 0.249642)
							(end 0.1778 0.2794)
						)
					)
					(width 0)
					(fill yes)
				)
			)
		)
	)
	(footprint ""
		(layer "B.Cu")
		(at 201.177398 -49.788572 -90)
		(property "Reference" "C335"
			(at 0 0 90)
			(layer "B.SilkS")
			(hide yes)
			(effects
				(font
					(size 1.27 1.27)
				)
				(justify mirror)
			)
		)
		(property "Value" "SC10U6D3V5KX-4GP"
			(at 0.0762 -6.1214 270)
			(unlocked yes)
			(layer "B.Fab")
			(hide yes)
			(effects
				(font
					(size 1.016 1.016)
					(thickness 0.1524)
				)
				(justify mirror)
			)
		)
		(property "Device Type" "C805H58"
			(at 0.0762 -8.1534 270)
			(unlocked yes)
			(layer "B.Fab")
			(hide yes)
			(effects
				(font
					(size 1.016 1.016)
					(thickness 0.1524)
				)
				(justify mirror)
			)
		)
		(duplicate_pad_numbers_are_jumpers no)
		(fp_line
			(start -0.635 0)
			(end 0.635 0)
			(stroke
				(width 0.508)
				(type default)
			)
			(layer "B.SilkS")
		)
		(fp_rect
			(start 0.9652 1.778)
			(end -0.9652 -1.778)
			(stroke
				(width 0)
				(type default)
			)
			(fill no)
			(layer "B.CrtYd")
		)
		(fp_poly
			(pts
				(xy 0.9652 -1.778) (xy -0.9652 -1.778) (xy -0.9652 1.778) (xy 0.9652 1.778)
			)
			(stroke
				(width 0)
				(type default)
			)
			(fill no)
			(layer "B.Fab")
		)
		(pad "1" smd rect
			(at 0 -0.9652 90)
			(size 1.397 1.143)
			(layers "B.Cu" "B.Mask" "B.Paste")
			(net "SYS_PLL_VDD")
		)
		(pad "2" smd rect
			(at 0 0.9652 90)
			(size 1.397 1.143)
			(layers "B.Cu" "B.Mask" "B.Paste")
			(net "GND")
		)
	)
	(footprint ""
		(layer "B.Cu")
		(at 177.9778 -77.4954)
		(property "Reference" "TP103"
			(at 0 0 0)
			(layer "B.SilkS")
			(hide yes)
			(effects
				(font
					(size 1.27 1.27)
				)
				(justify mirror)
			)
		)
		(property "Value" "TPAD28-2-GP"
			(at 0.0127 -1.6637 0)
			(unlocked yes)
			(layer "B.Fab")
			(hide yes)
			(effects
				(font
					(size 1.016 1.016)
					(thickness 0.1524)
				)
				(justify mirror)
			)
		)
		(property "Device Type" "TPAD28"
			(at 0.0127 -3.1877 0)
			(unlocked yes)
			(layer "B.Fab")
			(hide yes)
			(effects
				(font
					(size 1.016 1.016)
					(thickness 0.1524)
				)
				(justify mirror)
			)
		)
		(duplicate_pad_numbers_are_jumpers no)
		(fp_poly
			(pts
				(arc
					(start 0.3556 0)
					(mid -0.3556 0)
					(end 0.3556 0)
				)
			)
			(stroke
				(width 0)
				(type default)
			)
			(fill no)
			(layer "B.CrtYd")
		)
		(fp_poly
			(pts
				(arc
					(start 0.6096 0)
					(mid -0.6096 0)
					(end 0.6096 0)
				)
			)
			(stroke
				(width 0)
				(type default)
			)
			(fill no)
			(layer "B.Fab")
		)
		(pad "1" smd circle
			(at 0 0 180)
			(size 0.7112 0.7112)
			(layers "B.Cu" "B.Mask" "B.Paste")
			(net "IOC_GPIO_18")
		)
	)
	(footprint ""
		(layer "B.Cu")
		(at 93.246702 -158.624778)
		(property "Reference" "C11"
			(at 0 0 0)
			(layer "B.SilkS")
			(hide yes)
			(effects
				(font
					(size 1.27 1.27)
				)
				(justify mirror)
			)
		)
		(property "Value" "SC1U16V2KX-7-GP"
			(at -1.7526 -1.6002 0)
			(unlocked yes)
			(layer "B.Fab")
			(hide yes)
			(effects
				(font
					(size 1.016 1.016)
					(thickness 0.1524)
				)
				(justify mirror)
			)
		)
		(property "Device Type" "C402-TO0D2H24"
			(at -1.7526 -3.1242 0)
			(unlocked yes)
			(layer "B.Fab")
			(hide yes)
			(effects
				(font
					(size 1.016 1.016)
					(thickness 0.1524)
				)
				(justify mirror)
			)
		)
		(duplicate_pad_numbers_are_jumpers no)
		(fp_rect
			(start 0.4826 0.889)
			(end -0.4826 -0.889)
			(stroke
				(width 0)
				(type default)
			)
			(fill no)
			(layer "B.CrtYd")
		)
		(fp_rect
			(start 0.4826 0.889)
			(end -0.4826 -0.889)
			(stroke
				(width 0)
				(type default)
			)
			(fill no)
			(layer "B.Fab")
		)
		(pad "1" smd custom
			(at 0 -0.4572 180)
			(size 0.1524 0.1524)
			(layers "B.Cu" "B.Mask" "B.Paste")
			(net "P3V3_STBY")
			(options
				(clearance outline)
				(anchor circle)
			)
			(primitives
				(gr_poly
					(pts
						(arc
							(start -0.254 -0.3048)
							(mid -0.325842 -0.275042)
							(end -0.3556 -0.2032)
						)
						(arc
							(start -0.3556 0.2032)
							(mid -0.325842 0.275042)
							(end -0.254 0.3048)
						)
						(arc
							(start 0.254 0.3048)
							(mid 0.325842 0.275042)
							(end 0.3556 0.2032)
						)
						(arc
							(start 0.3556 -0.2032)
							(mid 0.325842 -0.275042)
							(end 0.254 -0.3048)
						)
					)
					(width 0)
					(fill yes)
				)
			)
		)
		(pad "2" smd custom
			(at 0 0.4572 180)
			(size 0.1524 0.1524)
			(layers "B.Cu" "B.Mask" "B.Paste")
			(net "GND")
			(options
				(clearance outline)
				(anchor circle)
			)
			(primitives
				(gr_poly
					(pts
						(arc
							(start -0.254 -0.3048)
							(mid -0.325842 -0.275042)
							(end -0.3556 -0.2032)
						)
						(arc
							(start -0.3556 0.2032)
							(mid -0.325842 0.275042)
							(end -0.254 0.3048)
						)
						(arc
							(start 0.254 0.3048)
							(mid 0.325842 0.275042)
							(end 0.3556 0.2032)
						)
						(arc
							(start 0.3556 -0.2032)
							(mid 0.325842 -0.275042)
							(end 0.254 -0.3048)
						)
					)
					(width 0)
					(fill yes)
				)
			)
		)
	)
	(footprint ""
		(layer "B.Cu")
		(at 200.75144 -61.2648 180)
		(property "Reference" "C439"
			(at 0 0 0)
			(layer "B.SilkS")
			(hide yes)
			(effects
				(font
					(size 1.27 1.27)
				)
				(justify mirror)
			)
		)
		(property "Value" "SCD1U16V2KX-3GP"
			(at -1.1811 -2.7051 180)
			(unlocked yes)
			(layer "B.Fab")
			(hide yes)
			(effects
				(font
					(size 1.016 1.016)
					(thickness 0.1524)
				)
				(justify mirror)
			)
		)
		(property "Device Type" "C402H22"
			(at -1.1811 -4.2291 180)
			(unlocked yes)
			(layer "B.Fab")
			(hide yes)
			(effects
				(font
					(size 1.016 1.016)
					(thickness 0.1524)
				)
				(justify mirror)
			)
		)
		(duplicate_pad_numbers_are_jumpers no)
		(fp_rect
			(start 0.4318 0.9525)
			(end -0.4318 -0.9525)
			(stroke
				(width 0)
				(type default)
			)
			(fill no)
			(layer "B.CrtYd")
		)
		(fp_rect
			(start 0.4318 0.9525)
			(end -0.4318 -0.9525)
			(stroke
				(width 0)
				(type default)
			)
			(fill no)
			(layer "B.Fab")
		)
		(pad "1" smd custom
			(at 0 -0.4445)
			(size 0.1524 0.1524)
			(layers "B.Cu" "B.Mask" "B.Paste")
			(net "P1V8")
			(options
				(clearance outline)
				(anchor circle)
			)
			(primitives
				(gr_poly
					(pts
						(arc
							(start 0.3048 0.2032)
							(mid 0.275042 0.275042)
							(end 0.2032 0.3048)
						)
						(arc
							(start -0.2032 0.3048)
							(mid -0.275042 0.275042)
							(end -0.3048 0.2032)
						)
						(arc
							(start -0.3048 -0.2032)
							(mid -0.275042 -0.275042)
							(end -0.2032 -0.3048)
						)
						(arc
							(start 0.2032 -0.3048)
							(mid 0.275042 -0.275042)
							(end 0.3048 -0.2032)
						)
					)
					(width 0)
					(fill yes)
				)
			)
		)
		(pad "2" smd custom
			(at 0 0.4445)
			(size 0.1524 0.1524)
			(layers "B.Cu" "B.Mask" "B.Paste")
			(net "GND")
			(options
				(clearance outline)
				(anchor circle)
			)
			(primitives
				(gr_poly
					(pts
						(arc
							(start 0.3048 0.2032)
							(mid 0.275042 0.275042)
							(end 0.2032 0.3048)
						)
						(arc
							(start -0.2032 0.3048)
							(mid -0.275042 0.275042)
							(end -0.3048 0.2032)
						)
						(arc
							(start -0.3048 -0.2032)
							(mid -0.275042 -0.275042)
							(end -0.2032 -0.3048)
						)
						(arc
							(start 0.2032 -0.3048)
							(mid 0.275042 -0.275042)
							(end 0.3048 -0.2032)
						)
					)
					(width 0)
					(fill yes)
				)
			)
		)
	)
	(footprint ""
		(layer "B.Cu")
		(at 38.43401 -121.142252 90)
		(property "Reference" "R282"
			(at 0 0 90)
			(layer "B.SilkS")
			(hide yes)
			(effects
				(font
					(size 1.27 1.27)
				)
				(justify mirror)
			)
		)
		(property "Value" "4K7R2F-GP"
			(at -0.064008 -3.993896 90)
			(unlocked yes)
			(layer "B.Fab")
			(hide yes)
			(effects
				(font
					(size 1.016 1.016)
					(thickness 0.1524)
				)
				(justify mirror)
			)
		)
		(property "Device Type" "R402H16"
			(at -0.064008 -5.517896 90)
			(unlocked yes)
			(layer "B.Fab")
			(hide yes)
			(effects
				(font
					(size 1.016 1.016)
					(thickness 0.1524)
				)
				(justify mirror)
			)
		)
		(duplicate_pad_numbers_are_jumpers no)
		(fp_line
			(start 0.508 -0.9398)
			(end 0.508 0.9398)
			(stroke
				(width 0.1524)
				(type default)
			)
			(layer "B.SilkS")
		)
		(fp_line
			(start -0.508 -0.9398)
			(end 0.508 -0.9398)
			(stroke
				(width 0.1524)
				(type default)
			)
			(layer "B.SilkS")
		)
		(fp_rect
			(start 0.508 0.9398)
			(end -0.508 -0.9398)
			(stroke
				(width 0)
				(type default)
			)
			(fill no)
			(layer "B.CrtYd")
		)
		(fp_rect
			(start 0.508 0.9398)
			(end -0.508 -0.9398)
			(stroke
				(width 0)
				(type default)
			)
			(fill no)
			(layer "B.Fab")
		)
		(pad "1" smd custom
			(at 0 -0.4445 270)
			(size 0.1397 0.1397)
			(layers "B.Cu" "B.Mask" "B.Paste")
			(net "P3V3_STBY")
			(options
				(clearance outline)
				(anchor circle)
			)
			(primitives
				(gr_poly
					(pts
						(arc
							(start -0.1778 0.2794)
							(mid -0.249642 0.249642)
							(end -0.2794 0.1778)
						)
						(arc
							(start -0.2794 -0.1778)
							(mid -0.249642 -0.249642)
							(end -0.1778 -0.2794)
						)
						(arc
							(start 0.1778 -0.2794)
							(mid 0.249642 -0.249642)
							(end 0.2794 -0.1778)
						)
						(arc
							(start 0.2794 0.1778)
							(mid 0.249642 0.249642)
							(end 0.1778 0.2794)
						)
					)
					(width 0)
					(fill yes)
				)
			)
		)
		(pad "2" smd custom
			(at 0 0.4445 270)
			(size 0.1397 0.1397)
			(layers "B.Cu" "B.Mask" "B.Paste")
			(net "TEMP_3_A0")
			(options
				(clearance outline)
				(anchor circle)
			)
			(primitives
				(gr_poly
					(pts
						(arc
							(start -0.1778 0.2794)
							(mid -0.249642 0.249642)
							(end -0.2794 0.1778)
						)
						(arc
							(start -0.2794 -0.1778)
							(mid -0.249642 -0.249642)
							(end -0.1778 -0.2794)
						)
						(arc
							(start 0.1778 -0.2794)
							(mid 0.249642 -0.249642)
							(end 0.2794 -0.1778)
						)
						(arc
							(start 0.2794 0.1778)
							(mid 0.249642 0.249642)
							(end 0.1778 0.2794)
						)
					)
					(width 0)
					(fill yes)
				)
			)
		)
	)
	(footprint ""
		(layer "B.Cu")
		(at 42.3418 -128.2192)
		(property "Reference" "R325"
			(at 0 0 0)
			(layer "B.SilkS")
			(hide yes)
			(effects
				(font
					(size 1.27 1.27)
				)
				(justify mirror)
			)
		)
		(property "Value" "0R2J-2-GP"
			(at -0.064008 -3.993896 0)
			(unlocked yes)
			(layer "B.Fab")
			(hide yes)
			(effects
				(font
					(size 1.016 1.016)
					(thickness 0.1524)
				)
				(justify mirror)
			)
		)
		(property "Device Type" "R402H16"
			(at -0.064008 -5.517896 0)
			(unlocked yes)
			(layer "B.Fab")
			(hide yes)
			(effects
				(font
					(size 1.016 1.016)
					(thickness 0.1524)
				)
				(justify mirror)
			)
		)
		(duplicate_pad_numbers_are_jumpers no)
		(fp_line
			(start -0.508 -0.9398)
			(end 0.508 -0.9398)
			(stroke
				(width 0.1524)
				(type default)
			)
			(layer "B.SilkS")
		)
		(fp_line
			(start 0.508 -0.9398)
			(end 0.508 0.9398)
			(stroke
				(width 0.1524)
				(type default)
			)
			(layer "B.SilkS")
		)
		(fp_rect
			(start 0.508 0.9398)
			(end -0.508 -0.9398)
			(stroke
				(width 0)
				(type default)
			)
			(fill no)
			(layer "B.CrtYd")
		)
		(fp_rect
			(start 0.508 0.9398)
			(end -0.508 -0.9398)
			(stroke
				(width 0)
				(type default)
			)
			(fill no)
			(layer "B.Fab")
		)
		(pad "1" smd custom
			(at 0 -0.4445 180)
			(size 0.1397 0.1397)
			(layers "B.Cu" "B.Mask" "B.Paste")
			(net "BMC0_SRST_N")
			(options
				(clearance outline)
				(anchor circle)
			)
			(primitives
				(gr_poly
					(pts
						(arc
							(start -0.1778 0.2794)
							(mid -0.249642 0.249642)
							(end -0.2794 0.1778)
						)
						(arc
							(start -0.2794 -0.1778)
							(mid -0.249642 -0.249642)
							(end -0.1778 -0.2794)
						)
						(arc
							(start 0.1778 -0.2794)
							(mid 0.249642 -0.249642)
							(end 0.2794 -0.1778)
						)
						(arc
							(start 0.2794 0.1778)
							(mid 0.249642 0.249642)
							(end 0.1778 0.2794)
						)
					)
					(width 0)
					(fill yes)
				)
			)
		)
		(pad "2" smd custom
			(at 0 0.4445 180)
			(size 0.1397 0.1397)
			(layers "B.Cu" "B.Mask" "B.Paste")
			(net "FM_BMC_RESET_N")
			(options
				(clearance outline)
				(anchor circle)
			)
			(primitives
				(gr_poly
					(pts
						(arc
							(start -0.1778 0.2794)
							(mid -0.249642 0.249642)
							(end -0.2794 0.1778)
						)
						(arc
							(start -0.2794 -0.1778)
							(mid -0.249642 -0.249642)
							(end -0.1778 -0.2794)
						)
						(arc
							(start 0.1778 -0.2794)
							(mid 0.249642 -0.249642)
							(end 0.2794 -0.1778)
						)
						(arc
							(start 0.2794 0.1778)
							(mid 0.249642 0.249642)
							(end 0.1778 0.2794)
						)
					)
					(width 0)
					(fill yes)
				)
			)
		)
	)
	(footprint ""
		(layer "B.Cu")
		(at 188.2394 -78.0796)
		(property "Reference" "TP87"
			(at 0 0 0)
			(layer "B.SilkS")
			(hide yes)
			(effects
				(font
					(size 1.27 1.27)
				)
				(justify mirror)
			)
		)
		(property "Value" "TPAD28-2-GP"
			(at 0.0127 -1.6637 0)
			(unlocked yes)
			(layer "B.Fab")
			(hide yes)
			(effects
				(font
					(size 1.016 1.016)
					(thickness 0.1524)
				)
				(justify mirror)
			)
		)
		(property "Device Type" "TPAD28"
			(at 0.0127 -3.1877 0)
			(unlocked yes)
			(layer "B.Fab")
			(hide yes)
			(effects
				(font
					(size 1.016 1.016)
					(thickness 0.1524)
				)
				(justify mirror)
			)
		)
		(duplicate_pad_numbers_are_jumpers no)
		(fp_poly
			(pts
				(arc
					(start 0.3556 0)
					(mid -0.3556 0)
					(end 0.3556 0)
				)
			)
			(stroke
				(width 0)
				(type default)
			)
			(fill no)
			(layer "B.CrtYd")
		)
		(fp_poly
			(pts
				(arc
					(start 0.6096 0)
					(mid -0.6096 0)
					(end 0.6096 0)
				)
			)
			(stroke
				(width 0)
				(type default)
			)
			(fill no)
			(layer "B.Fab")
		)
		(pad "1" smd circle
			(at 0 0 180)
			(size 0.7112 0.7112)
			(layers "B.Cu" "B.Mask" "B.Paste")
			(net "IOC_GPIO_2")
		)
	)
	(footprint ""
		(layer "B.Cu")
		(at 67.972686 -149.304502 90)
		(property "Reference" "R386"
			(at 0 0 90)
			(layer "B.SilkS")
			(hide yes)
			(effects
				(font
					(size 1.27 1.27)
				)
				(justify mirror)
			)
		)
		(property "Value" "4K7R2F-GP"
			(at -0.064008 -3.993896 90)
			(unlocked yes)
			(layer "B.Fab")
			(hide yes)
			(effects
				(font
					(size 1.016 1.016)
					(thickness 0.1524)
				)
				(justify mirror)
			)
		)
		(property "Device Type" "R402H16"
			(at -0.064008 -5.517896 90)
			(unlocked yes)
			(layer "B.Fab")
			(hide yes)
			(effects
				(font
					(size 1.016 1.016)
					(thickness 0.1524)
				)
				(justify mirror)
			)
		)
		(duplicate_pad_numbers_are_jumpers no)
		(fp_line
			(start 0.508 -0.9398)
			(end 0.508 0.9398)
			(stroke
				(width 0.1524)
				(type default)
			)
			(layer "B.SilkS")
		)
		(fp_line
			(start -0.508 -0.9398)
			(end 0.508 -0.9398)
			(stroke
				(width 0.1524)
				(type default)
			)
			(layer "B.SilkS")
		)
		(fp_rect
			(start 0.508 0.9398)
			(end -0.508 -0.9398)
			(stroke
				(width 0)
				(type default)
			)
			(fill no)
			(layer "B.CrtYd")
		)
		(fp_rect
			(start 0.508 0.9398)
			(end -0.508 -0.9398)
			(stroke
				(width 0)
				(type default)
			)
			(fill no)
			(layer "B.Fab")
		)
		(pad "1" smd custom
			(at 0 -0.4445 270)
			(size 0.1397 0.1397)
			(layers "B.Cu" "B.Mask" "B.Paste")
			(net "GND")
			(options
				(clearance outline)
				(anchor circle)
			)
			(primitives
				(gr_poly
					(pts
						(arc
							(start -0.1778 0.2794)
							(mid -0.249642 0.249642)
							(end -0.2794 0.1778)
						)
						(arc
							(start -0.2794 -0.1778)
							(mid -0.249642 -0.249642)
							(end -0.1778 -0.2794)
						)
						(arc
							(start 0.1778 -0.2794)
							(mid 0.249642 -0.249642)
							(end 0.2794 -0.1778)
						)
						(arc
							(start 0.2794 0.1778)
							(mid 0.249642 0.249642)
							(end 0.1778 0.2794)
						)
					)
					(width 0)
					(fill yes)
				)
			)
		)
		(pad "2" smd custom
			(at 0 0.4445 270)
			(size 0.1397 0.1397)
			(layers "B.Cu" "B.Mask" "B.Paste")
			(net "NCSI_TXD0")
			(options
				(clearance outline)
				(anchor circle)
			)
			(primitives
				(gr_poly
					(pts
						(arc
							(start -0.1778 0.2794)
							(mid -0.249642 0.249642)
							(end -0.2794 0.1778)
						)
						(arc
							(start -0.2794 -0.1778)
							(mid -0.249642 -0.249642)
							(end -0.1778 -0.2794)
						)
						(arc
							(start 0.1778 -0.2794)
							(mid 0.249642 -0.249642)
							(end 0.2794 -0.1778)
						)
						(arc
							(start 0.2794 0.1778)
							(mid 0.249642 0.249642)
							(end 0.1778 0.2794)
						)
					)
					(width 0)
					(fill yes)
				)
			)
		)
	)
	(footprint ""
		(layer "B.Cu")
		(at 115.9256 -14.2494)
		(property "Reference" "R741"
			(at 0 0 0)
			(layer "B.SilkS")
			(hide yes)
			(effects
				(font
					(size 1.27 1.27)
				)
				(justify mirror)
			)
		)
		(property "Value" "0R2J-2-GP"
			(at -0.064008 -3.993896 0)
			(unlocked yes)
			(layer "B.Fab")
			(hide yes)
			(effects
				(font
					(size 1.016 1.016)
					(thickness 0.1524)
				)
				(justify mirror)
			)
		)
		(property "Device Type" "R402H16"
			(at -0.064008 -5.517896 0)
			(unlocked yes)
			(layer "B.Fab")
			(hide yes)
			(effects
				(font
					(size 1.016 1.016)
					(thickness 0.1524)
				)
				(justify mirror)
			)
		)
		(duplicate_pad_numbers_are_jumpers no)
		(fp_line
			(start -0.508 -0.9398)
			(end 0.508 -0.9398)
			(stroke
				(width 0.1524)
				(type default)
			)
			(layer "B.SilkS")
		)
		(fp_line
			(start 0.508 -0.9398)
			(end 0.508 0.9398)
			(stroke
				(width 0.1524)
				(type default)
			)
			(layer "B.SilkS")
		)
		(fp_rect
			(start 0.508 0.9398)
			(end -0.508 -0.9398)
			(stroke
				(width 0)
				(type default)
			)
			(fill no)
			(layer "B.CrtYd")
		)
		(fp_rect
			(start 0.508 0.9398)
			(end -0.508 -0.9398)
			(stroke
				(width 0)
				(type default)
			)
			(fill no)
			(layer "B.Fab")
		)
		(pad "1" smd custom
			(at 0 -0.4445 180)
			(size 0.1397 0.1397)
			(layers "B.Cu" "B.Mask" "B.Paste")
			(net "IOM_ADM1278_EN")
			(options
				(clearance outline)
				(anchor circle)
			)
			(primitives
				(gr_poly
					(pts
						(arc
							(start -0.1778 0.2794)
							(mid -0.249642 0.249642)
							(end -0.2794 0.1778)
						)
						(arc
							(start -0.2794 -0.1778)
							(mid -0.249642 -0.249642)
							(end -0.1778 -0.2794)
						)
						(arc
							(start 0.1778 -0.2794)
							(mid 0.249642 -0.249642)
							(end 0.2794 -0.1778)
						)
						(arc
							(start 0.2794 0.1778)
							(mid 0.249642 0.249642)
							(end 0.1778 0.2794)
						)
					)
					(width 0)
					(fill yes)
				)
			)
		)
		(pad "2" smd custom
			(at 0 0.4445 180)
			(size 0.1397 0.1397)
			(layers "B.Cu" "B.Mask" "B.Paste")
			(net "MB0_HS_ENABLE")
			(options
				(clearance outline)
				(anchor circle)
			)
			(primitives
				(gr_poly
					(pts
						(arc
							(start -0.1778 0.2794)
							(mid -0.249642 0.249642)
							(end -0.2794 0.1778)
						)
						(arc
							(start -0.2794 -0.1778)
							(mid -0.249642 -0.249642)
							(end -0.1778 -0.2794)
						)
						(arc
							(start 0.1778 -0.2794)
							(mid 0.249642 -0.249642)
							(end 0.2794 -0.1778)
						)
						(arc
							(start 0.2794 0.1778)
							(mid 0.249642 0.249642)
							(end 0.1778 0.2794)
						)
					)
					(width 0)
					(fill yes)
				)
			)
		)
	)
	(footprint ""
		(layer "B.Cu")
		(at 193.9798 -61.6204 90)
		(property "Reference" "C420"
			(at 0 0 90)
			(layer "B.SilkS")
			(hide yes)
			(effects
				(font
					(size 1.27 1.27)
				)
				(justify mirror)
			)
		)
		(property "Value" "SCD1U6D3V1KX-GP"
			(at 2.8321 -1.7399 90)
			(unlocked yes)
			(layer "B.Fab")
			(hide yes)
			(effects
				(font
					(size 1.016 1.016)
					(thickness 0.1524)
				)
				(justify mirror)
			)
		)
		(property "Device Type" "C0201H13"
			(at 2.8321 -3.2639 90)
			(unlocked yes)
			(layer "B.Fab")
			(hide yes)
			(effects
				(font
					(size 1.016 1.016)
					(thickness 0.1524)
				)
				(justify mirror)
			)
		)
		(duplicate_pad_numbers_are_jumpers no)
		(fp_rect
			(start 0.2794 0.6477)
			(end -0.2794 -0.6477)
			(stroke
				(width 0)
				(type default)
			)
			(fill no)
			(layer "B.CrtYd")
		)
		(fp_rect
			(start 0.2794 0.6477)
			(end -0.2794 -0.6477)
			(stroke
				(width 0)
				(type default)
			)
			(fill no)
			(layer "B.Fab")
		)
		(pad "1" smd custom
			(at 0 -0.2794 270)
			(size 0.0762 0.0762)
			(layers "B.Cu" "B.Mask" "B.Paste")
			(net "P0V975")
			(options
				(clearance outline)
				(anchor circle)
			)
			(primitives
				(gr_poly
					(pts
						(arc
							(start 0.1524 0.127)
							(mid 0.137521 0.162921)
							(end 0.1016 0.1778)
						)
						(arc
							(start -0.1016 0.1778)
							(mid -0.137521 0.162921)
							(end -0.1524 0.127)
						)
						(arc
							(start -0.1524 -0.127)
							(mid -0.137521 -0.162921)
							(end -0.1016 -0.1778)
						)
						(arc
							(start 0.1016 -0.1778)
							(mid 0.137521 -0.162921)
							(end 0.1524 -0.127)
						)
					)
					(width 0)
					(fill yes)
				)
			)
		)
		(pad "2" smd custom
			(at 0 0.2794 270)
			(size 0.0762 0.0762)
			(layers "B.Cu" "B.Mask" "B.Paste")
			(net "GND")
			(options
				(clearance outline)
				(anchor circle)
			)
			(primitives
				(gr_poly
					(pts
						(arc
							(start 0.1524 0.127)
							(mid 0.137521 0.162921)
							(end 0.1016 0.1778)
						)
						(arc
							(start -0.1016 0.1778)
							(mid -0.137521 0.162921)
							(end -0.1524 0.127)
						)
						(arc
							(start -0.1524 -0.127)
							(mid -0.137521 -0.162921)
							(end -0.1016 -0.1778)
						)
						(arc
							(start 0.1016 -0.1778)
							(mid 0.137521 -0.162921)
							(end 0.1524 -0.127)
						)
					)
					(width 0)
					(fill yes)
				)
			)
		)
	)
	(footprint ""
		(layer "B.Cu")
		(at 88.692228 -96.411796 180)
		(property "Reference" "R728"
			(at 0 0 0)
			(layer "B.SilkS")
			(hide yes)
			(effects
				(font
					(size 1.27 1.27)
				)
				(justify mirror)
			)
		)
		(property "Value" "4K7R2F-GP"
			(at -0.064008 -3.993896 180)
			(unlocked yes)
			(layer "B.Fab")
			(hide yes)
			(effects
				(font
					(size 1.016 1.016)
					(thickness 0.1524)
				)
				(justify mirror)
			)
		)
		(property "Device Type" "R402H16"
			(at -0.064008 -5.517896 180)
			(unlocked yes)
			(layer "B.Fab")
			(hide yes)
			(effects
				(font
					(size 1.016 1.016)
					(thickness 0.1524)
				)
				(justify mirror)
			)
		)
		(duplicate_pad_numbers_are_jumpers no)
		(fp_line
			(start 0.508 -0.9398)
			(end 0.508 0.9398)
			(stroke
				(width 0.1524)
				(type default)
			)
			(layer "B.SilkS")
		)
		(fp_line
			(start -0.508 -0.9398)
			(end 0.508 -0.9398)
			(stroke
				(width 0.1524)
				(type default)
			)
			(layer "B.SilkS")
		)
		(fp_rect
			(start 0.508 0.9398)
			(end -0.508 -0.9398)
			(stroke
				(width 0)
				(type default)
			)
			(fill no)
			(layer "B.CrtYd")
		)
		(fp_rect
			(start 0.508 0.9398)
			(end -0.508 -0.9398)
			(stroke
				(width 0)
				(type default)
			)
			(fill no)
			(layer "B.Fab")
		)
		(pad "1" smd custom
			(at 0 -0.4445)
			(size 0.1397 0.1397)
			(layers "B.Cu" "B.Mask" "B.Paste")
			(net "CONN_A_PRSNTA")
			(options
				(clearance outline)
				(anchor circle)
			)
			(primitives
				(gr_poly
					(pts
						(arc
							(start -0.1778 0.2794)
							(mid -0.249642 0.249642)
							(end -0.2794 0.1778)
						)
						(arc
							(start -0.2794 -0.1778)
							(mid -0.249642 -0.249642)
							(end -0.1778 -0.2794)
						)
						(arc
							(start 0.1778 -0.2794)
							(mid 0.249642 -0.249642)
							(end 0.2794 -0.1778)
						)
						(arc
							(start 0.2794 0.1778)
							(mid 0.249642 0.249642)
							(end 0.1778 0.2794)
						)
					)
					(width 0)
					(fill yes)
				)
			)
		)
		(pad "2" smd custom
			(at 0 0.4445)
			(size 0.1397 0.1397)
			(layers "B.Cu" "B.Mask" "B.Paste")
			(net "P3V3_STBY")
			(options
				(clearance outline)
				(anchor circle)
			)
			(primitives
				(gr_poly
					(pts
						(arc
							(start -0.1778 0.2794)
							(mid -0.249642 0.249642)
							(end -0.2794 0.1778)
						)
						(arc
							(start -0.2794 -0.1778)
							(mid -0.249642 -0.249642)
							(end -0.1778 -0.2794)
						)
						(arc
							(start 0.1778 -0.2794)
							(mid 0.249642 -0.249642)
							(end 0.2794 -0.1778)
						)
						(arc
							(start 0.2794 0.1778)
							(mid 0.249642 0.249642)
							(end 0.1778 0.2794)
						)
					)
					(width 0)
					(fill yes)
				)
			)
		)
	)
	(footprint ""
		(layer "B.Cu")
		(at 206.7814 -56.9468 180)
		(property "Reference" "R593"
			(at 0 0 0)
			(layer "B.SilkS")
			(hide yes)
			(effects
				(font
					(size 1.27 1.27)
				)
				(justify mirror)
			)
		)
		(property "Value" "2K2R2F-GP"
			(at -0.064008 -3.993896 180)
			(unlocked yes)
			(layer "B.Fab")
			(hide yes)
			(effects
				(font
					(size 1.016 1.016)
					(thickness 0.1524)
				)
				(justify mirror)
			)
		)
		(property "Device Type" "R402H16"
			(at -0.064008 -5.517896 180)
			(unlocked yes)
			(layer "B.Fab")
			(hide yes)
			(effects
				(font
					(size 1.016 1.016)
					(thickness 0.1524)
				)
				(justify mirror)
			)
		)
		(duplicate_pad_numbers_are_jumpers no)
		(fp_line
			(start 0.508 -0.9398)
			(end 0.508 0.9398)
			(stroke
				(width 0.1524)
				(type default)
			)
			(layer "B.SilkS")
		)
		(fp_line
			(start -0.508 -0.9398)
			(end 0.508 -0.9398)
			(stroke
				(width 0.1524)
				(type default)
			)
			(layer "B.SilkS")
		)
		(fp_rect
			(start 0.508 0.9398)
			(end -0.508 -0.9398)
			(stroke
				(width 0)
				(type default)
			)
			(fill no)
			(layer "B.CrtYd")
		)
		(fp_rect
			(start 0.508 0.9398)
			(end -0.508 -0.9398)
			(stroke
				(width 0)
				(type default)
			)
			(fill no)
			(layer "B.Fab")
		)
		(pad "1" smd custom
			(at 0 -0.4445)
			(size 0.1397 0.1397)
			(layers "B.Cu" "B.Mask" "B.Paste")
			(net "P1V8")
			(options
				(clearance outline)
				(anchor circle)
			)
			(primitives
				(gr_poly
					(pts
						(arc
							(start -0.1778 0.2794)
							(mid -0.249642 0.249642)
							(end -0.2794 0.1778)
						)
						(arc
							(start -0.2794 -0.1778)
							(mid -0.249642 -0.249642)
							(end -0.1778 -0.2794)
						)
						(arc
							(start 0.1778 -0.2794)
							(mid 0.249642 -0.249642)
							(end 0.2794 -0.1778)
						)
						(arc
							(start 0.2794 0.1778)
							(mid 0.249642 0.249642)
							(end 0.1778 0.2794)
						)
					)
					(width 0)
					(fill yes)
				)
			)
		)
		(pad "2" smd custom
			(at 0 0.4445)
			(size 0.1397 0.1397)
			(layers "B.Cu" "B.Mask" "B.Paste")
			(net "SIO_DIN_1")
			(options
				(clearance outline)
				(anchor circle)
			)
			(primitives
				(gr_poly
					(pts
						(arc
							(start -0.1778 0.2794)
							(mid -0.249642 0.249642)
							(end -0.2794 0.1778)
						)
						(arc
							(start -0.2794 -0.1778)
							(mid -0.249642 -0.249642)
							(end -0.1778 -0.2794)
						)
						(arc
							(start 0.1778 -0.2794)
							(mid 0.249642 -0.249642)
							(end 0.2794 -0.1778)
						)
						(arc
							(start 0.2794 0.1778)
							(mid 0.249642 0.249642)
							(end 0.1778 0.2794)
						)
					)
					(width 0)
					(fill yes)
				)
			)
		)
	)
	(footprint ""
		(layer "B.Cu")
		(at 92.8116 -145.8976)
		(property "Reference" "R425"
			(at 0 0 0)
			(layer "B.SilkS")
			(hide yes)
			(effects
				(font
					(size 1.27 1.27)
				)
				(justify mirror)
			)
		)
		(property "Value" "4K7R2F-GP"
			(at -0.064008 -3.993896 0)
			(unlocked yes)
			(layer "B.Fab")
			(hide yes)
			(effects
				(font
					(size 1.016 1.016)
					(thickness 0.1524)
				)
				(justify mirror)
			)
		)
		(property "Device Type" "R402H16"
			(at -0.064008 -5.517896 0)
			(unlocked yes)
			(layer "B.Fab")
			(hide yes)
			(effects
				(font
					(size 1.016 1.016)
					(thickness 0.1524)
				)
				(justify mirror)
			)
		)
		(duplicate_pad_numbers_are_jumpers no)
		(fp_line
			(start -0.508 -0.9398)
			(end 0.508 -0.9398)
			(stroke
				(width 0.1524)
				(type default)
			)
			(layer "B.SilkS")
		)
		(fp_line
			(start 0.508 -0.9398)
			(end 0.508 0.9398)
			(stroke
				(width 0.1524)
				(type default)
			)
			(layer "B.SilkS")
		)
		(fp_rect
			(start 0.508 0.9398)
			(end -0.508 -0.9398)
			(stroke
				(width 0)
				(type default)
			)
			(fill no)
			(layer "B.CrtYd")
		)
		(fp_rect
			(start 0.508 0.9398)
			(end -0.508 -0.9398)
			(stroke
				(width 0)
				(type default)
			)
			(fill no)
			(layer "B.Fab")
		)
		(pad "1" smd custom
			(at 0 -0.4445 180)
			(size 0.1397 0.1397)
			(layers "B.Cu" "B.Mask" "B.Paste")
			(net "P3V3_STBY")
			(options
				(clearance outline)
				(anchor circle)
			)
			(primitives
				(gr_poly
					(pts
						(arc
							(start -0.1778 0.2794)
							(mid -0.249642 0.249642)
							(end -0.2794 0.1778)
						)
						(arc
							(start -0.2794 -0.1778)
							(mid -0.249642 -0.249642)
							(end -0.1778 -0.2794)
						)
						(arc
							(start 0.1778 -0.2794)
							(mid 0.249642 -0.249642)
							(end 0.2794 -0.1778)
						)
						(arc
							(start 0.2794 0.1778)
							(mid 0.249642 0.249642)
							(end 0.1778 0.2794)
						)
					)
					(width 0)
					(fill yes)
				)
			)
		)
		(pad "2" smd custom
			(at 0 0.4445 180)
			(size 0.1397 0.1397)
			(layers "B.Cu" "B.Mask" "B.Paste")
			(net "TCA9555_A2")
			(options
				(clearance outline)
				(anchor circle)
			)
			(primitives
				(gr_poly
					(pts
						(arc
							(start -0.1778 0.2794)
							(mid -0.249642 0.249642)
							(end -0.2794 0.1778)
						)
						(arc
							(start -0.2794 -0.1778)
							(mid -0.249642 -0.249642)
							(end -0.1778 -0.2794)
						)
						(arc
							(start 0.1778 -0.2794)
							(mid 0.249642 -0.249642)
							(end 0.2794 -0.1778)
						)
						(arc
							(start 0.2794 0.1778)
							(mid 0.249642 0.249642)
							(end 0.1778 0.2794)
						)
					)
					(width 0)
					(fill yes)
				)
			)
		)
	)
	(footprint ""
		(layer "B.Cu")
		(at 187.9854 -55.5752 90)
		(property "Reference" "C432"
			(at 0 0 90)
			(layer "B.SilkS")
			(hide yes)
			(effects
				(font
					(size 1.27 1.27)
				)
				(justify mirror)
			)
		)
		(property "Value" "SCD1U16V2KX-3GP"
			(at -1.1811 -2.7051 90)
			(unlocked yes)
			(layer "B.Fab")
			(hide yes)
			(effects
				(font
					(size 1.016 1.016)
					(thickness 0.1524)
				)
				(justify mirror)
			)
		)
		(property "Device Type" "C402H22"
			(at -1.1811 -4.2291 90)
			(unlocked yes)
			(layer "B.Fab")
			(hide yes)
			(effects
				(font
					(size 1.016 1.016)
					(thickness 0.1524)
				)
				(justify mirror)
			)
		)
		(duplicate_pad_numbers_are_jumpers no)
		(fp_rect
			(start 0.4318 0.9525)
			(end -0.4318 -0.9525)
			(stroke
				(width 0)
				(type default)
			)
			(fill no)
			(layer "B.CrtYd")
		)
		(fp_rect
			(start 0.4318 0.9525)
			(end -0.4318 -0.9525)
			(stroke
				(width 0)
				(type default)
			)
			(fill no)
			(layer "B.Fab")
		)
		(pad "1" smd custom
			(at 0 -0.4445 270)
			(size 0.1524 0.1524)
			(layers "B.Cu" "B.Mask" "B.Paste")
			(net "P1V8")
			(options
				(clearance outline)
				(anchor circle)
			)
			(primitives
				(gr_poly
					(pts
						(arc
							(start 0.3048 0.2032)
							(mid 0.275042 0.275042)
							(end 0.2032 0.3048)
						)
						(arc
							(start -0.2032 0.3048)
							(mid -0.275042 0.275042)
							(end -0.3048 0.2032)
						)
						(arc
							(start -0.3048 -0.2032)
							(mid -0.275042 -0.275042)
							(end -0.2032 -0.3048)
						)
						(arc
							(start 0.2032 -0.3048)
							(mid 0.275042 -0.275042)
							(end 0.3048 -0.2032)
						)
					)
					(width 0)
					(fill yes)
				)
			)
		)
		(pad "2" smd custom
			(at 0 0.4445 270)
			(size 0.1524 0.1524)
			(layers "B.Cu" "B.Mask" "B.Paste")
			(net "GND")
			(options
				(clearance outline)
				(anchor circle)
			)
			(primitives
				(gr_poly
					(pts
						(arc
							(start 0.3048 0.2032)
							(mid 0.275042 0.275042)
							(end 0.2032 0.3048)
						)
						(arc
							(start -0.2032 0.3048)
							(mid -0.275042 0.275042)
							(end -0.3048 0.2032)
						)
						(arc
							(start -0.3048 -0.2032)
							(mid -0.275042 -0.275042)
							(end -0.2032 -0.3048)
						)
						(arc
							(start 0.2032 -0.3048)
							(mid 0.275042 -0.275042)
							(end 0.3048 -0.2032)
						)
					)
					(width 0)
					(fill yes)
				)
			)
		)
	)
	(footprint ""
		(layer "B.Cu")
		(at 37.1602 -126.4412)
		(property "Reference" "R276"
			(at 0 0 0)
			(layer "B.SilkS")
			(hide yes)
			(effects
				(font
					(size 1.27 1.27)
				)
				(justify mirror)
			)
		)
		(property "Value" "4K7R2F-GP"
			(at -0.064008 -3.993896 0)
			(unlocked yes)
			(layer "B.Fab")
			(hide yes)
			(effects
				(font
					(size 1.016 1.016)
					(thickness 0.1524)
				)
				(justify mirror)
			)
		)
		(property "Device Type" "R402H16"
			(at -0.064008 -5.517896 0)
			(unlocked yes)
			(layer "B.Fab")
			(hide yes)
			(effects
				(font
					(size 1.016 1.016)
					(thickness 0.1524)
				)
				(justify mirror)
			)
		)
		(duplicate_pad_numbers_are_jumpers no)
		(fp_line
			(start -0.508 -0.9398)
			(end 0.508 -0.9398)
			(stroke
				(width 0.1524)
				(type default)
			)
			(layer "B.SilkS")
		)
		(fp_line
			(start 0.508 -0.9398)
			(end 0.508 0.9398)
			(stroke
				(width 0.1524)
				(type default)
			)
			(layer "B.SilkS")
		)
		(fp_rect
			(start 0.508 0.9398)
			(end -0.508 -0.9398)
			(stroke
				(width 0)
				(type default)
			)
			(fill no)
			(layer "B.CrtYd")
		)
		(fp_rect
			(start 0.508 0.9398)
			(end -0.508 -0.9398)
			(stroke
				(width 0)
				(type default)
			)
			(fill no)
			(layer "B.Fab")
		)
		(pad "1" smd custom
			(at 0 -0.4445 180)
			(size 0.1397 0.1397)
			(layers "B.Cu" "B.Mask" "B.Paste")
			(net "P3V3_STBY")
			(options
				(clearance outline)
				(anchor circle)
			)
			(primitives
				(gr_poly
					(pts
						(arc
							(start -0.1778 0.2794)
							(mid -0.249642 0.249642)
							(end -0.2794 0.1778)
						)
						(arc
							(start -0.2794 -0.1778)
							(mid -0.249642 -0.249642)
							(end -0.1778 -0.2794)
						)
						(arc
							(start 0.1778 -0.2794)
							(mid 0.249642 -0.249642)
							(end 0.2794 -0.1778)
						)
						(arc
							(start 0.2794 0.1778)
							(mid 0.249642 0.249642)
							(end 0.1778 0.2794)
						)
					)
					(width 0)
					(fill yes)
				)
			)
		)
		(pad "2" smd custom
			(at 0 0.4445 180)
			(size 0.1397 0.1397)
			(layers "B.Cu" "B.Mask" "B.Paste")
			(net "DEBUG_RST_BTN_N")
			(options
				(clearance outline)
				(anchor circle)
			)
			(primitives
				(gr_poly
					(pts
						(arc
							(start -0.1778 0.2794)
							(mid -0.249642 0.249642)
							(end -0.2794 0.1778)
						)
						(arc
							(start -0.2794 -0.1778)
							(mid -0.249642 -0.249642)
							(end -0.1778 -0.2794)
						)
						(arc
							(start 0.1778 -0.2794)
							(mid 0.249642 -0.249642)
							(end 0.2794 -0.1778)
						)
						(arc
							(start 0.2794 0.1778)
							(mid 0.249642 0.249642)
							(end 0.1778 0.2794)
						)
					)
					(width 0)
					(fill yes)
				)
			)
		)
	)
	(footprint ""
		(layer "B.Cu")
		(at 196.9008 -71.0438)
		(property "Reference" "C364"
			(at 0 0 0)
			(layer "B.SilkS")
			(hide yes)
			(effects
				(font
					(size 1.27 1.27)
				)
				(justify mirror)
			)
		)
		(property "Value" "SC1U6D3V1MX-GP"
			(at -1.9177 2.0193 0)
			(unlocked yes)
			(layer "B.Fab")
			(hide yes)
			(effects
				(font
					(size 1.016 1.016)
					(thickness 0.1524)
				)
				(justify mirror)
			)
		)
		(property "Device Type" "C0201H14"
			(at -1.9177 0.4953 0)
			(unlocked yes)
			(layer "B.Fab")
			(hide yes)
			(effects
				(font
					(size 1.016 1.016)
					(thickness 0.1524)
				)
				(justify mirror)
			)
		)
		(duplicate_pad_numbers_are_jumpers no)
		(fp_rect
			(start 0.1524 0.3048)
			(end -0.1524 -0.3048)
			(stroke
				(width 0)
				(type default)
			)
			(fill no)
			(layer "B.CrtYd")
		)
		(fp_poly
			(pts
				(xy 0.2794 0.6477) (xy 0.2794 -0.6477) (xy -0.2794 -0.6477) (xy -0.2794 -0.1905) (xy -0.1524 -0.1905)
				(xy -0.1524 -0.3048) (xy 0.1524 -0.3048) (xy 0.1524 0.3048) (xy -0.1524 0.3048) (xy -0.1524 -0.1778)
				(xy -0.2794 -0.1778) (xy -0.2794 0.6477)
			)
			(stroke
				(width 0)
				(type default)
			)
			(fill no)
			(layer "B.CrtYd")
		)
		(fp_rect
			(start 0.2794 0.6477)
			(end -0.2794 -0.6477)
			(stroke
				(width 0)
				(type default)
			)
			(fill no)
			(layer "B.Fab")
		)
		(pad "1" smd custom
			(at 0 -0.2794 180)
			(size 0.0762 0.0762)
			(layers "B.Cu" "B.Mask" "B.Paste")
			(net "PCE_AVDD")
			(options
				(clearance outline)
				(anchor circle)
			)
			(primitives
				(gr_poly
					(pts
						(arc
							(start 0.1524 0.127)
							(mid 0.137521 0.162921)
							(end 0.1016 0.1778)
						)
						(arc
							(start -0.1016 0.1778)
							(mid -0.137521 0.162921)
							(end -0.1524 0.127)
						)
						(arc
							(start -0.1524 -0.127)
							(mid -0.137521 -0.162921)
							(end -0.1016 -0.1778)
						)
						(arc
							(start 0.1016 -0.1778)
							(mid 0.137521 -0.162921)
							(end 0.1524 -0.127)
						)
					)
					(width 0)
					(fill yes)
				)
			)
		)
		(pad "2" smd custom
			(at 0 0.2794 180)
			(size 0.0762 0.0762)
			(layers "B.Cu" "B.Mask" "B.Paste")
			(net "GND")
			(options
				(clearance outline)
				(anchor circle)
			)
			(primitives
				(gr_poly
					(pts
						(arc
							(start 0.1524 0.127)
							(mid 0.137521 0.162921)
							(end 0.1016 0.1778)
						)
						(arc
							(start -0.1016 0.1778)
							(mid -0.137521 0.162921)
							(end -0.1524 0.127)
						)
						(arc
							(start -0.1524 -0.127)
							(mid -0.137521 -0.162921)
							(end -0.1016 -0.1778)
						)
						(arc
							(start 0.1016 -0.1778)
							(mid 0.137521 -0.162921)
							(end 0.1524 -0.127)
						)
					)
					(width 0)
					(fill yes)
				)
			)
		)
	)
	(footprint ""
		(layer "B.Cu")
		(at 124.625862 -15.858998)
		(property "Reference" "R445"
			(at 0 0 0)
			(layer "B.SilkS")
			(hide yes)
			(effects
				(font
					(size 1.27 1.27)
				)
				(justify mirror)
			)
		)
		(property "Value" "49K9R2F-L-GP"
			(at -0.064008 -3.993896 0)
			(unlocked yes)
			(layer "B.Fab")
			(hide yes)
			(effects
				(font
					(size 1.016 1.016)
					(thickness 0.1524)
				)
				(justify mirror)
			)
		)
		(property "Device Type" "R402H16"
			(at -0.064008 -5.517896 0)
			(unlocked yes)
			(layer "B.Fab")
			(hide yes)
			(effects
				(font
					(size 1.016 1.016)
					(thickness 0.1524)
				)
				(justify mirror)
			)
		)
		(duplicate_pad_numbers_are_jumpers no)
		(fp_line
			(start -0.508 -0.9398)
			(end 0.508 -0.9398)
			(stroke
				(width 0.1524)
				(type default)
			)
			(layer "B.SilkS")
		)
		(fp_line
			(start 0.508 -0.9398)
			(end 0.508 0.9398)
			(stroke
				(width 0.1524)
				(type default)
			)
			(layer "B.SilkS")
		)
		(fp_rect
			(start 0.508 0.9398)
			(end -0.508 -0.9398)
			(stroke
				(width 0)
				(type default)
			)
			(fill no)
			(layer "B.CrtYd")
		)
		(fp_rect
			(start 0.508 0.9398)
			(end -0.508 -0.9398)
			(stroke
				(width 0)
				(type default)
			)
			(fill no)
			(layer "B.Fab")
		)
		(pad "1" smd custom
			(at 0 -0.4445 180)
			(size 0.1397 0.1397)
			(layers "B.Cu" "B.Mask" "B.Paste")
			(net "P12V_IOM")
			(options
				(clearance outline)
				(anchor circle)
			)
			(primitives
				(gr_poly
					(pts
						(arc
							(start -0.1778 0.2794)
							(mid -0.249642 0.249642)
							(end -0.2794 0.1778)
						)
						(arc
							(start -0.2794 -0.1778)
							(mid -0.249642 -0.249642)
							(end -0.1778 -0.2794)
						)
						(arc
							(start 0.1778 -0.2794)
							(mid 0.249642 -0.249642)
							(end 0.2794 -0.1778)
						)
						(arc
							(start 0.2794 0.1778)
							(mid 0.249642 0.249642)
							(end 0.1778 0.2794)
						)
					)
					(width 0)
					(fill yes)
				)
			)
		)
		(pad "2" smd custom
			(at 0 0.4445 180)
			(size 0.1397 0.1397)
			(layers "B.Cu" "B.Mask" "B.Paste")
			(net "MB0_CM_OV_R")
			(options
				(clearance outline)
				(anchor circle)
			)
			(primitives
				(gr_poly
					(pts
						(arc
							(start -0.1778 0.2794)
							(mid -0.249642 0.249642)
							(end -0.2794 0.1778)
						)
						(arc
							(start -0.2794 -0.1778)
							(mid -0.249642 -0.249642)
							(end -0.1778 -0.2794)
						)
						(arc
							(start 0.1778 -0.2794)
							(mid 0.249642 -0.249642)
							(end 0.2794 -0.1778)
						)
						(arc
							(start 0.2794 0.1778)
							(mid 0.249642 0.249642)
							(end 0.1778 0.2794)
						)
					)
					(width 0)
					(fill yes)
				)
			)
		)
	)
	(footprint ""
		(layer "B.Cu")
		(at 184.6072 -79.530702 -90)
		(property "Reference" "TP99"
			(at 0 0 90)
			(layer "B.SilkS")
			(hide yes)
			(effects
				(font
					(size 1.27 1.27)
				)
				(justify mirror)
			)
		)
		(property "Value" "TPAD28-2-GP"
			(at 0.0127 -1.6637 270)
			(unlocked yes)
			(layer "B.Fab")
			(hide yes)
			(effects
				(font
					(size 1.016 1.016)
					(thickness 0.1524)
				)
				(justify mirror)
			)
		)
		(property "Device Type" "TPAD28"
			(at 0.0127 -3.1877 270)
			(unlocked yes)
			(layer "B.Fab")
			(hide yes)
			(effects
				(font
					(size 1.016 1.016)
					(thickness 0.1524)
				)
				(justify mirror)
			)
		)
		(duplicate_pad_numbers_are_jumpers no)
		(fp_poly
			(pts
				(arc
					(start 0 -0.3556)
					(mid 0 0.3556)
					(end 0 -0.3556)
				)
			)
			(stroke
				(width 0)
				(type default)
			)
			(fill no)
			(layer "B.CrtYd")
		)
		(fp_poly
			(pts
				(arc
					(start 0 -0.6096)
					(mid 0 0.6096)
					(end 0 -0.6096)
				)
			)
			(stroke
				(width 0)
				(type default)
			)
			(fill no)
			(layer "B.Fab")
		)
		(pad "1" smd circle
			(at 0 0 90)
			(size 0.7112 0.7112)
			(layers "B.Cu" "B.Mask" "B.Paste")
			(net "IOC_GPIO_14")
		)
	)
	(footprint ""
		(layer "B.Cu")
		(at 190.6524 -124.6124)
		(property "Reference" "R562"
			(at 0 0 0)
			(layer "B.SilkS")
			(hide yes)
			(effects
				(font
					(size 1.27 1.27)
				)
				(justify mirror)
			)
		)
		(property "Value" "100KR2F-L1-GP"
			(at -0.064008 -3.993896 0)
			(unlocked yes)
			(layer "B.Fab")
			(hide yes)
			(effects
				(font
					(size 1.016 1.016)
					(thickness 0.1524)
				)
				(justify mirror)
			)
		)
		(property "Device Type" "R402H16"
			(at -0.064008 -5.517896 0)
			(unlocked yes)
			(layer "B.Fab")
			(hide yes)
			(effects
				(font
					(size 1.016 1.016)
					(thickness 0.1524)
				)
				(justify mirror)
			)
		)
		(duplicate_pad_numbers_are_jumpers no)
		(fp_line
			(start -0.508 -0.9398)
			(end 0.508 -0.9398)
			(stroke
				(width 0.1524)
				(type default)
			)
			(layer "B.SilkS")
		)
		(fp_line
			(start 0.508 -0.9398)
			(end 0.508 0.9398)
			(stroke
				(width 0.1524)
				(type default)
			)
			(layer "B.SilkS")
		)
		(fp_rect
			(start 0.508 0.9398)
			(end -0.508 -0.9398)
			(stroke
				(width 0)
				(type default)
			)
			(fill no)
			(layer "B.CrtYd")
		)
		(fp_rect
			(start 0.508 0.9398)
			(end -0.508 -0.9398)
			(stroke
				(width 0)
				(type default)
			)
			(fill no)
			(layer "B.Fab")
		)
		(pad "1" smd custom
			(at 0 -0.4445 180)
			(size 0.1397 0.1397)
			(layers "B.Cu" "B.Mask" "B.Paste")
			(net "VT235_VDES")
			(options
				(clearance outline)
				(anchor circle)
			)
			(primitives
				(gr_poly
					(pts
						(arc
							(start -0.1778 0.2794)
							(mid -0.249642 0.249642)
							(end -0.2794 0.1778)
						)
						(arc
							(start -0.2794 -0.1778)
							(mid -0.249642 -0.249642)
							(end -0.1778 -0.2794)
						)
						(arc
							(start 0.1778 -0.2794)
							(mid 0.249642 -0.249642)
							(end 0.2794 -0.1778)
						)
						(arc
							(start 0.2794 0.1778)
							(mid 0.249642 0.249642)
							(end 0.1778 0.2794)
						)
					)
					(width 0)
					(fill yes)
				)
			)
		)
		(pad "2" smd custom
			(at 0 0.4445 180)
			(size 0.1397 0.1397)
			(layers "B.Cu" "B.Mask" "B.Paste")
			(net "AVSO_VREF")
			(options
				(clearance outline)
				(anchor circle)
			)
			(primitives
				(gr_poly
					(pts
						(arc
							(start -0.1778 0.2794)
							(mid -0.249642 0.249642)
							(end -0.2794 0.1778)
						)
						(arc
							(start -0.2794 -0.1778)
							(mid -0.249642 -0.249642)
							(end -0.1778 -0.2794)
						)
						(arc
							(start 0.1778 -0.2794)
							(mid 0.249642 -0.249642)
							(end 0.2794 -0.1778)
						)
						(arc
							(start 0.2794 0.1778)
							(mid 0.249642 0.249642)
							(end 0.1778 0.2794)
						)
					)
					(width 0)
					(fill yes)
				)
			)
		)
	)
	(footprint ""
		(layer "B.Cu")
		(at 55.785258 -142.888208)
		(property "Reference" "TP54"
			(at 0 0 0)
			(layer "B.SilkS")
			(hide yes)
			(effects
				(font
					(size 1.27 1.27)
				)
				(justify mirror)
			)
		)
		(property "Value" "TPAD28-2-GP"
			(at 0.0127 -1.6637 0)
			(unlocked yes)
			(layer "B.Fab")
			(hide yes)
			(effects
				(font
					(size 1.016 1.016)
					(thickness 0.1524)
				)
				(justify mirror)
			)
		)
		(property "Device Type" "TPAD28"
			(at 0.0127 -3.1877 0)
			(unlocked yes)
			(layer "B.Fab")
			(hide yes)
			(effects
				(font
					(size 1.016 1.016)
					(thickness 0.1524)
				)
				(justify mirror)
			)
		)
		(duplicate_pad_numbers_are_jumpers no)
		(fp_poly
			(pts
				(arc
					(start 0.3556 0)
					(mid -0.3556 0)
					(end 0.3556 0)
				)
			)
			(stroke
				(width 0)
				(type default)
			)
			(fill no)
			(layer "B.CrtYd")
		)
		(fp_poly
			(pts
				(arc
					(start 0.6096 0)
					(mid -0.6096 0)
					(end 0.6096 0)
				)
			)
			(stroke
				(width 0)
				(type default)
			)
			(fill no)
			(layer "B.Fab")
		)
		(pad "1" smd circle
			(at 0 0 180)
			(size 0.7112 0.7112)
			(layers "B.Cu" "B.Mask" "B.Paste")
			(net "TP_BMC_GPIOA6")
		)
	)
	(footprint ""
		(layer "B.Cu")
		(at 197.9168 -54.5338 90)
		(property "Reference" "C438"
			(at 0 0 90)
			(layer "B.SilkS")
			(hide yes)
			(effects
				(font
					(size 1.27 1.27)
				)
				(justify mirror)
			)
		)
		(property "Value" "SCD1U16V2KX-3GP"
			(at -1.1811 -2.7051 90)
			(unlocked yes)
			(layer "B.Fab")
			(hide yes)
			(effects
				(font
					(size 1.016 1.016)
					(thickness 0.1524)
				)
				(justify mirror)
			)
		)
		(property "Device Type" "C402H22"
			(at -1.1811 -4.2291 90)
			(unlocked yes)
			(layer "B.Fab")
			(hide yes)
			(effects
				(font
					(size 1.016 1.016)
					(thickness 0.1524)
				)
				(justify mirror)
			)
		)
		(duplicate_pad_numbers_are_jumpers no)
		(fp_rect
			(start 0.4318 0.9525)
			(end -0.4318 -0.9525)
			(stroke
				(width 0)
				(type default)
			)
			(fill no)
			(layer "B.CrtYd")
		)
		(fp_rect
			(start 0.4318 0.9525)
			(end -0.4318 -0.9525)
			(stroke
				(width 0)
				(type default)
			)
			(fill no)
			(layer "B.Fab")
		)
		(pad "1" smd custom
			(at 0 -0.4445 270)
			(size 0.1524 0.1524)
			(layers "B.Cu" "B.Mask" "B.Paste")
			(net "P1V8")
			(options
				(clearance outline)
				(anchor circle)
			)
			(primitives
				(gr_poly
					(pts
						(arc
							(start 0.3048 0.2032)
							(mid 0.275042 0.275042)
							(end 0.2032 0.3048)
						)
						(arc
							(start -0.2032 0.3048)
							(mid -0.275042 0.275042)
							(end -0.3048 0.2032)
						)
						(arc
							(start -0.3048 -0.2032)
							(mid -0.275042 -0.275042)
							(end -0.2032 -0.3048)
						)
						(arc
							(start 0.2032 -0.3048)
							(mid 0.275042 -0.275042)
							(end 0.3048 -0.2032)
						)
					)
					(width 0)
					(fill yes)
				)
			)
		)
		(pad "2" smd custom
			(at 0 0.4445 270)
			(size 0.1524 0.1524)
			(layers "B.Cu" "B.Mask" "B.Paste")
			(net "GND")
			(options
				(clearance outline)
				(anchor circle)
			)
			(primitives
				(gr_poly
					(pts
						(arc
							(start 0.3048 0.2032)
							(mid 0.275042 0.275042)
							(end 0.2032 0.3048)
						)
						(arc
							(start -0.2032 0.3048)
							(mid -0.275042 0.275042)
							(end -0.3048 0.2032)
						)
						(arc
							(start -0.3048 -0.2032)
							(mid -0.275042 -0.275042)
							(end -0.2032 -0.3048)
						)
						(arc
							(start 0.2032 -0.3048)
							(mid 0.275042 -0.275042)
							(end 0.3048 -0.2032)
						)
					)
					(width 0)
					(fill yes)
				)
			)
		)
	)
	(footprint ""
		(layer "B.Cu")
		(at 185.96864 -58.63336 90)
		(property "Reference" "C444"
			(at 0 0 90)
			(layer "B.SilkS")
			(hide yes)
			(effects
				(font
					(size 1.27 1.27)
				)
				(justify mirror)
			)
		)
		(property "Value" "SCD1U16V2KX-3GP"
			(at -1.1811 -2.7051 90)
			(unlocked yes)
			(layer "B.Fab")
			(hide yes)
			(effects
				(font
					(size 1.016 1.016)
					(thickness 0.1524)
				)
				(justify mirror)
			)
		)
		(property "Device Type" "C402H22"
			(at -1.1811 -4.2291 90)
			(unlocked yes)
			(layer "B.Fab")
			(hide yes)
			(effects
				(font
					(size 1.016 1.016)
					(thickness 0.1524)
				)
				(justify mirror)
			)
		)
		(duplicate_pad_numbers_are_jumpers no)
		(fp_rect
			(start 0.4318 0.9525)
			(end -0.4318 -0.9525)
			(stroke
				(width 0)
				(type default)
			)
			(fill no)
			(layer "B.CrtYd")
		)
		(fp_rect
			(start 0.4318 0.9525)
			(end -0.4318 -0.9525)
			(stroke
				(width 0)
				(type default)
			)
			(fill no)
			(layer "B.Fab")
		)
		(pad "1" smd custom
			(at 0 -0.4445 270)
			(size 0.1524 0.1524)
			(layers "B.Cu" "B.Mask" "B.Paste")
			(net "P1V8")
			(options
				(clearance outline)
				(anchor circle)
			)
			(primitives
				(gr_poly
					(pts
						(arc
							(start 0.3048 0.2032)
							(mid 0.275042 0.275042)
							(end 0.2032 0.3048)
						)
						(arc
							(start -0.2032 0.3048)
							(mid -0.275042 0.275042)
							(end -0.3048 0.2032)
						)
						(arc
							(start -0.3048 -0.2032)
							(mid -0.275042 -0.275042)
							(end -0.2032 -0.3048)
						)
						(arc
							(start 0.2032 -0.3048)
							(mid 0.275042 -0.275042)
							(end 0.3048 -0.2032)
						)
					)
					(width 0)
					(fill yes)
				)
			)
		)
		(pad "2" smd custom
			(at 0 0.4445 270)
			(size 0.1524 0.1524)
			(layers "B.Cu" "B.Mask" "B.Paste")
			(net "GND")
			(options
				(clearance outline)
				(anchor circle)
			)
			(primitives
				(gr_poly
					(pts
						(arc
							(start 0.3048 0.2032)
							(mid 0.275042 0.275042)
							(end 0.2032 0.3048)
						)
						(arc
							(start -0.2032 0.3048)
							(mid -0.275042 0.275042)
							(end -0.3048 0.2032)
						)
						(arc
							(start -0.3048 -0.2032)
							(mid -0.275042 -0.275042)
							(end -0.2032 -0.3048)
						)
						(arc
							(start 0.2032 -0.3048)
							(mid 0.275042 -0.275042)
							(end 0.3048 -0.2032)
						)
					)
					(width 0)
					(fill yes)
				)
			)
		)
	)
	(footprint ""
		(layer "B.Cu")
		(at 95.4024 -152.7556 180)
		(property "Reference" "C13"
			(at 0 0 0)
			(layer "B.SilkS")
			(hide yes)
			(effects
				(font
					(size 1.27 1.27)
				)
				(justify mirror)
			)
		)
		(property "Value" "SC1U16V3KX-5GP"
			(at 0 -2.8194 180)
			(unlocked yes)
			(layer "B.Fab")
			(hide yes)
			(effects
				(font
					(size 1.016 1.016)
					(thickness 0.1524)
				)
				(justify mirror)
			)
		)
		(property "Device Type" "C603H36"
			(at 0 -4.3434 180)
			(unlocked yes)
			(layer "B.Fab")
			(hide yes)
			(effects
				(font
					(size 1.016 1.016)
					(thickness 0.1524)
				)
				(justify mirror)
			)
		)
		(duplicate_pad_numbers_are_jumpers no)
		(fp_line
			(start -0.508 0)
			(end 0.508 0)
			(stroke
				(width 0.2032)
				(type default)
			)
			(layer "B.SilkS")
		)
		(fp_rect
			(start 0.5842 1.3335)
			(end -0.5842 -1.3335)
			(stroke
				(width 0)
				(type default)
			)
			(fill no)
			(layer "B.CrtYd")
		)
		(fp_rect
			(start 0.5842 1.3335)
			(end -0.5842 -1.3335)
			(stroke
				(width 0)
				(type default)
			)
			(fill no)
			(layer "B.Fab")
		)
		(pad "1" smd custom
			(at 0 -0.762)
			(size 0.2159 0.2159)
			(layers "B.Cu" "B.Mask" "B.Paste")
			(net "P3V3_STBY")
			(options
				(clearance outline)
				(anchor circle)
			)
			(primitives
				(gr_poly
					(pts
						(arc
							(start -0.3302 0.4318)
							(mid -0.402042 0.402042)
							(end -0.4318 0.3302)
						)
						(arc
							(start -0.4318 -0.3302)
							(mid -0.402042 -0.402042)
							(end -0.3302 -0.4318)
						)
						(arc
							(start 0.3302 -0.4318)
							(mid 0.402042 -0.402042)
							(end 0.4318 -0.3302)
						)
						(arc
							(start 0.4318 0.3302)
							(mid 0.402042 0.402042)
							(end 0.3302 0.4318)
						)
					)
					(width 0)
					(fill yes)
				)
			)
		)
		(pad "2" smd custom
			(at 0 0.762)
			(size 0.2159 0.2159)
			(layers "B.Cu" "B.Mask" "B.Paste")
			(net "GND")
			(options
				(clearance outline)
				(anchor circle)
			)
			(primitives
				(gr_poly
					(pts
						(arc
							(start -0.3302 0.4318)
							(mid -0.402042 0.402042)
							(end -0.4318 0.3302)
						)
						(arc
							(start -0.4318 -0.3302)
							(mid -0.402042 -0.402042)
							(end -0.3302 -0.4318)
						)
						(arc
							(start 0.3302 -0.4318)
							(mid 0.402042 -0.402042)
							(end 0.4318 -0.3302)
						)
						(arc
							(start 0.4318 0.3302)
							(mid 0.402042 0.402042)
							(end 0.3302 0.4318)
						)
					)
					(width 0)
					(fill yes)
				)
			)
		)
	)
	(footprint ""
		(layer "B.Cu")
		(at 129.00533 -14.629638)
		(property "Reference" "C145"
			(at 0 0 0)
			(layer "B.SilkS")
			(hide yes)
			(effects
				(font
					(size 1.27 1.27)
				)
				(justify mirror)
			)
		)
		(property "Value" "SC1U16V3KX-5GP"
			(at 0 -2.8194 0)
			(unlocked yes)
			(layer "B.Fab")
			(hide yes)
			(effects
				(font
					(size 1.016 1.016)
					(thickness 0.1524)
				)
				(justify mirror)
			)
		)
		(property "Device Type" "C603H36"
			(at 0 -4.3434 0)
			(unlocked yes)
			(layer "B.Fab")
			(hide yes)
			(effects
				(font
					(size 1.016 1.016)
					(thickness 0.1524)
				)
				(justify mirror)
			)
		)
		(duplicate_pad_numbers_are_jumpers no)
		(fp_line
			(start -0.508 0)
			(end 0.508 0)
			(stroke
				(width 0.2032)
				(type default)
			)
			(layer "B.SilkS")
		)
		(fp_rect
			(start 0.5842 1.3335)
			(end -0.5842 -1.3335)
			(stroke
				(width 0)
				(type default)
			)
			(fill no)
			(layer "B.CrtYd")
		)
		(fp_rect
			(start 0.5842 1.3335)
			(end -0.5842 -1.3335)
			(stroke
				(width 0)
				(type default)
			)
			(fill no)
			(layer "B.Fab")
		)
		(pad "1" smd custom
			(at 0 -0.762 180)
			(size 0.2159 0.2159)
			(layers "B.Cu" "B.Mask" "B.Paste")
			(net "MB0_CM_UV_R")
			(options
				(clearance outline)
				(anchor circle)
			)
			(primitives
				(gr_poly
					(pts
						(arc
							(start -0.3302 0.4318)
							(mid -0.402042 0.402042)
							(end -0.4318 0.3302)
						)
						(arc
							(start -0.4318 -0.3302)
							(mid -0.402042 -0.402042)
							(end -0.3302 -0.4318)
						)
						(arc
							(start 0.3302 -0.4318)
							(mid 0.402042 -0.402042)
							(end 0.4318 -0.3302)
						)
						(arc
							(start 0.4318 0.3302)
							(mid 0.402042 0.402042)
							(end 0.3302 0.4318)
						)
					)
					(width 0)
					(fill yes)
				)
			)
		)
		(pad "2" smd custom
			(at 0 0.762 180)
			(size 0.2159 0.2159)
			(layers "B.Cu" "B.Mask" "B.Paste")
			(net "AGND_CURRENT_MON")
			(options
				(clearance outline)
				(anchor circle)
			)
			(primitives
				(gr_poly
					(pts
						(arc
							(start -0.3302 0.4318)
							(mid -0.402042 0.402042)
							(end -0.4318 0.3302)
						)
						(arc
							(start -0.4318 -0.3302)
							(mid -0.402042 -0.402042)
							(end -0.3302 -0.4318)
						)
						(arc
							(start 0.3302 -0.4318)
							(mid 0.402042 -0.402042)
							(end 0.4318 -0.3302)
						)
						(arc
							(start 0.4318 0.3302)
							(mid 0.402042 0.402042)
							(end 0.3302 0.4318)
						)
					)
					(width 0)
					(fill yes)
				)
			)
		)
	)
	(footprint ""
		(layer "B.Cu")
		(at 40.4622 -134.112 180)
		(property "Reference" "R375"
			(at 0 0 0)
			(layer "B.SilkS")
			(hide yes)
			(effects
				(font
					(size 1.27 1.27)
				)
				(justify mirror)
			)
		)
		(property "Value" "4K7R2F-GP"
			(at -0.064008 -3.993896 180)
			(unlocked yes)
			(layer "B.Fab")
			(hide yes)
			(effects
				(font
					(size 1.016 1.016)
					(thickness 0.1524)
				)
				(justify mirror)
			)
		)
		(property "Device Type" "R402H16"
			(at -0.064008 -5.517896 180)
			(unlocked yes)
			(layer "B.Fab")
			(hide yes)
			(effects
				(font
					(size 1.016 1.016)
					(thickness 0.1524)
				)
				(justify mirror)
			)
		)
		(duplicate_pad_numbers_are_jumpers no)
		(fp_line
			(start 0.508 -0.9398)
			(end 0.508 0.9398)
			(stroke
				(width 0.1524)
				(type default)
			)
			(layer "B.SilkS")
		)
		(fp_line
			(start -0.508 -0.9398)
			(end 0.508 -0.9398)
			(stroke
				(width 0.1524)
				(type default)
			)
			(layer "B.SilkS")
		)
		(fp_rect
			(start 0.508 0.9398)
			(end -0.508 -0.9398)
			(stroke
				(width 0)
				(type default)
			)
			(fill no)
			(layer "B.CrtYd")
		)
		(fp_rect
			(start 0.508 0.9398)
			(end -0.508 -0.9398)
			(stroke
				(width 0)
				(type default)
			)
			(fill no)
			(layer "B.Fab")
		)
		(pad "1" smd custom
			(at 0 -0.4445)
			(size 0.1397 0.1397)
			(layers "B.Cu" "B.Mask" "B.Paste")
			(net "P3V3_STBY")
			(options
				(clearance outline)
				(anchor circle)
			)
			(primitives
				(gr_poly
					(pts
						(arc
							(start -0.1778 0.2794)
							(mid -0.249642 0.249642)
							(end -0.2794 0.1778)
						)
						(arc
							(start -0.2794 -0.1778)
							(mid -0.249642 -0.249642)
							(end -0.1778 -0.2794)
						)
						(arc
							(start 0.1778 -0.2794)
							(mid 0.249642 -0.249642)
							(end 0.2794 -0.1778)
						)
						(arc
							(start 0.2794 0.1778)
							(mid 0.249642 0.249642)
							(end 0.1778 0.2794)
						)
					)
					(width 0)
					(fill yes)
				)
			)
		)
		(pad "2" smd custom
			(at 0 0.4445)
			(size 0.1397 0.1397)
			(layers "B.Cu" "B.Mask" "B.Paste")
			(net "BMC_GPIOS7")
			(options
				(clearance outline)
				(anchor circle)
			)
			(primitives
				(gr_poly
					(pts
						(arc
							(start -0.1778 0.2794)
							(mid -0.249642 0.249642)
							(end -0.2794 0.1778)
						)
						(arc
							(start -0.2794 -0.1778)
							(mid -0.249642 -0.249642)
							(end -0.1778 -0.2794)
						)
						(arc
							(start 0.1778 -0.2794)
							(mid 0.249642 -0.249642)
							(end 0.2794 -0.1778)
						)
						(arc
							(start 0.2794 0.1778)
							(mid 0.249642 0.249642)
							(end 0.1778 0.2794)
						)
					)
					(width 0)
					(fill yes)
				)
			)
		)
	)
	(footprint ""
		(layer "B.Cu")
		(at 204.411072 -68.748656 -90)
		(property "Reference" "C352"
			(at 0 0 90)
			(layer "B.SilkS")
			(hide yes)
			(effects
				(font
					(size 1.27 1.27)
				)
				(justify mirror)
			)
		)
		(property "Value" "SC1U6D3V1MX-GP"
			(at -1.9177 2.0193 270)
			(unlocked yes)
			(layer "B.Fab")
			(hide yes)
			(effects
				(font
					(size 1.016 1.016)
					(thickness 0.1524)
				)
				(justify mirror)
			)
		)
		(property "Device Type" "C0201H14"
			(at -1.9177 0.4953 270)
			(unlocked yes)
			(layer "B.Fab")
			(hide yes)
			(effects
				(font
					(size 1.016 1.016)
					(thickness 0.1524)
				)
				(justify mirror)
			)
		)
		(duplicate_pad_numbers_are_jumpers no)
		(fp_rect
			(start 0.1524 0.3048)
			(end -0.1524 -0.3048)
			(stroke
				(width 0)
				(type default)
			)
			(fill no)
			(layer "B.CrtYd")
		)
		(fp_poly
			(pts
				(xy 0.2794 0.6477) (xy 0.2794 -0.6477) (xy -0.2794 -0.6477) (xy -0.2794 -0.1905) (xy -0.1524 -0.1905)
				(xy -0.1524 -0.3048) (xy 0.1524 -0.3048) (xy 0.1524 0.3048) (xy -0.1524 0.3048) (xy -0.1524 -0.1778)
				(xy -0.2794 -0.1778) (xy -0.2794 0.6477)
			)
			(stroke
				(width 0)
				(type default)
			)
			(fill no)
			(layer "B.CrtYd")
		)
		(fp_rect
			(start 0.2794 0.6477)
			(end -0.2794 -0.6477)
			(stroke
				(width 0)
				(type default)
			)
			(fill no)
			(layer "B.Fab")
		)
		(pad "1" smd custom
			(at 0 -0.2794 90)
			(size 0.0762 0.0762)
			(layers "B.Cu" "B.Mask" "B.Paste")
			(net "SAS0_VDDH")
			(options
				(clearance outline)
				(anchor circle)
			)
			(primitives
				(gr_poly
					(pts
						(arc
							(start 0.1524 0.127)
							(mid 0.137521 0.162921)
							(end 0.1016 0.1778)
						)
						(arc
							(start -0.1016 0.1778)
							(mid -0.137521 0.162921)
							(end -0.1524 0.127)
						)
						(arc
							(start -0.1524 -0.127)
							(mid -0.137521 -0.162921)
							(end -0.1016 -0.1778)
						)
						(arc
							(start 0.1016 -0.1778)
							(mid 0.137521 -0.162921)
							(end 0.1524 -0.127)
						)
					)
					(width 0)
					(fill yes)
				)
			)
		)
		(pad "2" smd custom
			(at 0 0.2794 90)
			(size 0.0762 0.0762)
			(layers "B.Cu" "B.Mask" "B.Paste")
			(net "GND")
			(options
				(clearance outline)
				(anchor circle)
			)
			(primitives
				(gr_poly
					(pts
						(arc
							(start 0.1524 0.127)
							(mid 0.137521 0.162921)
							(end 0.1016 0.1778)
						)
						(arc
							(start -0.1016 0.1778)
							(mid -0.137521 0.162921)
							(end -0.1524 0.127)
						)
						(arc
							(start -0.1524 -0.127)
							(mid -0.137521 -0.162921)
							(end -0.1016 -0.1778)
						)
						(arc
							(start 0.1016 -0.1778)
							(mid 0.137521 -0.162921)
							(end 0.1524 -0.127)
						)
					)
					(width 0)
					(fill yes)
				)
			)
		)
	)
	(footprint ""
		(layer "B.Cu")
		(at 193.802 -45.9232 90)
		(property "Reference" "R679"
			(at 0 0 90)
			(layer "B.SilkS")
			(hide yes)
			(effects
				(font
					(size 1.27 1.27)
				)
				(justify mirror)
			)
		)
		(property "Value" "10R2F-L-GP"
			(at -0.064008 -3.993896 90)
			(unlocked yes)
			(layer "B.Fab")
			(hide yes)
			(effects
				(font
					(size 1.016 1.016)
					(thickness 0.1524)
				)
				(justify mirror)
			)
		)
		(property "Device Type" "R402H14"
			(at -0.064008 -5.517896 90)
			(unlocked yes)
			(layer "B.Fab")
			(hide yes)
			(effects
				(font
					(size 1.016 1.016)
					(thickness 0.1524)
				)
				(justify mirror)
			)
		)
		(duplicate_pad_numbers_are_jumpers no)
		(fp_line
			(start 0.508 -0.9398)
			(end 0.508 0.9398)
			(stroke
				(width 0.1524)
				(type default)
			)
			(layer "B.SilkS")
		)
		(fp_line
			(start -0.508 -0.9398)
			(end 0.508 -0.9398)
			(stroke
				(width 0.1524)
				(type default)
			)
			(layer "B.SilkS")
		)
		(fp_rect
			(start 0.508 0.9398)
			(end -0.508 -0.9398)
			(stroke
				(width 0)
				(type default)
			)
			(fill no)
			(layer "B.CrtYd")
		)
		(fp_rect
			(start 0.508 0.9398)
			(end -0.508 -0.9398)
			(stroke
				(width 0)
				(type default)
			)
			(fill no)
			(layer "B.Fab")
		)
		(pad "1" smd custom
			(at 0 -0.4445 270)
			(size 0.1397 0.1397)
			(layers "B.Cu" "B.Mask" "B.Paste")
			(net "P1V8")
			(options
				(clearance outline)
				(anchor circle)
			)
			(primitives
				(gr_poly
					(pts
						(arc
							(start -0.1778 0.2794)
							(mid -0.249642 0.249642)
							(end -0.2794 0.1778)
						)
						(arc
							(start -0.2794 -0.1778)
							(mid -0.249642 -0.249642)
							(end -0.1778 -0.2794)
						)
						(arc
							(start 0.1778 -0.2794)
							(mid 0.249642 -0.249642)
							(end 0.2794 -0.1778)
						)
						(arc
							(start 0.2794 0.1778)
							(mid 0.249642 0.249642)
							(end 0.1778 0.2794)
						)
					)
					(width 0)
					(fill yes)
				)
			)
		)
		(pad "2" smd custom
			(at 0 0.4445 270)
			(size 0.1397 0.1397)
			(layers "B.Cu" "B.Mask" "B.Paste")
			(net "HM40ADC_VDDA")
			(options
				(clearance outline)
				(anchor circle)
			)
			(primitives
				(gr_poly
					(pts
						(arc
							(start -0.1778 0.2794)
							(mid -0.249642 0.249642)
							(end -0.2794 0.1778)
						)
						(arc
							(start -0.2794 -0.1778)
							(mid -0.249642 -0.249642)
							(end -0.1778 -0.2794)
						)
						(arc
							(start 0.1778 -0.2794)
							(mid 0.249642 -0.249642)
							(end 0.2794 -0.1778)
						)
						(arc
							(start 0.2794 0.1778)
							(mid 0.249642 0.249642)
							(end 0.1778 0.2794)
						)
					)
					(width 0)
					(fill yes)
				)
			)
		)
	)
	(footprint ""
		(layer "B.Cu")
		(at 39.751254 -142.892018 180)
		(property "Reference" "R145"
			(at 0 0 0)
			(layer "B.SilkS")
			(hide yes)
			(effects
				(font
					(size 1.27 1.27)
				)
				(justify mirror)
			)
		)
		(property "Value" "240R2F-1-GP"
			(at -0.064008 -3.993896 180)
			(unlocked yes)
			(layer "B.Fab")
			(hide yes)
			(effects
				(font
					(size 1.016 1.016)
					(thickness 0.1524)
				)
				(justify mirror)
			)
		)
		(property "Device Type" "R402H16"
			(at -0.064008 -5.517896 180)
			(unlocked yes)
			(layer "B.Fab")
			(hide yes)
			(effects
				(font
					(size 1.016 1.016)
					(thickness 0.1524)
				)
				(justify mirror)
			)
		)
		(duplicate_pad_numbers_are_jumpers no)
		(fp_line
			(start 0.508 -0.9398)
			(end 0.508 0.9398)
			(stroke
				(width 0.1524)
				(type default)
			)
			(layer "B.SilkS")
		)
		(fp_line
			(start -0.508 -0.9398)
			(end 0.508 -0.9398)
			(stroke
				(width 0.1524)
				(type default)
			)
			(layer "B.SilkS")
		)
		(fp_rect
			(start 0.508 0.9398)
			(end -0.508 -0.9398)
			(stroke
				(width 0)
				(type default)
			)
			(fill no)
			(layer "B.CrtYd")
		)
		(fp_rect
			(start 0.508 0.9398)
			(end -0.508 -0.9398)
			(stroke
				(width 0)
				(type default)
			)
			(fill no)
			(layer "B.Fab")
		)
		(pad "1" smd custom
			(at 0 -0.4445)
			(size 0.1397 0.1397)
			(layers "B.Cu" "B.Mask" "B.Paste")
			(net "GND")
			(options
				(clearance outline)
				(anchor circle)
			)
			(primitives
				(gr_poly
					(pts
						(arc
							(start -0.1778 0.2794)
							(mid -0.249642 0.249642)
							(end -0.2794 0.1778)
						)
						(arc
							(start -0.2794 -0.1778)
							(mid -0.249642 -0.249642)
							(end -0.1778 -0.2794)
						)
						(arc
							(start 0.1778 -0.2794)
							(mid 0.249642 -0.249642)
							(end 0.2794 -0.1778)
						)
						(arc
							(start 0.2794 0.1778)
							(mid 0.249642 0.249642)
							(end 0.1778 0.2794)
						)
					)
					(width 0)
					(fill yes)
				)
			)
		)
		(pad "2" smd custom
			(at 0 0.4445)
			(size 0.1397 0.1397)
			(layers "B.Cu" "B.Mask" "B.Paste")
			(net "MIOZ")
			(options
				(clearance outline)
				(anchor circle)
			)
			(primitives
				(gr_poly
					(pts
						(arc
							(start -0.1778 0.2794)
							(mid -0.249642 0.249642)
							(end -0.2794 0.1778)
						)
						(arc
							(start -0.2794 -0.1778)
							(mid -0.249642 -0.249642)
							(end -0.1778 -0.2794)
						)
						(arc
							(start 0.1778 -0.2794)
							(mid 0.249642 -0.249642)
							(end 0.2794 -0.1778)
						)
						(arc
							(start 0.2794 0.1778)
							(mid 0.249642 0.249642)
							(end 0.1778 0.2794)
						)
					)
					(width 0)
					(fill yes)
				)
			)
		)
	)
	(footprint ""
		(layer "B.Cu")
		(at 58.970418 -140.960348)
		(property "Reference" "TP15"
			(at 0 0 0)
			(layer "B.SilkS")
			(hide yes)
			(effects
				(font
					(size 1.27 1.27)
				)
				(justify mirror)
			)
		)
		(property "Value" "TPAD28-2-GP"
			(at 0.0127 -1.6637 0)
			(unlocked yes)
			(layer "B.Fab")
			(hide yes)
			(effects
				(font
					(size 1.016 1.016)
					(thickness 0.1524)
				)
				(justify mirror)
			)
		)
		(property "Device Type" "TPAD28"
			(at 0.0127 -3.1877 0)
			(unlocked yes)
			(layer "B.Fab")
			(hide yes)
			(effects
				(font
					(size 1.016 1.016)
					(thickness 0.1524)
				)
				(justify mirror)
			)
		)
		(duplicate_pad_numbers_are_jumpers no)
		(fp_poly
			(pts
				(arc
					(start 0.3556 0)
					(mid -0.3556 0)
					(end 0.3556 0)
				)
			)
			(stroke
				(width 0)
				(type default)
			)
			(fill no)
			(layer "B.CrtYd")
		)
		(fp_poly
			(pts
				(arc
					(start 0.6096 0)
					(mid -0.6096 0)
					(end 0.6096 0)
				)
			)
			(stroke
				(width 0)
				(type default)
			)
			(fill no)
			(layer "B.Fab")
		)
		(pad "1" smd circle
			(at 0 0 180)
			(size 0.7112 0.7112)
			(layers "B.Cu" "B.Mask" "B.Paste")
			(net "I2C_M2_2_SCL")
		)
	)
	(footprint ""
		(layer "B.Cu")
		(at 189.8904 -55.5752 90)
		(property "Reference" "C433"
			(at 0 0 90)
			(layer "B.SilkS")
			(hide yes)
			(effects
				(font
					(size 1.27 1.27)
				)
				(justify mirror)
			)
		)
		(property "Value" "SCD1U16V2KX-3GP"
			(at -1.1811 -2.7051 90)
			(unlocked yes)
			(layer "B.Fab")
			(hide yes)
			(effects
				(font
					(size 1.016 1.016)
					(thickness 0.1524)
				)
				(justify mirror)
			)
		)
		(property "Device Type" "C402H22"
			(at -1.1811 -4.2291 90)
			(unlocked yes)
			(layer "B.Fab")
			(hide yes)
			(effects
				(font
					(size 1.016 1.016)
					(thickness 0.1524)
				)
				(justify mirror)
			)
		)
		(duplicate_pad_numbers_are_jumpers no)
		(fp_rect
			(start 0.4318 0.9525)
			(end -0.4318 -0.9525)
			(stroke
				(width 0)
				(type default)
			)
			(fill no)
			(layer "B.CrtYd")
		)
		(fp_rect
			(start 0.4318 0.9525)
			(end -0.4318 -0.9525)
			(stroke
				(width 0)
				(type default)
			)
			(fill no)
			(layer "B.Fab")
		)
		(pad "1" smd custom
			(at 0 -0.4445 270)
			(size 0.1524 0.1524)
			(layers "B.Cu" "B.Mask" "B.Paste")
			(net "P1V8")
			(options
				(clearance outline)
				(anchor circle)
			)
			(primitives
				(gr_poly
					(pts
						(arc
							(start 0.3048 0.2032)
							(mid 0.275042 0.275042)
							(end 0.2032 0.3048)
						)
						(arc
							(start -0.2032 0.3048)
							(mid -0.275042 0.275042)
							(end -0.3048 0.2032)
						)
						(arc
							(start -0.3048 -0.2032)
							(mid -0.275042 -0.275042)
							(end -0.2032 -0.3048)
						)
						(arc
							(start 0.2032 -0.3048)
							(mid 0.275042 -0.275042)
							(end 0.3048 -0.2032)
						)
					)
					(width 0)
					(fill yes)
				)
			)
		)
		(pad "2" smd custom
			(at 0 0.4445 270)
			(size 0.1524 0.1524)
			(layers "B.Cu" "B.Mask" "B.Paste")
			(net "GND")
			(options
				(clearance outline)
				(anchor circle)
			)
			(primitives
				(gr_poly
					(pts
						(arc
							(start 0.3048 0.2032)
							(mid 0.275042 0.275042)
							(end 0.2032 0.3048)
						)
						(arc
							(start -0.2032 0.3048)
							(mid -0.275042 0.275042)
							(end -0.3048 0.2032)
						)
						(arc
							(start -0.3048 -0.2032)
							(mid -0.275042 -0.275042)
							(end -0.2032 -0.3048)
						)
						(arc
							(start 0.2032 -0.3048)
							(mid 0.275042 -0.275042)
							(end 0.3048 -0.2032)
						)
					)
					(width 0)
					(fill yes)
				)
			)
		)
	)
	(footprint ""
		(layer "B.Cu")
		(at 205.568804 -92.825824 180)
		(property "Reference" "L19"
			(at 0 0 0)
			(layer "B.SilkS")
			(hide yes)
			(effects
				(font
					(size 1.27 1.27)
				)
				(justify mirror)
			)
		)
		(property "Value" "MPZ2012S601AT-GP"
			(at 0 -4.2418 180)
			(unlocked yes)
			(layer "B.Fab")
			(hide yes)
			(effects
				(font
					(size 1.016 1.016)
					(thickness 0.1524)
				)
				(justify mirror)
			)
		)
		(property "Device Type" "L805H42"
			(at 0 -5.7912 180)
			(unlocked yes)
			(layer "B.Fab")
			(hide yes)
			(effects
				(font
					(size 1.016 1.016)
					(thickness 0.1524)
				)
				(justify mirror)
			)
		)
		(duplicate_pad_numbers_are_jumpers no)
		(fp_line
			(start 0.889 1.7018)
			(end 0.889 -1.7018)
			(stroke
				(width 0.1524)
				(type default)
			)
			(layer "B.SilkS")
		)
		(fp_line
			(start 0.889 -1.7018)
			(end -0.889 -1.7018)
			(stroke
				(width 0.1524)
				(type default)
			)
			(layer "B.SilkS")
		)
		(fp_line
			(start -0.889 1.7018)
			(end 0.889 1.7018)
			(stroke
				(width 0.1524)
				(type default)
			)
			(layer "B.SilkS")
		)
		(fp_line
			(start -0.889 -1.7018)
			(end -0.889 1.7018)
			(stroke
				(width 0.1524)
				(type default)
			)
			(layer "B.SilkS")
		)
		(fp_rect
			(start 0.9652 1.778)
			(end -0.9652 -1.778)
			(stroke
				(width 0)
				(type default)
			)
			(fill no)
			(layer "B.CrtYd")
		)
		(fp_rect
			(start 0.9652 1.778)
			(end -0.9652 -1.778)
			(stroke
				(width 0)
				(type default)
			)
			(fill no)
			(layer "B.Fab")
		)
		(pad "1" smd rect
			(at 0 -0.9652)
			(size 1.397 1.143)
			(layers "B.Cu" "B.Mask" "B.Paste")
			(net "PCE_VDDH")
		)
		(pad "2" smd rect
			(at 0 0.9652)
			(size 1.397 1.143)
			(layers "B.Cu" "B.Mask" "B.Paste")
			(net "P1V5")
		)
	)
	(footprint ""
		(layer "B.Cu")
		(at 186.8424 -124.405136 180)
		(property "Reference" "R560"
			(at 0 0 0)
			(layer "B.SilkS")
			(hide yes)
			(effects
				(font
					(size 1.27 1.27)
				)
				(justify mirror)
			)
		)
		(property "Value" "69K8R2F-GP"
			(at -0.064008 -3.993896 180)
			(unlocked yes)
			(layer "B.Fab")
			(hide yes)
			(effects
				(font
					(size 1.016 1.016)
					(thickness 0.1524)
				)
				(justify mirror)
			)
		)
		(property "Device Type" "R402H16"
			(at -0.064008 -5.517896 180)
			(unlocked yes)
			(layer "B.Fab")
			(hide yes)
			(effects
				(font
					(size 1.016 1.016)
					(thickness 0.1524)
				)
				(justify mirror)
			)
		)
		(duplicate_pad_numbers_are_jumpers no)
		(fp_line
			(start 0.508 -0.9398)
			(end 0.508 0.9398)
			(stroke
				(width 0.1524)
				(type default)
			)
			(layer "B.SilkS")
		)
		(fp_line
			(start -0.508 -0.9398)
			(end 0.508 -0.9398)
			(stroke
				(width 0.1524)
				(type default)
			)
			(layer "B.SilkS")
		)
		(fp_rect
			(start 0.508 0.9398)
			(end -0.508 -0.9398)
			(stroke
				(width 0)
				(type default)
			)
			(fill no)
			(layer "B.CrtYd")
		)
		(fp_rect
			(start 0.508 0.9398)
			(end -0.508 -0.9398)
			(stroke
				(width 0)
				(type default)
			)
			(fill no)
			(layer "B.Fab")
		)
		(pad "1" smd custom
			(at 0 -0.4445)
			(size 0.1397 0.1397)
			(layers "B.Cu" "B.Mask" "B.Paste")
			(net "AGND_P0V975")
			(options
				(clearance outline)
				(anchor circle)
			)
			(primitives
				(gr_poly
					(pts
						(arc
							(start -0.1778 0.2794)
							(mid -0.249642 0.249642)
							(end -0.2794 0.1778)
						)
						(arc
							(start -0.2794 -0.1778)
							(mid -0.249642 -0.249642)
							(end -0.1778 -0.2794)
						)
						(arc
							(start 0.1778 -0.2794)
							(mid 0.249642 -0.249642)
							(end 0.2794 -0.1778)
						)
						(arc
							(start 0.2794 0.1778)
							(mid 0.249642 0.249642)
							(end 0.1778 0.2794)
						)
					)
					(width 0)
					(fill yes)
				)
			)
		)
		(pad "2" smd custom
			(at 0 0.4445)
			(size 0.1397 0.1397)
			(layers "B.Cu" "B.Mask" "B.Paste")
			(net "VT235_IRIP")
			(options
				(clearance outline)
				(anchor circle)
			)
			(primitives
				(gr_poly
					(pts
						(arc
							(start -0.1778 0.2794)
							(mid -0.249642 0.249642)
							(end -0.2794 0.1778)
						)
						(arc
							(start -0.2794 -0.1778)
							(mid -0.249642 -0.249642)
							(end -0.1778 -0.2794)
						)
						(arc
							(start 0.1778 -0.2794)
							(mid 0.249642 -0.249642)
							(end 0.2794 -0.1778)
						)
						(arc
							(start 0.2794 0.1778)
							(mid 0.249642 0.249642)
							(end 0.1778 0.2794)
						)
					)
					(width 0)
					(fill yes)
				)
			)
		)
	)
	(footprint ""
		(layer "B.Cu")
		(at 189.640718 -81.153 180)
		(property "Reference" "C302"
			(at 0 0 0)
			(layer "B.SilkS")
			(hide yes)
			(effects
				(font
					(size 1.27 1.27)
				)
				(justify mirror)
			)
		)
		(property "Value" "SCD22U10V1KX-GP"
			(at 2.8321 -1.7399 180)
			(unlocked yes)
			(layer "B.Fab")
			(hide yes)
			(effects
				(font
					(size 1.016 1.016)
					(thickness 0.1524)
				)
				(justify mirror)
			)
		)
		(property "Device Type" "C0201H13"
			(at 2.8321 -3.2639 180)
			(unlocked yes)
			(layer "B.Fab")
			(hide yes)
			(effects
				(font
					(size 1.016 1.016)
					(thickness 0.1524)
				)
				(justify mirror)
			)
		)
		(duplicate_pad_numbers_are_jumpers no)
		(fp_rect
			(start 0.2794 0.6477)
			(end -0.2794 -0.6477)
			(stroke
				(width 0)
				(type default)
			)
			(fill no)
			(layer "B.CrtYd")
		)
		(fp_rect
			(start 0.2794 0.6477)
			(end -0.2794 -0.6477)
			(stroke
				(width 0)
				(type default)
			)
			(fill no)
			(layer "B.Fab")
		)
		(pad "1" smd custom
			(at 0 -0.2794)
			(size 0.0762 0.0762)
			(layers "B.Cu" "B.Mask" "B.Paste")
			(net "PCIE_IOM_TO_COMP_14_DN_C")
			(options
				(clearance outline)
				(anchor circle)
			)
			(primitives
				(gr_poly
					(pts
						(arc
							(start 0.1524 0.127)
							(mid 0.137521 0.162921)
							(end 0.1016 0.1778)
						)
						(arc
							(start -0.1016 0.1778)
							(mid -0.137521 0.162921)
							(end -0.1524 0.127)
						)
						(arc
							(start -0.1524 -0.127)
							(mid -0.137521 -0.162921)
							(end -0.1016 -0.1778)
						)
						(arc
							(start 0.1016 -0.1778)
							(mid 0.137521 -0.162921)
							(end 0.1524 -0.127)
						)
					)
					(width 0)
					(fill yes)
				)
			)
		)
		(pad "2" smd custom
			(at 0 0.2794)
			(size 0.0762 0.0762)
			(layers "B.Cu" "B.Mask" "B.Paste")
			(net "PCIE_IOM_TO_COMP_14_DN")
			(options
				(clearance outline)
				(anchor circle)
			)
			(primitives
				(gr_poly
					(pts
						(arc
							(start 0.1524 0.127)
							(mid 0.137521 0.162921)
							(end 0.1016 0.1778)
						)
						(arc
							(start -0.1016 0.1778)
							(mid -0.137521 0.162921)
							(end -0.1524 0.127)
						)
						(arc
							(start -0.1524 -0.127)
							(mid -0.137521 -0.162921)
							(end -0.1016 -0.1778)
						)
						(arc
							(start 0.1016 -0.1778)
							(mid 0.137521 -0.162921)
							(end 0.1524 -0.127)
						)
					)
					(width 0)
					(fill yes)
				)
			)
		)
	)
	(footprint ""
		(layer "B.Cu")
		(at 31.1404 -150.7744)
		(property "Reference" "L3"
			(at 0 0 0)
			(layer "B.SilkS")
			(hide yes)
			(effects
				(font
					(size 1.27 1.27)
				)
				(justify mirror)
			)
		)
		(property "Value" "MMZ2012S601ATA1N-GP"
			(at 0 -4.2418 0)
			(unlocked yes)
			(layer "B.Fab")
			(hide yes)
			(effects
				(font
					(size 1.016 1.016)
					(thickness 0.1524)
				)
				(justify mirror)
			)
		)
		(property "Device Type" "L805H42"
			(at 0 -5.7912 0)
			(unlocked yes)
			(layer "B.Fab")
			(hide yes)
			(effects
				(font
					(size 1.016 1.016)
					(thickness 0.1524)
				)
				(justify mirror)
			)
		)
		(duplicate_pad_numbers_are_jumpers no)
		(fp_line
			(start -0.889 -1.7018)
			(end -0.889 1.7018)
			(stroke
				(width 0.1524)
				(type default)
			)
			(layer "B.SilkS")
		)
		(fp_line
			(start -0.889 1.7018)
			(end 0.889 1.7018)
			(stroke
				(width 0.1524)
				(type default)
			)
			(layer "B.SilkS")
		)
		(fp_line
			(start 0.889 -1.7018)
			(end -0.889 -1.7018)
			(stroke
				(width 0.1524)
				(type default)
			)
			(layer "B.SilkS")
		)
		(fp_line
			(start 0.889 1.7018)
			(end 0.889 -1.7018)
			(stroke
				(width 0.1524)
				(type default)
			)
			(layer "B.SilkS")
		)
		(fp_rect
			(start 0.9652 1.778)
			(end -0.9652 -1.778)
			(stroke
				(width 0)
				(type default)
			)
			(fill no)
			(layer "B.CrtYd")
		)
		(fp_rect
			(start 0.9652 1.778)
			(end -0.9652 -1.778)
			(stroke
				(width 0)
				(type default)
			)
			(fill no)
			(layer "B.Fab")
		)
		(pad "1" smd rect
			(at 0 -0.9652 180)
			(size 1.397 1.143)
			(layers "B.Cu" "B.Mask" "B.Paste")
			(net "P3V3_STBY")
		)
		(pad "2" smd rect
			(at 0 0.9652 180)
			(size 1.397 1.143)
			(layers "B.Cu" "B.Mask" "B.Paste")
			(net "MPLLAV33")
		)
	)
	(footprint ""
		(layer "B.Cu")
		(at 192.405 -64.8208 90)
		(property "Reference" "C416"
			(at 0 0 90)
			(layer "B.SilkS")
			(hide yes)
			(effects
				(font
					(size 1.27 1.27)
				)
				(justify mirror)
			)
		)
		(property "Value" "SCD1U6D3V1KX-GP"
			(at 2.8321 -1.7399 90)
			(unlocked yes)
			(layer "B.Fab")
			(hide yes)
			(effects
				(font
					(size 1.016 1.016)
					(thickness 0.1524)
				)
				(justify mirror)
			)
		)
		(property "Device Type" "C0201H13"
			(at 2.8321 -3.2639 90)
			(unlocked yes)
			(layer "B.Fab")
			(hide yes)
			(effects
				(font
					(size 1.016 1.016)
					(thickness 0.1524)
				)
				(justify mirror)
			)
		)
		(duplicate_pad_numbers_are_jumpers no)
		(fp_rect
			(start 0.2794 0.6477)
			(end -0.2794 -0.6477)
			(stroke
				(width 0)
				(type default)
			)
			(fill no)
			(layer "B.CrtYd")
		)
		(fp_rect
			(start 0.2794 0.6477)
			(end -0.2794 -0.6477)
			(stroke
				(width 0)
				(type default)
			)
			(fill no)
			(layer "B.Fab")
		)
		(pad "1" smd custom
			(at 0 -0.2794 270)
			(size 0.0762 0.0762)
			(layers "B.Cu" "B.Mask" "B.Paste")
			(net "P0V975")
			(options
				(clearance outline)
				(anchor circle)
			)
			(primitives
				(gr_poly
					(pts
						(arc
							(start 0.1524 0.127)
							(mid 0.137521 0.162921)
							(end 0.1016 0.1778)
						)
						(arc
							(start -0.1016 0.1778)
							(mid -0.137521 0.162921)
							(end -0.1524 0.127)
						)
						(arc
							(start -0.1524 -0.127)
							(mid -0.137521 -0.162921)
							(end -0.1016 -0.1778)
						)
						(arc
							(start 0.1016 -0.1778)
							(mid 0.137521 -0.162921)
							(end 0.1524 -0.127)
						)
					)
					(width 0)
					(fill yes)
				)
			)
		)
		(pad "2" smd custom
			(at 0 0.2794 270)
			(size 0.0762 0.0762)
			(layers "B.Cu" "B.Mask" "B.Paste")
			(net "GND")
			(options
				(clearance outline)
				(anchor circle)
			)
			(primitives
				(gr_poly
					(pts
						(arc
							(start 0.1524 0.127)
							(mid 0.137521 0.162921)
							(end 0.1016 0.1778)
						)
						(arc
							(start -0.1016 0.1778)
							(mid -0.137521 0.162921)
							(end -0.1524 0.127)
						)
						(arc
							(start -0.1524 -0.127)
							(mid -0.137521 -0.162921)
							(end -0.1016 -0.1778)
						)
						(arc
							(start 0.1016 -0.1778)
							(mid 0.137521 -0.162921)
							(end 0.1524 -0.127)
						)
					)
					(width 0)
					(fill yes)
				)
			)
		)
	)
	(footprint ""
		(layer "B.Cu")
		(at 204.461872 -70.729856 -90)
		(property "Reference" "C353"
			(at 0 0 90)
			(layer "B.SilkS")
			(hide yes)
			(effects
				(font
					(size 1.27 1.27)
				)
				(justify mirror)
			)
		)
		(property "Value" "SCD1U6D3V1KX-GP"
			(at 2.8321 -1.7399 270)
			(unlocked yes)
			(layer "B.Fab")
			(hide yes)
			(effects
				(font
					(size 1.016 1.016)
					(thickness 0.1524)
				)
				(justify mirror)
			)
		)
		(property "Device Type" "C0201H13"
			(at 2.8321 -3.2639 270)
			(unlocked yes)
			(layer "B.Fab")
			(hide yes)
			(effects
				(font
					(size 1.016 1.016)
					(thickness 0.1524)
				)
				(justify mirror)
			)
		)
		(duplicate_pad_numbers_are_jumpers no)
		(fp_rect
			(start 0.2794 0.6477)
			(end -0.2794 -0.6477)
			(stroke
				(width 0)
				(type default)
			)
			(fill no)
			(layer "B.CrtYd")
		)
		(fp_rect
			(start 0.2794 0.6477)
			(end -0.2794 -0.6477)
			(stroke
				(width 0)
				(type default)
			)
			(fill no)
			(layer "B.Fab")
		)
		(pad "1" smd custom
			(at 0 -0.2794 90)
			(size 0.0762 0.0762)
			(layers "B.Cu" "B.Mask" "B.Paste")
			(net "SAS0_VDDH")
			(options
				(clearance outline)
				(anchor circle)
			)
			(primitives
				(gr_poly
					(pts
						(arc
							(start 0.1524 0.127)
							(mid 0.137521 0.162921)
							(end 0.1016 0.1778)
						)
						(arc
							(start -0.1016 0.1778)
							(mid -0.137521 0.162921)
							(end -0.1524 0.127)
						)
						(arc
							(start -0.1524 -0.127)
							(mid -0.137521 -0.162921)
							(end -0.1016 -0.1778)
						)
						(arc
							(start 0.1016 -0.1778)
							(mid 0.137521 -0.162921)
							(end 0.1524 -0.127)
						)
					)
					(width 0)
					(fill yes)
				)
			)
		)
		(pad "2" smd custom
			(at 0 0.2794 90)
			(size 0.0762 0.0762)
			(layers "B.Cu" "B.Mask" "B.Paste")
			(net "GND")
			(options
				(clearance outline)
				(anchor circle)
			)
			(primitives
				(gr_poly
					(pts
						(arc
							(start 0.1524 0.127)
							(mid 0.137521 0.162921)
							(end 0.1016 0.1778)
						)
						(arc
							(start -0.1016 0.1778)
							(mid -0.137521 0.162921)
							(end -0.1524 0.127)
						)
						(arc
							(start -0.1524 -0.127)
							(mid -0.137521 -0.162921)
							(end -0.1016 -0.1778)
						)
						(arc
							(start 0.1016 -0.1778)
							(mid 0.137521 -0.162921)
							(end 0.1524 -0.127)
						)
					)
					(width 0)
					(fill yes)
				)
			)
		)
	)
	(footprint ""
		(layer "B.Cu")
		(at 177.0888 -138.4554 180)
		(property "Reference" "R464"
			(at 0 0 0)
			(layer "B.SilkS")
			(hide yes)
			(effects
				(font
					(size 1.27 1.27)
				)
				(justify mirror)
			)
		)
		(property "Value" "2D2R3-1-U-GP"
			(at 0.0254 -2.5146 180)
			(unlocked yes)
			(layer "B.Fab")
			(hide yes)
			(effects
				(font
					(size 1.016 1.016)
					(thickness 0.1524)
				)
				(justify mirror)
			)
		)
		(property "Device Type" "R603H22"
			(at 0.0254 -4.0386 180)
			(unlocked yes)
			(layer "B.Fab")
			(hide yes)
			(effects
				(font
					(size 1.016 1.016)
					(thickness 0.1524)
				)
				(justify mirror)
			)
		)
		(duplicate_pad_numbers_are_jumpers no)
		(fp_line
			(start 0.4826 0)
			(end 0.2032 0)
			(stroke
				(width 0.2032)
				(type default)
			)
			(layer "B.SilkS")
		)
		(fp_line
			(start -0.2032 0)
			(end -0.4826 0)
			(stroke
				(width 0.2032)
				(type default)
			)
			(layer "B.SilkS")
		)
		(fp_rect
			(start 0.5842 1.3335)
			(end -0.5842 -1.3335)
			(stroke
				(width 0)
				(type default)
			)
			(fill no)
			(layer "B.CrtYd")
		)
		(fp_rect
			(start 0.5842 1.3335)
			(end -0.5842 -1.3335)
			(stroke
				(width 0)
				(type default)
			)
			(fill no)
			(layer "B.Fab")
		)
		(pad "1" smd custom
			(at 0 -0.762)
			(size 0.2159 0.2159)
			(layers "B.Cu" "B.Mask" "B.Paste")
			(net "P12V_STBY")
			(options
				(clearance outline)
				(anchor circle)
			)
			(primitives
				(gr_poly
					(pts
						(arc
							(start -0.3302 0.4318)
							(mid -0.402042 0.402042)
							(end -0.4318 0.3302)
						)
						(arc
							(start -0.4318 -0.3302)
							(mid -0.402042 -0.402042)
							(end -0.3302 -0.4318)
						)
						(arc
							(start 0.3302 -0.4318)
							(mid 0.402042 -0.402042)
							(end 0.4318 -0.3302)
						)
						(arc
							(start 0.4318 0.3302)
							(mid 0.402042 0.402042)
							(end 0.3302 0.4318)
						)
					)
					(width 0)
					(fill yes)
				)
			)
		)
		(pad "2" smd custom
			(at 0 0.762)
			(size 0.2159 0.2159)
			(layers "B.Cu" "B.Mask" "B.Paste")
			(net "P12V_STBY_VDD_PU1")
			(options
				(clearance outline)
				(anchor circle)
			)
			(primitives
				(gr_poly
					(pts
						(arc
							(start -0.3302 0.4318)
							(mid -0.402042 0.402042)
							(end -0.4318 0.3302)
						)
						(arc
							(start -0.4318 -0.3302)
							(mid -0.402042 -0.402042)
							(end -0.3302 -0.4318)
						)
						(arc
							(start 0.3302 -0.4318)
							(mid 0.402042 -0.402042)
							(end 0.4318 -0.3302)
						)
						(arc
							(start 0.4318 0.3302)
							(mid 0.402042 0.402042)
							(end 0.3302 0.4318)
						)
					)
					(width 0)
					(fill yes)
				)
			)
		)
	)
	(footprint ""
		(layer "B.Cu")
		(at 192.786 -54.0766)
		(property "Reference" "C460"
			(at 0 0 0)
			(layer "B.SilkS")
			(hide yes)
			(effects
				(font
					(size 1.27 1.27)
				)
				(justify mirror)
			)
		)
		(property "Value" "SCD1U16V2KX-3GP"
			(at -1.1811 -2.7051 0)
			(unlocked yes)
			(layer "B.Fab")
			(hide yes)
			(effects
				(font
					(size 1.016 1.016)
					(thickness 0.1524)
				)
				(justify mirror)
			)
		)
		(property "Device Type" "C402H22"
			(at -1.1811 -4.2291 0)
			(unlocked yes)
			(layer "B.Fab")
			(hide yes)
			(effects
				(font
					(size 1.016 1.016)
					(thickness 0.1524)
				)
				(justify mirror)
			)
		)
		(duplicate_pad_numbers_are_jumpers no)
		(fp_rect
			(start 0.4318 0.9525)
			(end -0.4318 -0.9525)
			(stroke
				(width 0)
				(type default)
			)
			(fill no)
			(layer "B.CrtYd")
		)
		(fp_rect
			(start 0.4318 0.9525)
			(end -0.4318 -0.9525)
			(stroke
				(width 0)
				(type default)
			)
			(fill no)
			(layer "B.Fab")
		)
		(pad "1" smd custom
			(at 0 -0.4445 180)
			(size 0.1524 0.1524)
			(layers "B.Cu" "B.Mask" "B.Paste")
			(net "P1V8")
			(options
				(clearance outline)
				(anchor circle)
			)
			(primitives
				(gr_poly
					(pts
						(arc
							(start 0.3048 0.2032)
							(mid 0.275042 0.275042)
							(end 0.2032 0.3048)
						)
						(arc
							(start -0.2032 0.3048)
							(mid -0.275042 0.275042)
							(end -0.3048 0.2032)
						)
						(arc
							(start -0.3048 -0.2032)
							(mid -0.275042 -0.275042)
							(end -0.2032 -0.3048)
						)
						(arc
							(start 0.2032 -0.3048)
							(mid 0.275042 -0.275042)
							(end 0.3048 -0.2032)
						)
					)
					(width 0)
					(fill yes)
				)
			)
		)
		(pad "2" smd custom
			(at 0 0.4445 180)
			(size 0.1524 0.1524)
			(layers "B.Cu" "B.Mask" "B.Paste")
			(net "GND")
			(options
				(clearance outline)
				(anchor circle)
			)
			(primitives
				(gr_poly
					(pts
						(arc
							(start 0.3048 0.2032)
							(mid 0.275042 0.275042)
							(end 0.2032 0.3048)
						)
						(arc
							(start -0.2032 0.3048)
							(mid -0.275042 0.275042)
							(end -0.3048 0.2032)
						)
						(arc
							(start -0.3048 -0.2032)
							(mid -0.275042 -0.275042)
							(end -0.2032 -0.3048)
						)
						(arc
							(start 0.2032 -0.3048)
							(mid 0.275042 -0.275042)
							(end 0.3048 -0.2032)
						)
					)
					(width 0)
					(fill yes)
				)
			)
		)
	)
	(footprint ""
		(layer "B.Cu")
		(at 197.2945 -63.9699 90)
		(property "Reference" "C395"
			(at 0 0 90)
			(layer "B.SilkS")
			(hide yes)
			(effects
				(font
					(size 1.27 1.27)
				)
				(justify mirror)
			)
		)
		(property "Value" "SC1U16V2KX-7-GP"
			(at -1.7526 -1.6002 90)
			(unlocked yes)
			(layer "B.Fab")
			(hide yes)
			(effects
				(font
					(size 1.016 1.016)
					(thickness 0.1524)
				)
				(justify mirror)
			)
		)
		(property "Device Type" "C402-TO0D2H24"
			(at -1.7526 -3.1242 90)
			(unlocked yes)
			(layer "B.Fab")
			(hide yes)
			(effects
				(font
					(size 1.016 1.016)
					(thickness 0.1524)
				)
				(justify mirror)
			)
		)
		(duplicate_pad_numbers_are_jumpers no)
		(fp_rect
			(start 0.4826 0.889)
			(end -0.4826 -0.889)
			(stroke
				(width 0)
				(type default)
			)
			(fill no)
			(layer "B.CrtYd")
		)
		(fp_rect
			(start 0.4826 0.889)
			(end -0.4826 -0.889)
			(stroke
				(width 0)
				(type default)
			)
			(fill no)
			(layer "B.Fab")
		)
		(pad "1" smd custom
			(at 0 -0.4572 270)
			(size 0.1524 0.1524)
			(layers "B.Cu" "B.Mask" "B.Paste")
			(net "P0V975")
			(options
				(clearance outline)
				(anchor circle)
			)
			(primitives
				(gr_poly
					(pts
						(arc
							(start -0.254 -0.3048)
							(mid -0.325842 -0.275042)
							(end -0.3556 -0.2032)
						)
						(arc
							(start -0.3556 0.2032)
							(mid -0.325842 0.275042)
							(end -0.254 0.3048)
						)
						(arc
							(start 0.254 0.3048)
							(mid 0.325842 0.275042)
							(end 0.3556 0.2032)
						)
						(arc
							(start 0.3556 -0.2032)
							(mid 0.325842 -0.275042)
							(end 0.254 -0.3048)
						)
					)
					(width 0)
					(fill yes)
				)
			)
		)
		(pad "2" smd custom
			(at 0 0.4572 270)
			(size 0.1524 0.1524)
			(layers "B.Cu" "B.Mask" "B.Paste")
			(net "GND")
			(options
				(clearance outline)
				(anchor circle)
			)
			(primitives
				(gr_poly
					(pts
						(arc
							(start -0.254 -0.3048)
							(mid -0.325842 -0.275042)
							(end -0.3556 -0.2032)
						)
						(arc
							(start -0.3556 0.2032)
							(mid -0.325842 0.275042)
							(end -0.254 0.3048)
						)
						(arc
							(start 0.254 0.3048)
							(mid 0.325842 0.275042)
							(end 0.3556 0.2032)
						)
						(arc
							(start 0.3556 -0.2032)
							(mid 0.325842 -0.275042)
							(end 0.254 -0.3048)
						)
					)
					(width 0)
					(fill yes)
				)
			)
		)
	)
	(footprint ""
		(layer "B.Cu")
		(at 40.69842 -129.57556 -90)
		(property "Reference" "R350"
			(at 0 0 90)
			(layer "B.SilkS")
			(hide yes)
			(effects
				(font
					(size 1.27 1.27)
				)
				(justify mirror)
			)
		)
		(property "Value" "0R2J-2-GP"
			(at -0.064008 -3.993896 270)
			(unlocked yes)
			(layer "B.Fab")
			(hide yes)
			(effects
				(font
					(size 1.016 1.016)
					(thickness 0.1524)
				)
				(justify mirror)
			)
		)
		(property "Device Type" "R402H16"
			(at -0.064008 -5.517896 270)
			(unlocked yes)
			(layer "B.Fab")
			(hide yes)
			(effects
				(font
					(size 1.016 1.016)
					(thickness 0.1524)
				)
				(justify mirror)
			)
		)
		(duplicate_pad_numbers_are_jumpers no)
		(fp_line
			(start -0.508 -0.9398)
			(end 0.508 -0.9398)
			(stroke
				(width 0.1524)
				(type default)
			)
			(layer "B.SilkS")
		)
		(fp_line
			(start 0.508 -0.9398)
			(end 0.508 0.9398)
			(stroke
				(width 0.1524)
				(type default)
			)
			(layer "B.SilkS")
		)
		(fp_rect
			(start 0.508 0.9398)
			(end -0.508 -0.9398)
			(stroke
				(width 0)
				(type default)
			)
			(fill no)
			(layer "B.CrtYd")
		)
		(fp_rect
			(start 0.508 0.9398)
			(end -0.508 -0.9398)
			(stroke
				(width 0)
				(type default)
			)
			(fill no)
			(layer "B.Fab")
		)
		(pad "1" smd custom
			(at 0 -0.4445 90)
			(size 0.1397 0.1397)
			(layers "B.Cu" "B.Mask" "B.Paste")
			(net "FM_TPM_PRSNT_N")
			(options
				(clearance outline)
				(anchor circle)
			)
			(primitives
				(gr_poly
					(pts
						(arc
							(start -0.1778 0.2794)
							(mid -0.249642 0.249642)
							(end -0.2794 0.1778)
						)
						(arc
							(start -0.2794 -0.1778)
							(mid -0.249642 -0.249642)
							(end -0.1778 -0.2794)
						)
						(arc
							(start 0.1778 -0.2794)
							(mid 0.249642 -0.249642)
							(end 0.2794 -0.1778)
						)
						(arc
							(start 0.2794 0.1778)
							(mid 0.249642 0.249642)
							(end 0.1778 0.2794)
						)
					)
					(width 0)
					(fill yes)
				)
			)
		)
		(pad "2" smd custom
			(at 0 0.4445 90)
			(size 0.1397 0.1397)
			(layers "B.Cu" "B.Mask" "B.Paste")
			(net "TPM_PRSNT_N_R")
			(options
				(clearance outline)
				(anchor circle)
			)
			(primitives
				(gr_poly
					(pts
						(arc
							(start -0.1778 0.2794)
							(mid -0.249642 0.249642)
							(end -0.2794 0.1778)
						)
						(arc
							(start -0.2794 -0.1778)
							(mid -0.249642 -0.249642)
							(end -0.1778 -0.2794)
						)
						(arc
							(start 0.1778 -0.2794)
							(mid 0.249642 -0.249642)
							(end 0.2794 -0.1778)
						)
						(arc
							(start 0.2794 0.1778)
							(mid 0.249642 0.249642)
							(end 0.1778 0.2794)
						)
					)
					(width 0)
					(fill yes)
				)
			)
		)
	)
	(footprint ""
		(layer "B.Cu")
		(at 54.3814 -132.6642)
		(property "Reference" "C114"
			(at 0 0 0)
			(layer "B.SilkS")
			(hide yes)
			(effects
				(font
					(size 1.27 1.27)
				)
				(justify mirror)
			)
		)
		(property "Value" "SC1U16V3KX-5GP"
			(at 0 -2.8194 0)
			(unlocked yes)
			(layer "B.Fab")
			(hide yes)
			(effects
				(font
					(size 1.016 1.016)
					(thickness 0.1524)
				)
				(justify mirror)
			)
		)
		(property "Device Type" "C603H36"
			(at 0 -4.3434 0)
			(unlocked yes)
			(layer "B.Fab")
			(hide yes)
			(effects
				(font
					(size 1.016 1.016)
					(thickness 0.1524)
				)
				(justify mirror)
			)
		)
		(duplicate_pad_numbers_are_jumpers no)
		(fp_line
			(start -0.508 0)
			(end 0.508 0)
			(stroke
				(width 0.2032)
				(type default)
			)
			(layer "B.SilkS")
		)
		(fp_rect
			(start 0.5842 1.3335)
			(end -0.5842 -1.3335)
			(stroke
				(width 0)
				(type default)
			)
			(fill no)
			(layer "B.CrtYd")
		)
		(fp_rect
			(start 0.5842 1.3335)
			(end -0.5842 -1.3335)
			(stroke
				(width 0)
				(type default)
			)
			(fill no)
			(layer "B.Fab")
		)
		(pad "1" smd custom
			(at 0 -0.762 180)
			(size 0.2159 0.2159)
			(layers "B.Cu" "B.Mask" "B.Paste")
			(net "P1V15_STBY")
			(options
				(clearance outline)
				(anchor circle)
			)
			(primitives
				(gr_poly
					(pts
						(arc
							(start -0.3302 0.4318)
							(mid -0.402042 0.402042)
							(end -0.4318 0.3302)
						)
						(arc
							(start -0.4318 -0.3302)
							(mid -0.402042 -0.402042)
							(end -0.3302 -0.4318)
						)
						(arc
							(start 0.3302 -0.4318)
							(mid 0.402042 -0.402042)
							(end 0.4318 -0.3302)
						)
						(arc
							(start 0.4318 0.3302)
							(mid 0.402042 0.402042)
							(end 0.3302 0.4318)
						)
					)
					(width 0)
					(fill yes)
				)
			)
		)
		(pad "2" smd custom
			(at 0 0.762 180)
			(size 0.2159 0.2159)
			(layers "B.Cu" "B.Mask" "B.Paste")
			(net "GND")
			(options
				(clearance outline)
				(anchor circle)
			)
			(primitives
				(gr_poly
					(pts
						(arc
							(start -0.3302 0.4318)
							(mid -0.402042 0.402042)
							(end -0.4318 0.3302)
						)
						(arc
							(start -0.4318 -0.3302)
							(mid -0.402042 -0.402042)
							(end -0.3302 -0.4318)
						)
						(arc
							(start 0.3302 -0.4318)
							(mid 0.402042 -0.402042)
							(end 0.4318 -0.3302)
						)
						(arc
							(start 0.4318 0.3302)
							(mid 0.402042 0.402042)
							(end 0.3302 0.4318)
						)
					)
					(width 0)
					(fill yes)
				)
			)
		)
	)
	(footprint ""
		(layer "B.Cu")
		(at 55.6768 -135.8392 180)
		(property "Reference" "R295"
			(at 0 0 0)
			(layer "B.SilkS")
			(hide yes)
			(effects
				(font
					(size 1.27 1.27)
				)
				(justify mirror)
			)
		)
		(property "Value" "0R2J-2-GP"
			(at -0.064008 -3.993896 180)
			(unlocked yes)
			(layer "B.Fab")
			(hide yes)
			(effects
				(font
					(size 1.016 1.016)
					(thickness 0.1524)
				)
				(justify mirror)
			)
		)
		(property "Device Type" "R402H16"
			(at -0.064008 -5.517896 180)
			(unlocked yes)
			(layer "B.Fab")
			(hide yes)
			(effects
				(font
					(size 1.016 1.016)
					(thickness 0.1524)
				)
				(justify mirror)
			)
		)
		(duplicate_pad_numbers_are_jumpers no)
		(fp_line
			(start 0.508 -0.9398)
			(end 0.508 0.9398)
			(stroke
				(width 0.1524)
				(type default)
			)
			(layer "B.SilkS")
		)
		(fp_line
			(start -0.508 -0.9398)
			(end 0.508 -0.9398)
			(stroke
				(width 0.1524)
				(type default)
			)
			(layer "B.SilkS")
		)
		(fp_rect
			(start 0.508 0.9398)
			(end -0.508 -0.9398)
			(stroke
				(width 0)
				(type default)
			)
			(fill no)
			(layer "B.CrtYd")
		)
		(fp_rect
			(start 0.508 0.9398)
			(end -0.508 -0.9398)
			(stroke
				(width 0)
				(type default)
			)
			(fill no)
			(layer "B.Fab")
		)
		(pad "1" smd custom
			(at 0 -0.4445)
			(size 0.1397 0.1397)
			(layers "B.Cu" "B.Mask" "B.Paste")
			(net "SCC_RMT_TYPE_0")
			(options
				(clearance outline)
				(anchor circle)
			)
			(primitives
				(gr_poly
					(pts
						(arc
							(start -0.1778 0.2794)
							(mid -0.249642 0.249642)
							(end -0.2794 0.1778)
						)
						(arc
							(start -0.2794 -0.1778)
							(mid -0.249642 -0.249642)
							(end -0.1778 -0.2794)
						)
						(arc
							(start 0.1778 -0.2794)
							(mid 0.249642 -0.249642)
							(end 0.2794 -0.1778)
						)
						(arc
							(start 0.2794 0.1778)
							(mid 0.249642 0.249642)
							(end 0.1778 0.2794)
						)
					)
					(width 0)
					(fill yes)
				)
			)
		)
		(pad "2" smd custom
			(at 0 0.4445)
			(size 0.1397 0.1397)
			(layers "B.Cu" "B.Mask" "B.Paste")
			(net "SCC_RMT_TYPE_0_R")
			(options
				(clearance outline)
				(anchor circle)
			)
			(primitives
				(gr_poly
					(pts
						(arc
							(start -0.1778 0.2794)
							(mid -0.249642 0.249642)
							(end -0.2794 0.1778)
						)
						(arc
							(start -0.2794 -0.1778)
							(mid -0.249642 -0.249642)
							(end -0.1778 -0.2794)
						)
						(arc
							(start 0.1778 -0.2794)
							(mid 0.249642 -0.249642)
							(end 0.2794 -0.1778)
						)
						(arc
							(start 0.2794 0.1778)
							(mid 0.249642 0.249642)
							(end 0.1778 0.2794)
						)
					)
					(width 0)
					(fill yes)
				)
			)
		)
	)
	(footprint ""
		(layer "B.Cu")
		(at 184.268872 -74.793856 -90)
		(property "Reference" "C470"
			(at 0 0 90)
			(layer "B.SilkS")
			(hide yes)
			(effects
				(font
					(size 1.27 1.27)
				)
				(justify mirror)
			)
		)
		(property "Value" "SCD1U16V2KX-3GP"
			(at -1.1811 -2.7051 270)
			(unlocked yes)
			(layer "B.Fab")
			(hide yes)
			(effects
				(font
					(size 1.016 1.016)
					(thickness 0.1524)
				)
				(justify mirror)
			)
		)
		(property "Device Type" "C402H22"
			(at -1.1811 -4.2291 270)
			(unlocked yes)
			(layer "B.Fab")
			(hide yes)
			(effects
				(font
					(size 1.016 1.016)
					(thickness 0.1524)
				)
				(justify mirror)
			)
		)
		(duplicate_pad_numbers_are_jumpers no)
		(fp_rect
			(start 0.4318 0.9525)
			(end -0.4318 -0.9525)
			(stroke
				(width 0)
				(type default)
			)
			(fill no)
			(layer "B.CrtYd")
		)
		(fp_rect
			(start 0.4318 0.9525)
			(end -0.4318 -0.9525)
			(stroke
				(width 0)
				(type default)
			)
			(fill no)
			(layer "B.Fab")
		)
		(pad "1" smd custom
			(at 0 -0.4445 90)
			(size 0.1524 0.1524)
			(layers "B.Cu" "B.Mask" "B.Paste")
			(net "P1V8")
			(options
				(clearance outline)
				(anchor circle)
			)
			(primitives
				(gr_poly
					(pts
						(arc
							(start 0.3048 0.2032)
							(mid 0.275042 0.275042)
							(end 0.2032 0.3048)
						)
						(arc
							(start -0.2032 0.3048)
							(mid -0.275042 0.275042)
							(end -0.3048 0.2032)
						)
						(arc
							(start -0.3048 -0.2032)
							(mid -0.275042 -0.275042)
							(end -0.2032 -0.3048)
						)
						(arc
							(start 0.2032 -0.3048)
							(mid 0.275042 -0.275042)
							(end 0.3048 -0.2032)
						)
					)
					(width 0)
					(fill yes)
				)
			)
		)
		(pad "2" smd custom
			(at 0 0.4445 90)
			(size 0.1524 0.1524)
			(layers "B.Cu" "B.Mask" "B.Paste")
			(net "GND")
			(options
				(clearance outline)
				(anchor circle)
			)
			(primitives
				(gr_poly
					(pts
						(arc
							(start 0.3048 0.2032)
							(mid 0.275042 0.275042)
							(end 0.2032 0.3048)
						)
						(arc
							(start -0.2032 0.3048)
							(mid -0.275042 0.275042)
							(end -0.3048 0.2032)
						)
						(arc
							(start -0.3048 -0.2032)
							(mid -0.275042 -0.275042)
							(end -0.2032 -0.3048)
						)
						(arc
							(start 0.2032 -0.3048)
							(mid 0.275042 -0.275042)
							(end 0.3048 -0.2032)
						)
					)
					(width 0)
					(fill yes)
				)
			)
		)
	)
	(footprint ""
		(layer "B.Cu")
		(at 193.0146 -124.3584 180)
		(property "Reference" "C286"
			(at 0 0 0)
			(layer "B.SilkS")
			(hide yes)
			(effects
				(font
					(size 1.27 1.27)
				)
				(justify mirror)
			)
		)
		(property "Value" "SCD33U16V3KX-1GP"
			(at 0 -2.8194 180)
			(unlocked yes)
			(layer "B.Fab")
			(hide yes)
			(effects
				(font
					(size 1.016 1.016)
					(thickness 0.1524)
				)
				(justify mirror)
			)
		)
		(property "Device Type" "C603H36"
			(at 0 -4.3434 180)
			(unlocked yes)
			(layer "B.Fab")
			(hide yes)
			(effects
				(font
					(size 1.016 1.016)
					(thickness 0.1524)
				)
				(justify mirror)
			)
		)
		(duplicate_pad_numbers_are_jumpers no)
		(fp_line
			(start -0.508 0)
			(end 0.508 0)
			(stroke
				(width 0.2032)
				(type default)
			)
			(layer "B.SilkS")
		)
		(fp_rect
			(start 0.5842 1.3335)
			(end -0.5842 -1.3335)
			(stroke
				(width 0)
				(type default)
			)
			(fill no)
			(layer "B.CrtYd")
		)
		(fp_rect
			(start 0.5842 1.3335)
			(end -0.5842 -1.3335)
			(stroke
				(width 0)
				(type default)
			)
			(fill no)
			(layer "B.Fab")
		)
		(pad "1" smd custom
			(at 0 -0.762)
			(size 0.2159 0.2159)
			(layers "B.Cu" "B.Mask" "B.Paste")
			(net "AVSO_VREF")
			(options
				(clearance outline)
				(anchor circle)
			)
			(primitives
				(gr_poly
					(pts
						(arc
							(start -0.3302 0.4318)
							(mid -0.402042 0.402042)
							(end -0.4318 0.3302)
						)
						(arc
							(start -0.4318 -0.3302)
							(mid -0.402042 -0.402042)
							(end -0.3302 -0.4318)
						)
						(arc
							(start 0.3302 -0.4318)
							(mid 0.402042 -0.402042)
							(end 0.4318 -0.3302)
						)
						(arc
							(start 0.4318 0.3302)
							(mid 0.402042 0.402042)
							(end 0.3302 0.4318)
						)
					)
					(width 0)
					(fill yes)
				)
			)
		)
		(pad "2" smd custom
			(at 0 0.762)
			(size 0.2159 0.2159)
			(layers "B.Cu" "B.Mask" "B.Paste")
			(net "GND")
			(options
				(clearance outline)
				(anchor circle)
			)
			(primitives
				(gr_poly
					(pts
						(arc
							(start -0.3302 0.4318)
							(mid -0.402042 0.402042)
							(end -0.4318 0.3302)
						)
						(arc
							(start -0.4318 -0.3302)
							(mid -0.402042 -0.402042)
							(end -0.3302 -0.4318)
						)
						(arc
							(start 0.3302 -0.4318)
							(mid 0.402042 -0.402042)
							(end 0.4318 -0.3302)
						)
						(arc
							(start 0.4318 0.3302)
							(mid 0.402042 0.402042)
							(end 0.3302 0.4318)
						)
					)
					(width 0)
					(fill yes)
				)
			)
		)
	)
	(footprint ""
		(layer "B.Cu")
		(at 157.099 -122.174 -90)
		(property "Reference" "C216"
			(at 0 0 90)
			(layer "B.SilkS")
			(hide yes)
			(effects
				(font
					(size 1.27 1.27)
				)
				(justify mirror)
			)
		)
		(property "Value" "SC10U6D3V5KX-4GP"
			(at 0.0762 -6.1214 270)
			(unlocked yes)
			(layer "B.Fab")
			(hide yes)
			(effects
				(font
					(size 1.016 1.016)
					(thickness 0.1524)
				)
				(justify mirror)
			)
		)
		(property "Device Type" "C805H58"
			(at 0.0762 -8.1534 270)
			(unlocked yes)
			(layer "B.Fab")
			(hide yes)
			(effects
				(font
					(size 1.016 1.016)
					(thickness 0.1524)
				)
				(justify mirror)
			)
		)
		(duplicate_pad_numbers_are_jumpers no)
		(fp_line
			(start -0.635 0)
			(end 0.635 0)
			(stroke
				(width 0.508)
				(type default)
			)
			(layer "B.SilkS")
		)
		(fp_rect
			(start 0.9652 1.778)
			(end -0.9652 -1.778)
			(stroke
				(width 0)
				(type default)
			)
			(fill no)
			(layer "B.CrtYd")
		)
		(fp_poly
			(pts
				(xy 0.9652 -1.778) (xy -0.9652 -1.778) (xy -0.9652 1.778) (xy 0.9652 1.778)
			)
			(stroke
				(width 0)
				(type default)
			)
			(fill no)
			(layer "B.Fab")
		)
		(pad "1" smd rect
			(at 0 -0.9652 90)
			(size 1.397 1.143)
			(layers "B.Cu" "B.Mask" "B.Paste")
			(net "P1V8_STBY")
		)
		(pad "2" smd rect
			(at 0 0.9652 90)
			(size 1.397 1.143)
			(layers "B.Cu" "B.Mask" "B.Paste")
			(net "GND")
		)
	)
	(footprint ""
		(layer "B.Cu")
		(at 41.3258 -131.7752 180)
		(property "Reference" "R370"
			(at 0 0 0)
			(layer "B.SilkS")
			(hide yes)
			(effects
				(font
					(size 1.27 1.27)
				)
				(justify mirror)
			)
		)
		(property "Value" "4K7R2F-GP"
			(at -0.064008 -3.993896 180)
			(unlocked yes)
			(layer "B.Fab")
			(hide yes)
			(effects
				(font
					(size 1.016 1.016)
					(thickness 0.1524)
				)
				(justify mirror)
			)
		)
		(property "Device Type" "R402H16"
			(at -0.064008 -5.517896 180)
			(unlocked yes)
			(layer "B.Fab")
			(hide yes)
			(effects
				(font
					(size 1.016 1.016)
					(thickness 0.1524)
				)
				(justify mirror)
			)
		)
		(duplicate_pad_numbers_are_jumpers no)
		(fp_line
			(start 0.508 -0.9398)
			(end 0.508 0.9398)
			(stroke
				(width 0.1524)
				(type default)
			)
			(layer "B.SilkS")
		)
		(fp_line
			(start -0.508 -0.9398)
			(end 0.508 -0.9398)
			(stroke
				(width 0.1524)
				(type default)
			)
			(layer "B.SilkS")
		)
		(fp_rect
			(start 0.508 0.9398)
			(end -0.508 -0.9398)
			(stroke
				(width 0)
				(type default)
			)
			(fill no)
			(layer "B.CrtYd")
		)
		(fp_rect
			(start 0.508 0.9398)
			(end -0.508 -0.9398)
			(stroke
				(width 0)
				(type default)
			)
			(fill no)
			(layer "B.Fab")
		)
		(pad "1" smd custom
			(at 0 -0.4445)
			(size 0.1397 0.1397)
			(layers "B.Cu" "B.Mask" "B.Paste")
			(net "P3V3_STBY")
			(options
				(clearance outline)
				(anchor circle)
			)
			(primitives
				(gr_poly
					(pts
						(arc
							(start -0.1778 0.2794)
							(mid -0.249642 0.249642)
							(end -0.2794 0.1778)
						)
						(arc
							(start -0.2794 -0.1778)
							(mid -0.249642 -0.249642)
							(end -0.1778 -0.2794)
						)
						(arc
							(start 0.1778 -0.2794)
							(mid 0.249642 -0.249642)
							(end 0.2794 -0.1778)
						)
						(arc
							(start 0.2794 0.1778)
							(mid 0.249642 0.249642)
							(end 0.1778 0.2794)
						)
					)
					(width 0)
					(fill yes)
				)
			)
		)
		(pad "2" smd custom
			(at 0 0.4445)
			(size 0.1397 0.1397)
			(layers "B.Cu" "B.Mask" "B.Paste")
			(net "BMC_SPI_MOSI")
			(options
				(clearance outline)
				(anchor circle)
			)
			(primitives
				(gr_poly
					(pts
						(arc
							(start -0.1778 0.2794)
							(mid -0.249642 0.249642)
							(end -0.2794 0.1778)
						)
						(arc
							(start -0.2794 -0.1778)
							(mid -0.249642 -0.249642)
							(end -0.1778 -0.2794)
						)
						(arc
							(start 0.1778 -0.2794)
							(mid 0.249642 -0.249642)
							(end 0.2794 -0.1778)
						)
						(arc
							(start 0.2794 0.1778)
							(mid 0.249642 0.249642)
							(end 0.1778 0.2794)
						)
					)
					(width 0)
					(fill yes)
				)
			)
		)
	)
	(footprint ""
		(layer "B.Cu")
		(at 25.343104 -142.282164 -90)
		(property "Reference" "R222"
			(at 0 0 90)
			(layer "B.SilkS")
			(hide yes)
			(effects
				(font
					(size 1.27 1.27)
				)
				(justify mirror)
			)
		)
		(property "Value" "120R2F-GP"
			(at -0.064008 -3.993896 270)
			(unlocked yes)
			(layer "B.Fab")
			(hide yes)
			(effects
				(font
					(size 1.016 1.016)
					(thickness 0.1524)
				)
				(justify mirror)
			)
		)
		(property "Device Type" "R402H16"
			(at -0.064008 -5.517896 270)
			(unlocked yes)
			(layer "B.Fab")
			(hide yes)
			(effects
				(font
					(size 1.016 1.016)
					(thickness 0.1524)
				)
				(justify mirror)
			)
		)
		(duplicate_pad_numbers_are_jumpers no)
		(fp_line
			(start -0.508 -0.9398)
			(end 0.508 -0.9398)
			(stroke
				(width 0.1524)
				(type default)
			)
			(layer "B.SilkS")
		)
		(fp_line
			(start 0.508 -0.9398)
			(end 0.508 0.9398)
			(stroke
				(width 0.1524)
				(type default)
			)
			(layer "B.SilkS")
		)
		(fp_rect
			(start 0.508 0.9398)
			(end -0.508 -0.9398)
			(stroke
				(width 0)
				(type default)
			)
			(fill no)
			(layer "B.CrtYd")
		)
		(fp_rect
			(start 0.508 0.9398)
			(end -0.508 -0.9398)
			(stroke
				(width 0)
				(type default)
			)
			(fill no)
			(layer "B.Fab")
		)
		(pad "1" smd custom
			(at 0 -0.4445 90)
			(size 0.1397 0.1397)
			(layers "B.Cu" "B.Mask" "B.Paste")
			(net "GND")
			(options
				(clearance outline)
				(anchor circle)
			)
			(primitives
				(gr_poly
					(pts
						(arc
							(start -0.1778 0.2794)
							(mid -0.249642 0.249642)
							(end -0.2794 0.1778)
						)
						(arc
							(start -0.2794 -0.1778)
							(mid -0.249642 -0.249642)
							(end -0.1778 -0.2794)
						)
						(arc
							(start 0.1778 -0.2794)
							(mid 0.249642 -0.249642)
							(end 0.2794 -0.1778)
						)
						(arc
							(start 0.2794 0.1778)
							(mid 0.249642 0.249642)
							(end 0.1778 0.2794)
						)
					)
					(width 0)
					(fill yes)
				)
			)
		)
		(pad "2" smd custom
			(at 0 0.4445 90)
			(size 0.1397 0.1397)
			(layers "B.Cu" "B.Mask" "B.Paste")
			(net "MEMRASN")
			(options
				(clearance outline)
				(anchor circle)
			)
			(primitives
				(gr_poly
					(pts
						(arc
							(start -0.1778 0.2794)
							(mid -0.249642 0.249642)
							(end -0.2794 0.1778)
						)
						(arc
							(start -0.2794 -0.1778)
							(mid -0.249642 -0.249642)
							(end -0.1778 -0.2794)
						)
						(arc
							(start 0.1778 -0.2794)
							(mid 0.249642 -0.249642)
							(end 0.2794 -0.1778)
						)
						(arc
							(start 0.2794 0.1778)
							(mid 0.249642 0.249642)
							(end 0.1778 0.2794)
						)
					)
					(width 0)
					(fill yes)
				)
			)
		)
	)
	(footprint ""
		(layer "B.Cu")
		(at 207.194404 -92.851224)
		(property "Reference" "R685"
			(at 0 0 0)
			(layer "B.SilkS")
			(hide yes)
			(effects
				(font
					(size 1.27 1.27)
				)
				(justify mirror)
			)
		)
		(property "Value" "10R2F-L-GP"
			(at -0.064008 -3.993896 0)
			(unlocked yes)
			(layer "B.Fab")
			(hide yes)
			(effects
				(font
					(size 1.016 1.016)
					(thickness 0.1524)
				)
				(justify mirror)
			)
		)
		(property "Device Type" "R402H14"
			(at -0.064008 -5.517896 0)
			(unlocked yes)
			(layer "B.Fab")
			(hide yes)
			(effects
				(font
					(size 1.016 1.016)
					(thickness 0.1524)
				)
				(justify mirror)
			)
		)
		(duplicate_pad_numbers_are_jumpers no)
		(fp_line
			(start -0.508 -0.9398)
			(end 0.508 -0.9398)
			(stroke
				(width 0.1524)
				(type default)
			)
			(layer "B.SilkS")
		)
		(fp_line
			(start 0.508 -0.9398)
			(end 0.508 0.9398)
			(stroke
				(width 0.1524)
				(type default)
			)
			(layer "B.SilkS")
		)
		(fp_rect
			(start 0.508 0.9398)
			(end -0.508 -0.9398)
			(stroke
				(width 0)
				(type default)
			)
			(fill no)
			(layer "B.CrtYd")
		)
		(fp_rect
			(start 0.508 0.9398)
			(end -0.508 -0.9398)
			(stroke
				(width 0)
				(type default)
			)
			(fill no)
			(layer "B.Fab")
		)
		(pad "1" smd custom
			(at 0 -0.4445 180)
			(size 0.1397 0.1397)
			(layers "B.Cu" "B.Mask" "B.Paste")
			(net "P1V5")
			(options
				(clearance outline)
				(anchor circle)
			)
			(primitives
				(gr_poly
					(pts
						(arc
							(start -0.1778 0.2794)
							(mid -0.249642 0.249642)
							(end -0.2794 0.1778)
						)
						(arc
							(start -0.2794 -0.1778)
							(mid -0.249642 -0.249642)
							(end -0.1778 -0.2794)
						)
						(arc
							(start 0.1778 -0.2794)
							(mid 0.249642 -0.249642)
							(end 0.2794 -0.1778)
						)
						(arc
							(start 0.2794 0.1778)
							(mid 0.249642 0.249642)
							(end 0.1778 0.2794)
						)
					)
					(width 0)
					(fill yes)
				)
			)
		)
		(pad "2" smd custom
			(at 0 0.4445 180)
			(size 0.1397 0.1397)
			(layers "B.Cu" "B.Mask" "B.Paste")
			(net "PCE_VDDH")
			(options
				(clearance outline)
				(anchor circle)
			)
			(primitives
				(gr_poly
					(pts
						(arc
							(start -0.1778 0.2794)
							(mid -0.249642 0.249642)
							(end -0.2794 0.1778)
						)
						(arc
							(start -0.2794 -0.1778)
							(mid -0.249642 -0.249642)
							(end -0.1778 -0.2794)
						)
						(arc
							(start 0.1778 -0.2794)
							(mid 0.249642 -0.249642)
							(end 0.2794 -0.1778)
						)
						(arc
							(start 0.2794 0.1778)
							(mid 0.249642 0.249642)
							(end 0.1778 0.2794)
						)
					)
					(width 0)
					(fill yes)
				)
			)
		)
	)
	(footprint ""
		(layer "B.Cu")
		(at 168.656 -108.204 -90)
		(property "Reference" "C457"
			(at 0 0 90)
			(layer "B.SilkS")
			(hide yes)
			(effects
				(font
					(size 1.27 1.27)
				)
				(justify mirror)
			)
		)
		(property "Value" "SCD1U16V2KX-3GP"
			(at -1.1811 -2.7051 270)
			(unlocked yes)
			(layer "B.Fab")
			(hide yes)
			(effects
				(font
					(size 1.016 1.016)
					(thickness 0.1524)
				)
				(justify mirror)
			)
		)
		(property "Device Type" "C402H22"
			(at -1.1811 -4.2291 270)
			(unlocked yes)
			(layer "B.Fab")
			(hide yes)
			(effects
				(font
					(size 1.016 1.016)
					(thickness 0.1524)
				)
				(justify mirror)
			)
		)
		(duplicate_pad_numbers_are_jumpers no)
		(fp_rect
			(start 0.4318 0.9525)
			(end -0.4318 -0.9525)
			(stroke
				(width 0)
				(type default)
			)
			(fill no)
			(layer "B.CrtYd")
		)
		(fp_rect
			(start 0.4318 0.9525)
			(end -0.4318 -0.9525)
			(stroke
				(width 0)
				(type default)
			)
			(fill no)
			(layer "B.Fab")
		)
		(pad "1" smd custom
			(at 0 -0.4445 90)
			(size 0.1524 0.1524)
			(layers "B.Cu" "B.Mask" "B.Paste")
			(net "P1V8")
			(options
				(clearance outline)
				(anchor circle)
			)
			(primitives
				(gr_poly
					(pts
						(arc
							(start 0.3048 0.2032)
							(mid 0.275042 0.275042)
							(end 0.2032 0.3048)
						)
						(arc
							(start -0.2032 0.3048)
							(mid -0.275042 0.275042)
							(end -0.3048 0.2032)
						)
						(arc
							(start -0.3048 -0.2032)
							(mid -0.275042 -0.275042)
							(end -0.2032 -0.3048)
						)
						(arc
							(start 0.2032 -0.3048)
							(mid 0.275042 -0.275042)
							(end 0.3048 -0.2032)
						)
					)
					(width 0)
					(fill yes)
				)
			)
		)
		(pad "2" smd custom
			(at 0 0.4445 90)
			(size 0.1524 0.1524)
			(layers "B.Cu" "B.Mask" "B.Paste")
			(net "GND")
			(options
				(clearance outline)
				(anchor circle)
			)
			(primitives
				(gr_poly
					(pts
						(arc
							(start 0.3048 0.2032)
							(mid 0.275042 0.275042)
							(end 0.2032 0.3048)
						)
						(arc
							(start -0.2032 0.3048)
							(mid -0.275042 0.275042)
							(end -0.3048 0.2032)
						)
						(arc
							(start -0.3048 -0.2032)
							(mid -0.275042 -0.275042)
							(end -0.2032 -0.3048)
						)
						(arc
							(start 0.2032 -0.3048)
							(mid 0.275042 -0.275042)
							(end 0.3048 -0.2032)
						)
					)
					(width 0)
					(fill yes)
				)
			)
		)
	)
	(footprint ""
		(layer "B.Cu")
		(at 197.5358 -78.3336 180)
		(property "Reference" "C372"
			(at 0 0 0)
			(layer "B.SilkS")
			(hide yes)
			(effects
				(font
					(size 1.27 1.27)
				)
				(justify mirror)
			)
		)
		(property "Value" "SCD1U6D3V1KX-GP"
			(at 2.8321 -1.7399 180)
			(unlocked yes)
			(layer "B.Fab")
			(hide yes)
			(effects
				(font
					(size 1.016 1.016)
					(thickness 0.1524)
				)
				(justify mirror)
			)
		)
		(property "Device Type" "C0201H13"
			(at 2.8321 -3.2639 180)
			(unlocked yes)
			(layer "B.Fab")
			(hide yes)
			(effects
				(font
					(size 1.016 1.016)
					(thickness 0.1524)
				)
				(justify mirror)
			)
		)
		(duplicate_pad_numbers_are_jumpers no)
		(fp_rect
			(start 0.2794 0.6477)
			(end -0.2794 -0.6477)
			(stroke
				(width 0)
				(type default)
			)
			(fill no)
			(layer "B.CrtYd")
		)
		(fp_rect
			(start 0.2794 0.6477)
			(end -0.2794 -0.6477)
			(stroke
				(width 0)
				(type default)
			)
			(fill no)
			(layer "B.Fab")
		)
		(pad "1" smd custom
			(at 0 -0.2794)
			(size 0.0762 0.0762)
			(layers "B.Cu" "B.Mask" "B.Paste")
			(net "PCE_AVDD")
			(options
				(clearance outline)
				(anchor circle)
			)
			(primitives
				(gr_poly
					(pts
						(arc
							(start 0.1524 0.127)
							(mid 0.137521 0.162921)
							(end 0.1016 0.1778)
						)
						(arc
							(start -0.1016 0.1778)
							(mid -0.137521 0.162921)
							(end -0.1524 0.127)
						)
						(arc
							(start -0.1524 -0.127)
							(mid -0.137521 -0.162921)
							(end -0.1016 -0.1778)
						)
						(arc
							(start 0.1016 -0.1778)
							(mid 0.137521 -0.162921)
							(end 0.1524 -0.127)
						)
					)
					(width 0)
					(fill yes)
				)
			)
		)
		(pad "2" smd custom
			(at 0 0.2794)
			(size 0.0762 0.0762)
			(layers "B.Cu" "B.Mask" "B.Paste")
			(net "GND")
			(options
				(clearance outline)
				(anchor circle)
			)
			(primitives
				(gr_poly
					(pts
						(arc
							(start 0.1524 0.127)
							(mid 0.137521 0.162921)
							(end 0.1016 0.1778)
						)
						(arc
							(start -0.1016 0.1778)
							(mid -0.137521 0.162921)
							(end -0.1524 0.127)
						)
						(arc
							(start -0.1524 -0.127)
							(mid -0.137521 -0.162921)
							(end -0.1016 -0.1778)
						)
						(arc
							(start 0.1016 -0.1778)
							(mid 0.137521 -0.162921)
							(end 0.1524 -0.127)
						)
					)
					(width 0)
					(fill yes)
				)
			)
		)
	)
	(footprint ""
		(layer "B.Cu")
		(at 16.319754 -129.076958 180)
		(property "Reference" "R258"
			(at 0 0 0)
			(layer "B.SilkS")
			(hide yes)
			(effects
				(font
					(size 1.27 1.27)
				)
				(justify mirror)
			)
		)
		(property "Value" "120R2F-GP"
			(at -0.064008 -3.993896 180)
			(unlocked yes)
			(layer "B.Fab")
			(hide yes)
			(effects
				(font
					(size 1.016 1.016)
					(thickness 0.1524)
				)
				(justify mirror)
			)
		)
		(property "Device Type" "R402H16"
			(at -0.064008 -5.517896 180)
			(unlocked yes)
			(layer "B.Fab")
			(hide yes)
			(effects
				(font
					(size 1.016 1.016)
					(thickness 0.1524)
				)
				(justify mirror)
			)
		)
		(duplicate_pad_numbers_are_jumpers no)
		(fp_line
			(start 0.508 -0.9398)
			(end 0.508 0.9398)
			(stroke
				(width 0.1524)
				(type default)
			)
			(layer "B.SilkS")
		)
		(fp_line
			(start -0.508 -0.9398)
			(end 0.508 -0.9398)
			(stroke
				(width 0.1524)
				(type default)
			)
			(layer "B.SilkS")
		)
		(fp_rect
			(start 0.508 0.9398)
			(end -0.508 -0.9398)
			(stroke
				(width 0)
				(type default)
			)
			(fill no)
			(layer "B.CrtYd")
		)
		(fp_rect
			(start 0.508 0.9398)
			(end -0.508 -0.9398)
			(stroke
				(width 0)
				(type default)
			)
			(fill no)
			(layer "B.Fab")
		)
		(pad "1" smd custom
			(at 0 -0.4445)
			(size 0.1397 0.1397)
			(layers "B.Cu" "B.Mask" "B.Paste")
			(net "GND")
			(options
				(clearance outline)
				(anchor circle)
			)
			(primitives
				(gr_poly
					(pts
						(arc
							(start -0.1778 0.2794)
							(mid -0.249642 0.249642)
							(end -0.2794 0.1778)
						)
						(arc
							(start -0.2794 -0.1778)
							(mid -0.249642 -0.249642)
							(end -0.1778 -0.2794)
						)
						(arc
							(start 0.1778 -0.2794)
							(mid 0.249642 -0.249642)
							(end 0.2794 -0.1778)
						)
						(arc
							(start 0.2794 0.1778)
							(mid 0.249642 0.249642)
							(end 0.1778 0.2794)
						)
					)
					(width 0)
					(fill yes)
				)
			)
		)
		(pad "2" smd custom
			(at 0 0.4445)
			(size 0.1397 0.1397)
			(layers "B.Cu" "B.Mask" "B.Paste")
			(net "MEMA_12")
			(options
				(clearance outline)
				(anchor circle)
			)
			(primitives
				(gr_poly
					(pts
						(arc
							(start -0.1778 0.2794)
							(mid -0.249642 0.249642)
							(end -0.2794 0.1778)
						)
						(arc
							(start -0.2794 -0.1778)
							(mid -0.249642 -0.249642)
							(end -0.1778 -0.2794)
						)
						(arc
							(start 0.1778 -0.2794)
							(mid 0.249642 -0.249642)
							(end 0.2794 -0.1778)
						)
						(arc
							(start 0.2794 0.1778)
							(mid 0.249642 0.249642)
							(end 0.1778 0.2794)
						)
					)
					(width 0)
					(fill yes)
				)
			)
		)
	)
	(footprint ""
		(layer "B.Cu")
		(at 34.722308 -124.678694 180)
		(property "Reference" "R716"
			(at 0 0 0)
			(layer "B.SilkS")
			(hide yes)
			(effects
				(font
					(size 1.27 1.27)
				)
				(justify mirror)
			)
		)
		(property "Value" "10KR2F-2-GP"
			(at -0.064008 -3.993896 180)
			(unlocked yes)
			(layer "B.Fab")
			(hide yes)
			(effects
				(font
					(size 1.016 1.016)
					(thickness 0.1524)
				)
				(justify mirror)
			)
		)
		(property "Device Type" "R402H16"
			(at -0.064008 -5.517896 180)
			(unlocked yes)
			(layer "B.Fab")
			(hide yes)
			(effects
				(font
					(size 1.016 1.016)
					(thickness 0.1524)
				)
				(justify mirror)
			)
		)
		(duplicate_pad_numbers_are_jumpers no)
		(fp_line
			(start 0.508 -0.9398)
			(end 0.508 0.9398)
			(stroke
				(width 0.1524)
				(type default)
			)
			(layer "B.SilkS")
		)
		(fp_line
			(start -0.508 -0.9398)
			(end 0.508 -0.9398)
			(stroke
				(width 0.1524)
				(type default)
			)
			(layer "B.SilkS")
		)
		(fp_rect
			(start 0.508 0.9398)
			(end -0.508 -0.9398)
			(stroke
				(width 0)
				(type default)
			)
			(fill no)
			(layer "B.CrtYd")
		)
		(fp_rect
			(start 0.508 0.9398)
			(end -0.508 -0.9398)
			(stroke
				(width 0)
				(type default)
			)
			(fill no)
			(layer "B.Fab")
		)
		(pad "1" smd custom
			(at 0 -0.4445)
			(size 0.1397 0.1397)
			(layers "B.Cu" "B.Mask" "B.Paste")
			(net "SYS_RESET_N_OUT")
			(options
				(clearance outline)
				(anchor circle)
			)
			(primitives
				(gr_poly
					(pts
						(arc
							(start -0.1778 0.2794)
							(mid -0.249642 0.249642)
							(end -0.2794 0.1778)
						)
						(arc
							(start -0.2794 -0.1778)
							(mid -0.249642 -0.249642)
							(end -0.1778 -0.2794)
						)
						(arc
							(start 0.1778 -0.2794)
							(mid 0.249642 -0.249642)
							(end 0.2794 -0.1778)
						)
						(arc
							(start 0.2794 0.1778)
							(mid 0.249642 0.249642)
							(end 0.1778 0.2794)
						)
					)
					(width 0)
					(fill yes)
				)
			)
		)
		(pad "2" smd custom
			(at 0 0.4445)
			(size 0.1397 0.1397)
			(layers "B.Cu" "B.Mask" "B.Paste")
			(net "GND")
			(options
				(clearance outline)
				(anchor circle)
			)
			(primitives
				(gr_poly
					(pts
						(arc
							(start -0.1778 0.2794)
							(mid -0.249642 0.249642)
							(end -0.2794 0.1778)
						)
						(arc
							(start -0.2794 -0.1778)
							(mid -0.249642 -0.249642)
							(end -0.1778 -0.2794)
						)
						(arc
							(start 0.1778 -0.2794)
							(mid 0.249642 -0.249642)
							(end 0.2794 -0.1778)
						)
						(arc
							(start 0.2794 0.1778)
							(mid 0.249642 0.249642)
							(end 0.1778 0.2794)
						)
					)
					(width 0)
					(fill yes)
				)
			)
		)
	)
	(footprint ""
		(layer "B.Cu")
		(at 169.97299 -38.442138)
		(property "Reference" "C497"
			(at 0 0 0)
			(layer "B.SilkS")
			(hide yes)
			(effects
				(font
					(size 1.27 1.27)
				)
				(justify mirror)
			)
		)
		(property "Value" "SCD01U16V1KX-GP"
			(at 2.8321 -1.7399 0)
			(unlocked yes)
			(layer "B.Fab")
			(hide yes)
			(effects
				(font
					(size 1.016 1.016)
					(thickness 0.1524)
				)
				(justify mirror)
			)
		)
		(property "Device Type" "C0201H13"
			(at 2.8321 -3.2639 0)
			(unlocked yes)
			(layer "B.Fab")
			(hide yes)
			(effects
				(font
					(size 1.016 1.016)
					(thickness 0.1524)
				)
				(justify mirror)
			)
		)
		(duplicate_pad_numbers_are_jumpers no)
		(fp_rect
			(start 0.2794 0.6477)
			(end -0.2794 -0.6477)
			(stroke
				(width 0)
				(type default)
			)
			(fill no)
			(layer "B.CrtYd")
		)
		(fp_rect
			(start 0.2794 0.6477)
			(end -0.2794 -0.6477)
			(stroke
				(width 0)
				(type default)
			)
			(fill no)
			(layer "B.Fab")
		)
		(pad "1" smd custom
			(at 0 -0.2794 180)
			(size 0.0762 0.0762)
			(layers "B.Cu" "B.Mask" "B.Paste")
			(net "PHY_CON_B_TO_IOC_0_DN")
			(options
				(clearance outline)
				(anchor circle)
			)
			(primitives
				(gr_poly
					(pts
						(arc
							(start 0.1524 0.127)
							(mid 0.137521 0.162921)
							(end 0.1016 0.1778)
						)
						(arc
							(start -0.1016 0.1778)
							(mid -0.137521 0.162921)
							(end -0.1524 0.127)
						)
						(arc
							(start -0.1524 -0.127)
							(mid -0.137521 -0.162921)
							(end -0.1016 -0.1778)
						)
						(arc
							(start 0.1016 -0.1778)
							(mid 0.137521 -0.162921)
							(end 0.1524 -0.127)
						)
					)
					(width 0)
					(fill yes)
				)
			)
		)
		(pad "2" smd custom
			(at 0 0.2794 180)
			(size 0.0762 0.0762)
			(layers "B.Cu" "B.Mask" "B.Paste")
			(net "PHY_CON_B_TO_IOC_0_DN_C")
			(options
				(clearance outline)
				(anchor circle)
			)
			(primitives
				(gr_poly
					(pts
						(arc
							(start 0.1524 0.127)
							(mid 0.137521 0.162921)
							(end 0.1016 0.1778)
						)
						(arc
							(start -0.1016 0.1778)
							(mid -0.137521 0.162921)
							(end -0.1524 0.127)
						)
						(arc
							(start -0.1524 -0.127)
							(mid -0.137521 -0.162921)
							(end -0.1016 -0.1778)
						)
						(arc
							(start 0.1016 -0.1778)
							(mid 0.137521 -0.162921)
							(end 0.1524 -0.127)
						)
					)
					(width 0)
					(fill yes)
				)
			)
		)
	)
	(footprint ""
		(layer "B.Cu")
		(at 184.115202 -68.250308 90)
		(property "Reference" "C473"
			(at 0 0 90)
			(layer "B.SilkS")
			(hide yes)
			(effects
				(font
					(size 1.27 1.27)
				)
				(justify mirror)
			)
		)
		(property "Value" "SC1KP50V2KX-1GP"
			(at -1.1811 -2.7051 90)
			(unlocked yes)
			(layer "B.Fab")
			(hide yes)
			(effects
				(font
					(size 1.016 1.016)
					(thickness 0.1524)
				)
				(justify mirror)
			)
		)
		(property "Device Type" "C402H22"
			(at -1.1811 -4.2291 90)
			(unlocked yes)
			(layer "B.Fab")
			(hide yes)
			(effects
				(font
					(size 1.016 1.016)
					(thickness 0.1524)
				)
				(justify mirror)
			)
		)
		(duplicate_pad_numbers_are_jumpers no)
		(fp_rect
			(start 0.4318 0.9525)
			(end -0.4318 -0.9525)
			(stroke
				(width 0)
				(type default)
			)
			(fill no)
			(layer "B.CrtYd")
		)
		(fp_rect
			(start 0.4318 0.9525)
			(end -0.4318 -0.9525)
			(stroke
				(width 0)
				(type default)
			)
			(fill no)
			(layer "B.Fab")
		)
		(pad "1" smd custom
			(at 0 -0.4445 270)
			(size 0.1524 0.1524)
			(layers "B.Cu" "B.Mask" "B.Paste")
			(net "P1V8")
			(options
				(clearance outline)
				(anchor circle)
			)
			(primitives
				(gr_poly
					(pts
						(arc
							(start 0.3048 0.2032)
							(mid 0.275042 0.275042)
							(end 0.2032 0.3048)
						)
						(arc
							(start -0.2032 0.3048)
							(mid -0.275042 0.275042)
							(end -0.3048 0.2032)
						)
						(arc
							(start -0.3048 -0.2032)
							(mid -0.275042 -0.275042)
							(end -0.2032 -0.3048)
						)
						(arc
							(start 0.2032 -0.3048)
							(mid 0.275042 -0.275042)
							(end 0.3048 -0.2032)
						)
					)
					(width 0)
					(fill yes)
				)
			)
		)
		(pad "2" smd custom
			(at 0 0.4445 270)
			(size 0.1524 0.1524)
			(layers "B.Cu" "B.Mask" "B.Paste")
			(net "GND")
			(options
				(clearance outline)
				(anchor circle)
			)
			(primitives
				(gr_poly
					(pts
						(arc
							(start 0.3048 0.2032)
							(mid 0.275042 0.275042)
							(end 0.2032 0.3048)
						)
						(arc
							(start -0.2032 0.3048)
							(mid -0.275042 0.275042)
							(end -0.3048 0.2032)
						)
						(arc
							(start -0.3048 -0.2032)
							(mid -0.275042 -0.275042)
							(end -0.2032 -0.3048)
						)
						(arc
							(start 0.2032 -0.3048)
							(mid 0.275042 -0.275042)
							(end 0.3048 -0.2032)
						)
					)
					(width 0)
					(fill yes)
				)
			)
		)
	)
	(footprint ""
		(layer "B.Cu")
		(at 184.6326 -69.9008 90)
		(property "Reference" "C467"
			(at 0 0 90)
			(layer "B.SilkS")
			(hide yes)
			(effects
				(font
					(size 1.27 1.27)
				)
				(justify mirror)
			)
		)
		(property "Value" "SCD1U16V2KX-3GP"
			(at -1.1811 -2.7051 90)
			(unlocked yes)
			(layer "B.Fab")
			(hide yes)
			(effects
				(font
					(size 1.016 1.016)
					(thickness 0.1524)
				)
				(justify mirror)
			)
		)
		(property "Device Type" "C402H22"
			(at -1.1811 -4.2291 90)
			(unlocked yes)
			(layer "B.Fab")
			(hide yes)
			(effects
				(font
					(size 1.016 1.016)
					(thickness 0.1524)
				)
				(justify mirror)
			)
		)
		(duplicate_pad_numbers_are_jumpers no)
		(fp_rect
			(start 0.4318 0.9525)
			(end -0.4318 -0.9525)
			(stroke
				(width 0)
				(type default)
			)
			(fill no)
			(layer "B.CrtYd")
		)
		(fp_rect
			(start 0.4318 0.9525)
			(end -0.4318 -0.9525)
			(stroke
				(width 0)
				(type default)
			)
			(fill no)
			(layer "B.Fab")
		)
		(pad "1" smd custom
			(at 0 -0.4445 270)
			(size 0.1524 0.1524)
			(layers "B.Cu" "B.Mask" "B.Paste")
			(net "P1V8")
			(options
				(clearance outline)
				(anchor circle)
			)
			(primitives
				(gr_poly
					(pts
						(arc
							(start 0.3048 0.2032)
							(mid 0.275042 0.275042)
							(end 0.2032 0.3048)
						)
						(arc
							(start -0.2032 0.3048)
							(mid -0.275042 0.275042)
							(end -0.3048 0.2032)
						)
						(arc
							(start -0.3048 -0.2032)
							(mid -0.275042 -0.275042)
							(end -0.2032 -0.3048)
						)
						(arc
							(start 0.2032 -0.3048)
							(mid 0.275042 -0.275042)
							(end 0.3048 -0.2032)
						)
					)
					(width 0)
					(fill yes)
				)
			)
		)
		(pad "2" smd custom
			(at 0 0.4445 270)
			(size 0.1524 0.1524)
			(layers "B.Cu" "B.Mask" "B.Paste")
			(net "GND")
			(options
				(clearance outline)
				(anchor circle)
			)
			(primitives
				(gr_poly
					(pts
						(arc
							(start 0.3048 0.2032)
							(mid 0.275042 0.275042)
							(end 0.2032 0.3048)
						)
						(arc
							(start -0.2032 0.3048)
							(mid -0.275042 0.275042)
							(end -0.3048 0.2032)
						)
						(arc
							(start -0.3048 -0.2032)
							(mid -0.275042 -0.275042)
							(end -0.2032 -0.3048)
						)
						(arc
							(start 0.2032 -0.3048)
							(mid 0.275042 -0.275042)
							(end 0.3048 -0.2032)
						)
					)
					(width 0)
					(fill yes)
				)
			)
		)
	)
	(footprint ""
		(layer "B.Cu")
		(at 45.5168 -133.7818)
		(property "Reference" "R184"
			(at 0 0 0)
			(layer "B.SilkS")
			(hide yes)
			(effects
				(font
					(size 1.27 1.27)
				)
				(justify mirror)
			)
		)
		(property "Value" "2K2R2F-GP"
			(at -0.064008 -3.993896 0)
			(unlocked yes)
			(layer "B.Fab")
			(hide yes)
			(effects
				(font
					(size 1.016 1.016)
					(thickness 0.1524)
				)
				(justify mirror)
			)
		)
		(property "Device Type" "R402H16"
			(at -0.064008 -5.517896 0)
			(unlocked yes)
			(layer "B.Fab")
			(hide yes)
			(effects
				(font
					(size 1.016 1.016)
					(thickness 0.1524)
				)
				(justify mirror)
			)
		)
		(duplicate_pad_numbers_are_jumpers no)
		(fp_line
			(start -0.508 -0.9398)
			(end 0.508 -0.9398)
			(stroke
				(width 0.1524)
				(type default)
			)
			(layer "B.SilkS")
		)
		(fp_line
			(start 0.508 -0.9398)
			(end 0.508 0.9398)
			(stroke
				(width 0.1524)
				(type default)
			)
			(layer "B.SilkS")
		)
		(fp_rect
			(start 0.508 0.9398)
			(end -0.508 -0.9398)
			(stroke
				(width 0)
				(type default)
			)
			(fill no)
			(layer "B.CrtYd")
		)
		(fp_rect
			(start 0.508 0.9398)
			(end -0.508 -0.9398)
			(stroke
				(width 0)
				(type default)
			)
			(fill no)
			(layer "B.Fab")
		)
		(pad "1" smd custom
			(at 0 -0.4445 180)
			(size 0.1397 0.1397)
			(layers "B.Cu" "B.Mask" "B.Paste")
			(net "I2C_IOM_SDA")
			(options
				(clearance outline)
				(anchor circle)
			)
			(primitives
				(gr_poly
					(pts
						(arc
							(start -0.1778 0.2794)
							(mid -0.249642 0.249642)
							(end -0.2794 0.1778)
						)
						(arc
							(start -0.2794 -0.1778)
							(mid -0.249642 -0.249642)
							(end -0.1778 -0.2794)
						)
						(arc
							(start 0.1778 -0.2794)
							(mid 0.249642 -0.249642)
							(end 0.2794 -0.1778)
						)
						(arc
							(start 0.2794 0.1778)
							(mid 0.249642 0.249642)
							(end 0.1778 0.2794)
						)
					)
					(width 0)
					(fill yes)
				)
			)
		)
		(pad "2" smd custom
			(at 0 0.4445 180)
			(size 0.1397 0.1397)
			(layers "B.Cu" "B.Mask" "B.Paste")
			(net "P3V3_STBY")
			(options
				(clearance outline)
				(anchor circle)
			)
			(primitives
				(gr_poly
					(pts
						(arc
							(start -0.1778 0.2794)
							(mid -0.249642 0.249642)
							(end -0.2794 0.1778)
						)
						(arc
							(start -0.2794 -0.1778)
							(mid -0.249642 -0.249642)
							(end -0.1778 -0.2794)
						)
						(arc
							(start 0.1778 -0.2794)
							(mid 0.249642 -0.249642)
							(end 0.2794 -0.1778)
						)
						(arc
							(start 0.2794 0.1778)
							(mid 0.249642 0.249642)
							(end 0.1778 0.2794)
						)
					)
					(width 0)
					(fill yes)
				)
			)
		)
	)
	(footprint ""
		(layer "B.Cu")
		(at 43.2308 -153.3144 -90)
		(property "Reference" "TP66"
			(at 0 0 90)
			(layer "B.SilkS")
			(hide yes)
			(effects
				(font
					(size 1.27 1.27)
				)
				(justify mirror)
			)
		)
		(property "Value" "TPAD28-2-GP"
			(at 0.0127 -1.6637 270)
			(unlocked yes)
			(layer "B.Fab")
			(hide yes)
			(effects
				(font
					(size 1.016 1.016)
					(thickness 0.1524)
				)
				(justify mirror)
			)
		)
		(property "Device Type" "TPAD28"
			(at 0.0127 -3.1877 270)
			(unlocked yes)
			(layer "B.Fab")
			(hide yes)
			(effects
				(font
					(size 1.016 1.016)
					(thickness 0.1524)
				)
				(justify mirror)
			)
		)
		(duplicate_pad_numbers_are_jumpers no)
		(fp_poly
			(pts
				(arc
					(start 0 -0.3556)
					(mid 0 0.3556)
					(end 0 -0.3556)
				)
			)
			(stroke
				(width 0)
				(type default)
			)
			(fill no)
			(layer "B.CrtYd")
		)
		(fp_poly
			(pts
				(arc
					(start 0 -0.6096)
					(mid 0 0.6096)
					(end 0 -0.6096)
				)
			)
			(stroke
				(width 0)
				(type default)
			)
			(fill no)
			(layer "B.Fab")
		)
		(pad "1" smd circle
			(at 0 0 90)
			(size 0.7112 0.7112)
			(layers "B.Cu" "B.Mask" "B.Paste")
			(net "TP_BMC_GPION7")
		)
	)
	(footprint ""
		(layer "B.Cu")
		(at 190.3984 -120.6246 -90)
		(property "Reference" "C283"
			(at 0 0 90)
			(layer "B.SilkS")
			(hide yes)
			(effects
				(font
					(size 1.27 1.27)
				)
				(justify mirror)
			)
		)
		(property "Value" "SC22U6D3V6KX-2-GP"
			(at 0.0762 -5.1308 270)
			(unlocked yes)
			(layer "B.Fab")
			(hide yes)
			(effects
				(font
					(size 1.016 1.016)
					(thickness 0.1524)
				)
				(justify mirror)
			)
		)
		(property "Device Type" "C1206H71"
			(at 0.127 -6.6548 270)
			(unlocked yes)
			(layer "B.Fab")
			(hide yes)
			(effects
				(font
					(size 1.016 1.016)
					(thickness 0.1524)
				)
				(justify mirror)
			)
		)
		(duplicate_pad_numbers_are_jumpers no)
		(fp_line
			(start -1.016 2.2352)
			(end 1.016 2.2352)
			(stroke
				(width 0.1524)
				(type default)
			)
			(layer "B.SilkS")
		)
		(fp_line
			(start 1.016 2.2352)
			(end 1.016 0.8382)
			(stroke
				(width 0.1524)
				(type default)
			)
			(layer "B.SilkS")
		)
		(fp_line
			(start -1.016 0.8382)
			(end -1.016 2.2352)
			(stroke
				(width 0.1524)
				(type default)
			)
			(layer "B.SilkS")
		)
		(fp_line
			(start 1.016 -0.8382)
			(end 1.016 -2.2352)
			(stroke
				(width 0.1524)
				(type default)
			)
			(layer "B.SilkS")
		)
		(fp_line
			(start -1.016 -2.2352)
			(end -1.016 -0.8382)
			(stroke
				(width 0.1524)
				(type default)
			)
			(layer "B.SilkS")
		)
		(fp_line
			(start 1.016 -2.2352)
			(end -1.016 -2.2352)
			(stroke
				(width 0.1524)
				(type default)
			)
			(layer "B.SilkS")
		)
		(fp_rect
			(start 1.0922 2.3114)
			(end -1.0922 -2.3114)
			(stroke
				(width 0)
				(type default)
			)
			(fill no)
			(layer "B.CrtYd")
		)
		(fp_poly
			(pts
				(xy -1.0922 -2.3114) (xy -1.0922 2.3114) (xy 1.0922 2.3114) (xy 1.0922 -2.3114)
			)
			(stroke
				(width 0)
				(type default)
			)
			(fill no)
			(layer "B.Fab")
		)
		(pad "1" smd rect
			(at 0 -1.397 90)
			(size 1.651 1.27)
			(layers "B.Cu" "B.Mask" "B.Paste")
			(net "VT235_VDDL")
		)
		(pad "2" smd rect
			(at 0 1.397 90)
			(size 1.651 1.27)
			(layers "B.Cu" "B.Mask" "B.Paste")
			(net "GND")
		)
	)
	(footprint ""
		(layer "B.Cu")
		(at 205.7654 -56.9468 180)
		(property "Reference" "R595"
			(at 0 0 0)
			(layer "B.SilkS")
			(hide yes)
			(effects
				(font
					(size 1.27 1.27)
				)
				(justify mirror)
			)
		)
		(property "Value" "2K2R2F-GP"
			(at -0.064008 -3.993896 180)
			(unlocked yes)
			(layer "B.Fab")
			(hide yes)
			(effects
				(font
					(size 1.016 1.016)
					(thickness 0.1524)
				)
				(justify mirror)
			)
		)
		(property "Device Type" "R402H16"
			(at -0.064008 -5.517896 180)
			(unlocked yes)
			(layer "B.Fab")
			(hide yes)
			(effects
				(font
					(size 1.016 1.016)
					(thickness 0.1524)
				)
				(justify mirror)
			)
		)
		(duplicate_pad_numbers_are_jumpers no)
		(fp_line
			(start 0.508 -0.9398)
			(end 0.508 0.9398)
			(stroke
				(width 0.1524)
				(type default)
			)
			(layer "B.SilkS")
		)
		(fp_line
			(start -0.508 -0.9398)
			(end 0.508 -0.9398)
			(stroke
				(width 0.1524)
				(type default)
			)
			(layer "B.SilkS")
		)
		(fp_rect
			(start 0.508 0.9398)
			(end -0.508 -0.9398)
			(stroke
				(width 0)
				(type default)
			)
			(fill no)
			(layer "B.CrtYd")
		)
		(fp_rect
			(start 0.508 0.9398)
			(end -0.508 -0.9398)
			(stroke
				(width 0)
				(type default)
			)
			(fill no)
			(layer "B.Fab")
		)
		(pad "1" smd custom
			(at 0 -0.4445)
			(size 0.1397 0.1397)
			(layers "B.Cu" "B.Mask" "B.Paste")
			(net "P1V8")
			(options
				(clearance outline)
				(anchor circle)
			)
			(primitives
				(gr_poly
					(pts
						(arc
							(start -0.1778 0.2794)
							(mid -0.249642 0.249642)
							(end -0.2794 0.1778)
						)
						(arc
							(start -0.2794 -0.1778)
							(mid -0.249642 -0.249642)
							(end -0.1778 -0.2794)
						)
						(arc
							(start 0.1778 -0.2794)
							(mid 0.249642 -0.249642)
							(end 0.2794 -0.1778)
						)
						(arc
							(start 0.2794 0.1778)
							(mid 0.249642 0.249642)
							(end 0.1778 0.2794)
						)
					)
					(width 0)
					(fill yes)
				)
			)
		)
		(pad "2" smd custom
			(at 0 0.4445)
			(size 0.1397 0.1397)
			(layers "B.Cu" "B.Mask" "B.Paste")
			(net "SIO_LOAD_1")
			(options
				(clearance outline)
				(anchor circle)
			)
			(primitives
				(gr_poly
					(pts
						(arc
							(start -0.1778 0.2794)
							(mid -0.249642 0.249642)
							(end -0.2794 0.1778)
						)
						(arc
							(start -0.2794 -0.1778)
							(mid -0.249642 -0.249642)
							(end -0.1778 -0.2794)
						)
						(arc
							(start 0.1778 -0.2794)
							(mid 0.249642 -0.249642)
							(end 0.2794 -0.1778)
						)
						(arc
							(start 0.2794 0.1778)
							(mid 0.249642 0.249642)
							(end 0.1778 0.2794)
						)
					)
					(width 0)
					(fill yes)
				)
			)
		)
	)
	(footprint ""
		(layer "B.Cu")
		(at 121.397522 -9.64311 180)
		(property "Reference" "CA1"
			(at 0 0 0)
			(layer "B.SilkS")
			(hide yes)
			(effects
				(font
					(size 1.27 1.27)
				)
				(justify mirror)
			)
		)
		(property "Value" "SC2D2U25V5KX-2-GP"
			(at 0.0762 -6.1214 180)
			(unlocked yes)
			(layer "B.Fab")
			(hide yes)
			(effects
				(font
					(size 1.016 1.016)
					(thickness 0.1524)
				)
				(justify mirror)
			)
		)
		(property "Device Type" "C805H54"
			(at 0.0762 -8.1534 180)
			(unlocked yes)
			(layer "B.Fab")
			(hide yes)
			(effects
				(font
					(size 1.016 1.016)
					(thickness 0.1524)
				)
				(justify mirror)
			)
		)
		(duplicate_pad_numbers_are_jumpers no)
		(fp_line
			(start -0.635 0)
			(end 0.635 0)
			(stroke
				(width 0.508)
				(type default)
			)
			(layer "B.SilkS")
		)
		(fp_rect
			(start 0.9652 1.778)
			(end -0.9652 -1.778)
			(stroke
				(width 0)
				(type default)
			)
			(fill no)
			(layer "B.CrtYd")
		)
		(fp_poly
			(pts
				(xy 0.9652 -1.778) (xy -0.9652 -1.778) (xy -0.9652 1.778) (xy 0.9652 1.778)
			)
			(stroke
				(width 0)
				(type default)
			)
			(fill no)
			(layer "B.Fab")
		)
		(pad "1" smd rect
			(at 0 -0.9652)
			(size 1.397 1.143)
			(layers "B.Cu" "B.Mask" "B.Paste")
			(net "P12V_IOM_PGOOD")
		)
		(pad "2" smd rect
			(at 0 0.9652)
			(size 1.397 1.143)
			(layers "B.Cu" "B.Mask" "B.Paste")
			(net "GND")
		)
	)
	(footprint ""
		(layer "B.Cu")
		(at 176.0728 -71.0057)
		(property "Reference" "TP100"
			(at 0 0 0)
			(layer "B.SilkS")
			(hide yes)
			(effects
				(font
					(size 1.27 1.27)
				)
				(justify mirror)
			)
		)
		(property "Value" "TPAD28-2-GP"
			(at 0.0127 -1.6637 0)
			(unlocked yes)
			(layer "B.Fab")
			(hide yes)
			(effects
				(font
					(size 1.016 1.016)
					(thickness 0.1524)
				)
				(justify mirror)
			)
		)
		(property "Device Type" "TPAD28"
			(at 0.0127 -3.1877 0)
			(unlocked yes)
			(layer "B.Fab")
			(hide yes)
			(effects
				(font
					(size 1.016 1.016)
					(thickness 0.1524)
				)
				(justify mirror)
			)
		)
		(duplicate_pad_numbers_are_jumpers no)
		(fp_poly
			(pts
				(arc
					(start 0.3556 0)
					(mid -0.3556 0)
					(end 0.3556 0)
				)
			)
			(stroke
				(width 0)
				(type default)
			)
			(fill no)
			(layer "B.CrtYd")
		)
		(fp_poly
			(pts
				(arc
					(start 0.6096 0)
					(mid -0.6096 0)
					(end 0.6096 0)
				)
			)
			(stroke
				(width 0)
				(type default)
			)
			(fill no)
			(layer "B.Fab")
		)
		(pad "1" smd circle
			(at 0 0 180)
			(size 0.7112 0.7112)
			(layers "B.Cu" "B.Mask" "B.Paste")
			(net "IOC_GPIO_15")
		)
	)
	(footprint ""
		(layer "B.Cu")
		(at 11.345672 -144.098264 -90)
		(property "Reference" "C65"
			(at 0 0 90)
			(layer "B.SilkS")
			(hide yes)
			(effects
				(font
					(size 1.27 1.27)
				)
				(justify mirror)
			)
		)
		(property "Value" "SC1U16V3KX-5GP"
			(at 0 -2.8194 270)
			(unlocked yes)
			(layer "B.Fab")
			(hide yes)
			(effects
				(font
					(size 1.016 1.016)
					(thickness 0.1524)
				)
				(justify mirror)
			)
		)
		(property "Device Type" "C603H36"
			(at 0 -4.3434 270)
			(unlocked yes)
			(layer "B.Fab")
			(hide yes)
			(effects
				(font
					(size 1.016 1.016)
					(thickness 0.1524)
				)
				(justify mirror)
			)
		)
		(duplicate_pad_numbers_are_jumpers no)
		(fp_line
			(start -0.508 0)
			(end 0.508 0)
			(stroke
				(width 0.2032)
				(type default)
			)
			(layer "B.SilkS")
		)
		(fp_rect
			(start 0.5842 1.3335)
			(end -0.5842 -1.3335)
			(stroke
				(width 0)
				(type default)
			)
			(fill no)
			(layer "B.CrtYd")
		)
		(fp_rect
			(start 0.5842 1.3335)
			(end -0.5842 -1.3335)
			(stroke
				(width 0)
				(type default)
			)
			(fill no)
			(layer "B.Fab")
		)
		(pad "1" smd custom
			(at 0 -0.762 90)
			(size 0.2159 0.2159)
			(layers "B.Cu" "B.Mask" "B.Paste")
			(net "P2V5_STBY")
			(options
				(clearance outline)
				(anchor circle)
			)
			(primitives
				(gr_poly
					(pts
						(arc
							(start -0.3302 0.4318)
							(mid -0.402042 0.402042)
							(end -0.4318 0.3302)
						)
						(arc
							(start -0.4318 -0.3302)
							(mid -0.402042 -0.402042)
							(end -0.3302 -0.4318)
						)
						(arc
							(start 0.3302 -0.4318)
							(mid 0.402042 -0.402042)
							(end 0.4318 -0.3302)
						)
						(arc
							(start 0.4318 0.3302)
							(mid 0.402042 0.402042)
							(end 0.3302 0.4318)
						)
					)
					(width 0)
					(fill yes)
				)
			)
		)
		(pad "2" smd custom
			(at 0 0.762 90)
			(size 0.2159 0.2159)
			(layers "B.Cu" "B.Mask" "B.Paste")
			(net "GND")
			(options
				(clearance outline)
				(anchor circle)
			)
			(primitives
				(gr_poly
					(pts
						(arc
							(start -0.3302 0.4318)
							(mid -0.402042 0.402042)
							(end -0.4318 0.3302)
						)
						(arc
							(start -0.4318 -0.3302)
							(mid -0.402042 -0.402042)
							(end -0.3302 -0.4318)
						)
						(arc
							(start 0.3302 -0.4318)
							(mid 0.402042 -0.402042)
							(end 0.4318 -0.3302)
						)
						(arc
							(start 0.4318 0.3302)
							(mid 0.402042 0.402042)
							(end 0.3302 0.4318)
						)
					)
					(width 0)
					(fill yes)
				)
			)
		)
	)
	(footprint ""
		(layer "B.Cu")
		(at 38.42131 -122.188478 -90)
		(property "Reference" "R337"
			(at 0 0 90)
			(layer "B.SilkS")
			(hide yes)
			(effects
				(font
					(size 1.27 1.27)
				)
				(justify mirror)
			)
		)
		(property "Value" "4K7R2F-GP"
			(at -0.064008 -3.993896 270)
			(unlocked yes)
			(layer "B.Fab")
			(hide yes)
			(effects
				(font
					(size 1.016 1.016)
					(thickness 0.1524)
				)
				(justify mirror)
			)
		)
		(property "Device Type" "R402H16"
			(at -0.064008 -5.517896 270)
			(unlocked yes)
			(layer "B.Fab")
			(hide yes)
			(effects
				(font
					(size 1.016 1.016)
					(thickness 0.1524)
				)
				(justify mirror)
			)
		)
		(duplicate_pad_numbers_are_jumpers no)
		(fp_line
			(start -0.508 -0.9398)
			(end 0.508 -0.9398)
			(stroke
				(width 0.1524)
				(type default)
			)
			(layer "B.SilkS")
		)
		(fp_line
			(start 0.508 -0.9398)
			(end 0.508 0.9398)
			(stroke
				(width 0.1524)
				(type default)
			)
			(layer "B.SilkS")
		)
		(fp_rect
			(start 0.508 0.9398)
			(end -0.508 -0.9398)
			(stroke
				(width 0)
				(type default)
			)
			(fill no)
			(layer "B.CrtYd")
		)
		(fp_rect
			(start 0.508 0.9398)
			(end -0.508 -0.9398)
			(stroke
				(width 0)
				(type default)
			)
			(fill no)
			(layer "B.Fab")
		)
		(pad "1" smd custom
			(at 0 -0.4445 90)
			(size 0.1397 0.1397)
			(layers "B.Cu" "B.Mask" "B.Paste")
			(net "TEMP_3_A0")
			(options
				(clearance outline)
				(anchor circle)
			)
			(primitives
				(gr_poly
					(pts
						(arc
							(start -0.1778 0.2794)
							(mid -0.249642 0.249642)
							(end -0.2794 0.1778)
						)
						(arc
							(start -0.2794 -0.1778)
							(mid -0.249642 -0.249642)
							(end -0.1778 -0.2794)
						)
						(arc
							(start 0.1778 -0.2794)
							(mid 0.249642 -0.249642)
							(end 0.2794 -0.1778)
						)
						(arc
							(start 0.2794 0.1778)
							(mid 0.249642 0.249642)
							(end 0.1778 0.2794)
						)
					)
					(width 0)
					(fill yes)
				)
			)
		)
		(pad "2" smd custom
			(at 0 0.4445 90)
			(size 0.1397 0.1397)
			(layers "B.Cu" "B.Mask" "B.Paste")
			(net "GND")
			(options
				(clearance outline)
				(anchor circle)
			)
			(primitives
				(gr_poly
					(pts
						(arc
							(start -0.1778 0.2794)
							(mid -0.249642 0.249642)
							(end -0.2794 0.1778)
						)
						(arc
							(start -0.2794 -0.1778)
							(mid -0.249642 -0.249642)
							(end -0.1778 -0.2794)
						)
						(arc
							(start 0.1778 -0.2794)
							(mid 0.249642 -0.249642)
							(end 0.2794 -0.1778)
						)
						(arc
							(start 0.2794 0.1778)
							(mid 0.249642 0.249642)
							(end 0.1778 0.2794)
						)
					)
					(width 0)
					(fill yes)
				)
			)
		)
	)
	(footprint ""
		(layer "B.Cu")
		(at 95.25 -6.223 90)
		(property "Reference" "C525"
			(at 0 0 90)
			(layer "B.SilkS")
			(hide yes)
			(effects
				(font
					(size 1.27 1.27)
				)
				(justify mirror)
			)
		)
		(property "Value" "SC1000P2KV6KX-GP-U"
			(at -0.0508 -3.5052 90)
			(unlocked yes)
			(layer "B.Fab")
			(hide yes)
			(effects
				(font
					(size 1.016 1.016)
					(thickness 0.1524)
				)
				(justify mirror)
			)
		)
		(property "Device Type" "C1206H58"
			(at -0.0508 -5.0292 90)
			(unlocked yes)
			(layer "B.Fab")
			(hide yes)
			(effects
				(font
					(size 1.016 1.016)
					(thickness 0.1524)
				)
				(justify mirror)
			)
		)
		(duplicate_pad_numbers_are_jumpers no)
		(fp_line
			(start 1.016 -2.2352)
			(end 1.016 -0.8382)
			(stroke
				(width 0.1524)
				(type default)
			)
			(layer "B.SilkS")
		)
		(fp_line
			(start -1.016 -2.2352)
			(end 1.016 -2.2352)
			(stroke
				(width 0.1524)
				(type default)
			)
			(layer "B.SilkS")
		)
		(fp_line
			(start -1.016 -2.2352)
			(end -1.016 -0.8382)
			(stroke
				(width 0.1524)
				(type default)
			)
			(layer "B.SilkS")
		)
		(fp_line
			(start -1.016 0.8382)
			(end -1.016 2.2352)
			(stroke
				(width 0.1524)
				(type default)
			)
			(layer "B.SilkS")
		)
		(fp_line
			(start 1.016 2.2352)
			(end 1.016 0.8128)
			(stroke
				(width 0.1524)
				(type default)
			)
			(layer "B.SilkS")
		)
		(fp_line
			(start -1.016 2.2352)
			(end 1.016 2.2352)
			(stroke
				(width 0.1524)
				(type default)
			)
			(layer "B.SilkS")
		)
		(fp_rect
			(start 1.0922 2.3114)
			(end -1.0922 -2.3114)
			(stroke
				(width 0)
				(type default)
			)
			(fill no)
			(layer "B.CrtYd")
		)
		(fp_poly
			(pts
				(xy 1.0922 -2.3114) (xy -1.0922 -2.3114) (xy -1.0922 2.3114) (xy 1.0922 2.3114)
			)
			(stroke
				(width 0)
				(type default)
			)
			(fill no)
			(layer "B.Fab")
		)
		(pad "1" smd rect
			(at 0 -1.397 270)
			(size 1.651 1.27)
			(layers "B.Cu" "B.Mask" "B.Paste")
			(net "USB_CONN_GND")
		)
		(pad "2" smd rect
			(at 0 1.397 270)
			(size 1.651 1.27)
			(layers "B.Cu" "B.Mask" "B.Paste")
			(net "GND")
		)
	)
	(footprint ""
		(layer "B.Cu")
		(at 63.00851 -150.9395 -90)
		(property "Reference" "R393"
			(at 0 0 90)
			(layer "B.SilkS")
			(hide yes)
			(effects
				(font
					(size 1.27 1.27)
				)
				(justify mirror)
			)
		)
		(property "Value" "4K7R2F-GP"
			(at -0.064008 -3.993896 270)
			(unlocked yes)
			(layer "B.Fab")
			(hide yes)
			(effects
				(font
					(size 1.016 1.016)
					(thickness 0.1524)
				)
				(justify mirror)
			)
		)
		(property "Device Type" "R402H16"
			(at -0.064008 -5.517896 270)
			(unlocked yes)
			(layer "B.Fab")
			(hide yes)
			(effects
				(font
					(size 1.016 1.016)
					(thickness 0.1524)
				)
				(justify mirror)
			)
		)
		(duplicate_pad_numbers_are_jumpers no)
		(fp_line
			(start -0.508 -0.9398)
			(end 0.508 -0.9398)
			(stroke
				(width 0.1524)
				(type default)
			)
			(layer "B.SilkS")
		)
		(fp_line
			(start 0.508 -0.9398)
			(end 0.508 0.9398)
			(stroke
				(width 0.1524)
				(type default)
			)
			(layer "B.SilkS")
		)
		(fp_rect
			(start 0.508 0.9398)
			(end -0.508 -0.9398)
			(stroke
				(width 0)
				(type default)
			)
			(fill no)
			(layer "B.CrtYd")
		)
		(fp_rect
			(start 0.508 0.9398)
			(end -0.508 -0.9398)
			(stroke
				(width 0)
				(type default)
			)
			(fill no)
			(layer "B.Fab")
		)
		(pad "1" smd custom
			(at 0 -0.4445 90)
			(size 0.1397 0.1397)
			(layers "B.Cu" "B.Mask" "B.Paste")
			(net "P3V3_STBY")
			(options
				(clearance outline)
				(anchor circle)
			)
			(primitives
				(gr_poly
					(pts
						(arc
							(start -0.1778 0.2794)
							(mid -0.249642 0.249642)
							(end -0.2794 0.1778)
						)
						(arc
							(start -0.2794 -0.1778)
							(mid -0.249642 -0.249642)
							(end -0.1778 -0.2794)
						)
						(arc
							(start 0.1778 -0.2794)
							(mid 0.249642 -0.249642)
							(end 0.2794 -0.1778)
						)
						(arc
							(start 0.2794 0.1778)
							(mid 0.249642 0.249642)
							(end 0.1778 0.2794)
						)
					)
					(width 0)
					(fill yes)
				)
			)
		)
		(pad "2" smd custom
			(at 0 0.4445 90)
			(size 0.1397 0.1397)
			(layers "B.Cu" "B.Mask" "B.Paste")
			(net "MAC2_TXD2")
			(options
				(clearance outline)
				(anchor circle)
			)
			(primitives
				(gr_poly
					(pts
						(arc
							(start -0.1778 0.2794)
							(mid -0.249642 0.249642)
							(end -0.2794 0.1778)
						)
						(arc
							(start -0.2794 -0.1778)
							(mid -0.249642 -0.249642)
							(end -0.1778 -0.2794)
						)
						(arc
							(start 0.1778 -0.2794)
							(mid 0.249642 -0.249642)
							(end 0.2794 -0.1778)
						)
						(arc
							(start 0.2794 0.1778)
							(mid 0.249642 0.249642)
							(end 0.1778 0.2794)
						)
					)
					(width 0)
					(fill yes)
				)
			)
		)
	)
	(footprint ""
		(layer "B.Cu")
		(at 50.702464 -157.62986 -90)
		(property "Reference" "R281"
			(at 0 0 90)
			(layer "B.SilkS")
			(hide yes)
			(effects
				(font
					(size 1.27 1.27)
				)
				(justify mirror)
			)
		)
		(property "Value" "0R2J-2-GP"
			(at -0.064008 -3.993896 270)
			(unlocked yes)
			(layer "B.Fab")
			(hide yes)
			(effects
				(font
					(size 1.016 1.016)
					(thickness 0.1524)
				)
				(justify mirror)
			)
		)
		(property "Device Type" "R402H16"
			(at -0.064008 -5.517896 270)
			(unlocked yes)
			(layer "B.Fab")
			(hide yes)
			(effects
				(font
					(size 1.016 1.016)
					(thickness 0.1524)
				)
				(justify mirror)
			)
		)
		(duplicate_pad_numbers_are_jumpers no)
		(fp_line
			(start -0.508 -0.9398)
			(end 0.508 -0.9398)
			(stroke
				(width 0.1524)
				(type default)
			)
			(layer "B.SilkS")
		)
		(fp_line
			(start 0.508 -0.9398)
			(end 0.508 0.9398)
			(stroke
				(width 0.1524)
				(type default)
			)
			(layer "B.SilkS")
		)
		(fp_rect
			(start 0.508 0.9398)
			(end -0.508 -0.9398)
			(stroke
				(width 0)
				(type default)
			)
			(fill no)
			(layer "B.CrtYd")
		)
		(fp_rect
			(start 0.508 0.9398)
			(end -0.508 -0.9398)
			(stroke
				(width 0)
				(type default)
			)
			(fill no)
			(layer "B.Fab")
		)
		(pad "1" smd custom
			(at 0 -0.4445 90)
			(size 0.1397 0.1397)
			(layers "B.Cu" "B.Mask" "B.Paste")
			(net "I2C_MEZZ_OOB_SDA")
			(options
				(clearance outline)
				(anchor circle)
			)
			(primitives
				(gr_poly
					(pts
						(arc
							(start -0.1778 0.2794)
							(mid -0.249642 0.249642)
							(end -0.2794 0.1778)
						)
						(arc
							(start -0.2794 -0.1778)
							(mid -0.249642 -0.249642)
							(end -0.1778 -0.2794)
						)
						(arc
							(start 0.1778 -0.2794)
							(mid 0.249642 -0.249642)
							(end 0.2794 -0.1778)
						)
						(arc
							(start 0.2794 0.1778)
							(mid 0.249642 0.249642)
							(end 0.1778 0.2794)
						)
					)
					(width 0)
					(fill yes)
				)
			)
		)
		(pad "2" smd custom
			(at 0 0.4445 90)
			(size 0.1397 0.1397)
			(layers "B.Cu" "B.Mask" "B.Paste")
			(net "BMC_SMB5_DAT")
			(options
				(clearance outline)
				(anchor circle)
			)
			(primitives
				(gr_poly
					(pts
						(arc
							(start -0.1778 0.2794)
							(mid -0.249642 0.249642)
							(end -0.2794 0.1778)
						)
						(arc
							(start -0.2794 -0.1778)
							(mid -0.249642 -0.249642)
							(end -0.1778 -0.2794)
						)
						(arc
							(start 0.1778 -0.2794)
							(mid 0.249642 -0.249642)
							(end 0.2794 -0.1778)
						)
						(arc
							(start 0.2794 0.1778)
							(mid 0.249642 0.249642)
							(end 0.1778 0.2794)
						)
					)
					(width 0)
					(fill yes)
				)
			)
		)
	)
	(footprint ""
		(layer "B.Cu")
		(at 178.695604 -70.088506)
		(property "Reference" "TP125"
			(at 0 0 0)
			(layer "B.SilkS")
			(hide yes)
			(effects
				(font
					(size 1.27 1.27)
				)
				(justify mirror)
			)
		)
		(property "Value" "TPAD28-2-GP"
			(at 0.0127 -1.6637 0)
			(unlocked yes)
			(layer "B.Fab")
			(hide yes)
			(effects
				(font
					(size 1.016 1.016)
					(thickness 0.1524)
				)
				(justify mirror)
			)
		)
		(property "Device Type" "TPAD28"
			(at 0.0127 -3.1877 0)
			(unlocked yes)
			(layer "B.Fab")
			(hide yes)
			(effects
				(font
					(size 1.016 1.016)
					(thickness 0.1524)
				)
				(justify mirror)
			)
		)
		(duplicate_pad_numbers_are_jumpers no)
		(fp_poly
			(pts
				(arc
					(start 0.3556 0)
					(mid -0.3556 0)
					(end 0.3556 0)
				)
			)
			(stroke
				(width 0)
				(type default)
			)
			(fill no)
			(layer "B.CrtYd")
		)
		(fp_poly
			(pts
				(arc
					(start 0.6096 0)
					(mid -0.6096 0)
					(end 0.6096 0)
				)
			)
			(stroke
				(width 0)
				(type default)
			)
			(fill no)
			(layer "B.Fab")
		)
		(pad "1" smd circle
			(at 0 0 180)
			(size 0.7112 0.7112)
			(layers "B.Cu" "B.Mask" "B.Paste")
			(net "IOC_GPIO_33")
		)
	)
	(footprint ""
		(layer "B.Cu")
		(at 190.8175 -64.8208 90)
		(property "Reference" "C396"
			(at 0 0 90)
			(layer "B.SilkS")
			(hide yes)
			(effects
				(font
					(size 1.27 1.27)
				)
				(justify mirror)
			)
		)
		(property "Value" "SCD1U6D3V1KX-GP"
			(at 2.8321 -1.7399 90)
			(unlocked yes)
			(layer "B.Fab")
			(hide yes)
			(effects
				(font
					(size 1.016 1.016)
					(thickness 0.1524)
				)
				(justify mirror)
			)
		)
		(property "Device Type" "C0201H13"
			(at 2.8321 -3.2639 90)
			(unlocked yes)
			(layer "B.Fab")
			(hide yes)
			(effects
				(font
					(size 1.016 1.016)
					(thickness 0.1524)
				)
				(justify mirror)
			)
		)
		(duplicate_pad_numbers_are_jumpers no)
		(fp_rect
			(start 0.2794 0.6477)
			(end -0.2794 -0.6477)
			(stroke
				(width 0)
				(type default)
			)
			(fill no)
			(layer "B.CrtYd")
		)
		(fp_rect
			(start 0.2794 0.6477)
			(end -0.2794 -0.6477)
			(stroke
				(width 0)
				(type default)
			)
			(fill no)
			(layer "B.Fab")
		)
		(pad "1" smd custom
			(at 0 -0.2794 270)
			(size 0.0762 0.0762)
			(layers "B.Cu" "B.Mask" "B.Paste")
			(net "P0V975")
			(options
				(clearance outline)
				(anchor circle)
			)
			(primitives
				(gr_poly
					(pts
						(arc
							(start 0.1524 0.127)
							(mid 0.137521 0.162921)
							(end 0.1016 0.1778)
						)
						(arc
							(start -0.1016 0.1778)
							(mid -0.137521 0.162921)
							(end -0.1524 0.127)
						)
						(arc
							(start -0.1524 -0.127)
							(mid -0.137521 -0.162921)
							(end -0.1016 -0.1778)
						)
						(arc
							(start 0.1016 -0.1778)
							(mid 0.137521 -0.162921)
							(end 0.1524 -0.127)
						)
					)
					(width 0)
					(fill yes)
				)
			)
		)
		(pad "2" smd custom
			(at 0 0.2794 270)
			(size 0.0762 0.0762)
			(layers "B.Cu" "B.Mask" "B.Paste")
			(net "GND")
			(options
				(clearance outline)
				(anchor circle)
			)
			(primitives
				(gr_poly
					(pts
						(arc
							(start 0.1524 0.127)
							(mid 0.137521 0.162921)
							(end 0.1016 0.1778)
						)
						(arc
							(start -0.1016 0.1778)
							(mid -0.137521 0.162921)
							(end -0.1524 0.127)
						)
						(arc
							(start -0.1524 -0.127)
							(mid -0.137521 -0.162921)
							(end -0.1016 -0.1778)
						)
						(arc
							(start 0.1016 -0.1778)
							(mid 0.137521 -0.162921)
							(end 0.1524 -0.127)
						)
					)
					(width 0)
					(fill yes)
				)
			)
		)
	)
	(footprint ""
		(layer "B.Cu")
		(at 32.37738 -126.8349 90)
		(property "Reference" "R734"
			(at 0 0 90)
			(layer "B.SilkS")
			(hide yes)
			(effects
				(font
					(size 1.27 1.27)
				)
				(justify mirror)
			)
		)
		(property "Value" "0R2J-2-GP"
			(at -0.064008 -3.993896 90)
			(unlocked yes)
			(layer "B.Fab")
			(hide yes)
			(effects
				(font
					(size 1.016 1.016)
					(thickness 0.1524)
				)
				(justify mirror)
			)
		)
		(property "Device Type" "R402H16"
			(at -0.064008 -5.517896 90)
			(unlocked yes)
			(layer "B.Fab")
			(hide yes)
			(effects
				(font
					(size 1.016 1.016)
					(thickness 0.1524)
				)
				(justify mirror)
			)
		)
		(duplicate_pad_numbers_are_jumpers no)
		(fp_line
			(start 0.508 -0.9398)
			(end 0.508 0.9398)
			(stroke
				(width 0.1524)
				(type default)
			)
			(layer "B.SilkS")
		)
		(fp_line
			(start -0.508 -0.9398)
			(end 0.508 -0.9398)
			(stroke
				(width 0.1524)
				(type default)
			)
			(layer "B.SilkS")
		)
		(fp_rect
			(start 0.508 0.9398)
			(end -0.508 -0.9398)
			(stroke
				(width 0)
				(type default)
			)
			(fill no)
			(layer "B.CrtYd")
		)
		(fp_rect
			(start 0.508 0.9398)
			(end -0.508 -0.9398)
			(stroke
				(width 0)
				(type default)
			)
			(fill no)
			(layer "B.Fab")
		)
		(pad "1" smd custom
			(at 0 -0.4445 270)
			(size 0.1397 0.1397)
			(layers "B.Cu" "B.Mask" "B.Paste")
			(net "U104_EN")
			(options
				(clearance outline)
				(anchor circle)
			)
			(primitives
				(gr_poly
					(pts
						(arc
							(start -0.1778 0.2794)
							(mid -0.249642 0.249642)
							(end -0.2794 0.1778)
						)
						(arc
							(start -0.2794 -0.1778)
							(mid -0.249642 -0.249642)
							(end -0.1778 -0.2794)
						)
						(arc
							(start 0.1778 -0.2794)
							(mid 0.249642 -0.249642)
							(end 0.2794 -0.1778)
						)
						(arc
							(start 0.2794 0.1778)
							(mid 0.249642 0.249642)
							(end 0.1778 0.2794)
						)
					)
					(width 0)
					(fill yes)
				)
			)
		)
		(pad "2" smd custom
			(at 0 0.4445 270)
			(size 0.1397 0.1397)
			(layers "B.Cu" "B.Mask" "B.Paste")
			(net "SYS_RST_EN")
			(options
				(clearance outline)
				(anchor circle)
			)
			(primitives
				(gr_poly
					(pts
						(arc
							(start -0.1778 0.2794)
							(mid -0.249642 0.249642)
							(end -0.2794 0.1778)
						)
						(arc
							(start -0.2794 -0.1778)
							(mid -0.249642 -0.249642)
							(end -0.1778 -0.2794)
						)
						(arc
							(start 0.1778 -0.2794)
							(mid 0.249642 -0.249642)
							(end 0.2794 -0.1778)
						)
						(arc
							(start 0.2794 0.1778)
							(mid 0.249642 0.249642)
							(end 0.1778 0.2794)
						)
					)
					(width 0)
					(fill yes)
				)
			)
		)
	)
	(footprint ""
		(layer "B.Cu")
		(at 45.300392 -144.335754 90)
		(property "Reference" "C56"
			(at 0 0 90)
			(layer "B.SilkS")
			(hide yes)
			(effects
				(font
					(size 1.27 1.27)
				)
				(justify mirror)
			)
		)
		(property "Value" "SC1U16V3KX-5GP"
			(at 0 -2.8194 90)
			(unlocked yes)
			(layer "B.Fab")
			(hide yes)
			(effects
				(font
					(size 1.016 1.016)
					(thickness 0.1524)
				)
				(justify mirror)
			)
		)
		(property "Device Type" "C603H36"
			(at 0 -4.3434 90)
			(unlocked yes)
			(layer "B.Fab")
			(hide yes)
			(effects
				(font
					(size 1.016 1.016)
					(thickness 0.1524)
				)
				(justify mirror)
			)
		)
		(duplicate_pad_numbers_are_jumpers no)
		(fp_line
			(start -0.508 0)
			(end 0.508 0)
			(stroke
				(width 0.2032)
				(type default)
			)
			(layer "B.SilkS")
		)
		(fp_rect
			(start 0.5842 1.3335)
			(end -0.5842 -1.3335)
			(stroke
				(width 0)
				(type default)
			)
			(fill no)
			(layer "B.CrtYd")
		)
		(fp_rect
			(start 0.5842 1.3335)
			(end -0.5842 -1.3335)
			(stroke
				(width 0)
				(type default)
			)
			(fill no)
			(layer "B.Fab")
		)
		(pad "1" smd custom
			(at 0 -0.762 270)
			(size 0.2159 0.2159)
			(layers "B.Cu" "B.Mask" "B.Paste")
			(net "P1V2_STBY")
			(options
				(clearance outline)
				(anchor circle)
			)
			(primitives
				(gr_poly
					(pts
						(arc
							(start -0.3302 0.4318)
							(mid -0.402042 0.402042)
							(end -0.4318 0.3302)
						)
						(arc
							(start -0.4318 -0.3302)
							(mid -0.402042 -0.402042)
							(end -0.3302 -0.4318)
						)
						(arc
							(start 0.3302 -0.4318)
							(mid 0.402042 -0.402042)
							(end 0.4318 -0.3302)
						)
						(arc
							(start 0.4318 0.3302)
							(mid 0.402042 0.402042)
							(end 0.3302 0.4318)
						)
					)
					(width 0)
					(fill yes)
				)
			)
		)
		(pad "2" smd custom
			(at 0 0.762 270)
			(size 0.2159 0.2159)
			(layers "B.Cu" "B.Mask" "B.Paste")
			(net "GND")
			(options
				(clearance outline)
				(anchor circle)
			)
			(primitives
				(gr_poly
					(pts
						(arc
							(start -0.3302 0.4318)
							(mid -0.402042 0.402042)
							(end -0.4318 0.3302)
						)
						(arc
							(start -0.4318 -0.3302)
							(mid -0.402042 -0.402042)
							(end -0.3302 -0.4318)
						)
						(arc
							(start 0.3302 -0.4318)
							(mid 0.402042 -0.402042)
							(end 0.4318 -0.3302)
						)
						(arc
							(start 0.4318 0.3302)
							(mid 0.402042 0.402042)
							(end 0.3302 0.4318)
						)
					)
					(width 0)
					(fill yes)
				)
			)
		)
	)
	(footprint ""
		(layer "B.Cu")
		(at 196.4182 -59.4106 90)
		(property "Reference" "C428"
			(at 0 0 90)
			(layer "B.SilkS")
			(hide yes)
			(effects
				(font
					(size 1.27 1.27)
				)
				(justify mirror)
			)
		)
		(property "Value" "SC1KP50V2KX-1GP"
			(at -1.1811 -2.7051 90)
			(unlocked yes)
			(layer "B.Fab")
			(hide yes)
			(effects
				(font
					(size 1.016 1.016)
					(thickness 0.1524)
				)
				(justify mirror)
			)
		)
		(property "Device Type" "C402H22"
			(at -1.1811 -4.2291 90)
			(unlocked yes)
			(layer "B.Fab")
			(hide yes)
			(effects
				(font
					(size 1.016 1.016)
					(thickness 0.1524)
				)
				(justify mirror)
			)
		)
		(duplicate_pad_numbers_are_jumpers no)
		(fp_rect
			(start 0.4318 0.9525)
			(end -0.4318 -0.9525)
			(stroke
				(width 0)
				(type default)
			)
			(fill no)
			(layer "B.CrtYd")
		)
		(fp_rect
			(start 0.4318 0.9525)
			(end -0.4318 -0.9525)
			(stroke
				(width 0)
				(type default)
			)
			(fill no)
			(layer "B.Fab")
		)
		(pad "1" smd custom
			(at 0 -0.4445 270)
			(size 0.1524 0.1524)
			(layers "B.Cu" "B.Mask" "B.Paste")
			(net "P0V975")
			(options
				(clearance outline)
				(anchor circle)
			)
			(primitives
				(gr_poly
					(pts
						(arc
							(start 0.3048 0.2032)
							(mid 0.275042 0.275042)
							(end 0.2032 0.3048)
						)
						(arc
							(start -0.2032 0.3048)
							(mid -0.275042 0.275042)
							(end -0.3048 0.2032)
						)
						(arc
							(start -0.3048 -0.2032)
							(mid -0.275042 -0.275042)
							(end -0.2032 -0.3048)
						)
						(arc
							(start 0.2032 -0.3048)
							(mid 0.275042 -0.275042)
							(end 0.3048 -0.2032)
						)
					)
					(width 0)
					(fill yes)
				)
			)
		)
		(pad "2" smd custom
			(at 0 0.4445 270)
			(size 0.1524 0.1524)
			(layers "B.Cu" "B.Mask" "B.Paste")
			(net "GND")
			(options
				(clearance outline)
				(anchor circle)
			)
			(primitives
				(gr_poly
					(pts
						(arc
							(start 0.3048 0.2032)
							(mid 0.275042 0.275042)
							(end 0.2032 0.3048)
						)
						(arc
							(start -0.2032 0.3048)
							(mid -0.275042 0.275042)
							(end -0.3048 0.2032)
						)
						(arc
							(start -0.3048 -0.2032)
							(mid -0.275042 -0.275042)
							(end -0.2032 -0.3048)
						)
						(arc
							(start 0.2032 -0.3048)
							(mid 0.275042 -0.275042)
							(end 0.3048 -0.2032)
						)
					)
					(width 0)
					(fill yes)
				)
			)
		)
	)
	(footprint ""
		(layer "B.Cu")
		(at 23.58898 -143.81861 180)
		(property "Reference" "C67"
			(at 0 0 0)
			(layer "B.SilkS")
			(hide yes)
			(effects
				(font
					(size 1.27 1.27)
				)
				(justify mirror)
			)
		)
		(property "Value" "SCD1U16V2KX-3GP"
			(at -1.1811 -2.7051 180)
			(unlocked yes)
			(layer "B.Fab")
			(hide yes)
			(effects
				(font
					(size 1.016 1.016)
					(thickness 0.1524)
				)
				(justify mirror)
			)
		)
		(property "Device Type" "C402H22"
			(at -1.1811 -4.2291 180)
			(unlocked yes)
			(layer "B.Fab")
			(hide yes)
			(effects
				(font
					(size 1.016 1.016)
					(thickness 0.1524)
				)
				(justify mirror)
			)
		)
		(duplicate_pad_numbers_are_jumpers no)
		(fp_rect
			(start 0.4318 0.9525)
			(end -0.4318 -0.9525)
			(stroke
				(width 0)
				(type default)
			)
			(fill no)
			(layer "B.CrtYd")
		)
		(fp_rect
			(start 0.4318 0.9525)
			(end -0.4318 -0.9525)
			(stroke
				(width 0)
				(type default)
			)
			(fill no)
			(layer "B.Fab")
		)
		(pad "1" smd custom
			(at 0 -0.4445)
			(size 0.1524 0.1524)
			(layers "B.Cu" "B.Mask" "B.Paste")
			(net "GND")
			(options
				(clearance outline)
				(anchor circle)
			)
			(primitives
				(gr_poly
					(pts
						(arc
							(start 0.3048 0.2032)
							(mid 0.275042 0.275042)
							(end 0.2032 0.3048)
						)
						(arc
							(start -0.2032 0.3048)
							(mid -0.275042 0.275042)
							(end -0.3048 0.2032)
						)
						(arc
							(start -0.3048 -0.2032)
							(mid -0.275042 -0.275042)
							(end -0.2032 -0.3048)
						)
						(arc
							(start 0.2032 -0.3048)
							(mid 0.275042 -0.275042)
							(end 0.3048 -0.2032)
						)
					)
					(width 0)
					(fill yes)
				)
			)
		)
		(pad "2" smd custom
			(at 0 0.4445)
			(size 0.1524 0.1524)
			(layers "B.Cu" "B.Mask" "B.Paste")
			(net "P1V2_STBY")
			(options
				(clearance outline)
				(anchor circle)
			)
			(primitives
				(gr_poly
					(pts
						(arc
							(start 0.3048 0.2032)
							(mid 0.275042 0.275042)
							(end 0.2032 0.3048)
						)
						(arc
							(start -0.2032 0.3048)
							(mid -0.275042 0.275042)
							(end -0.3048 0.2032)
						)
						(arc
							(start -0.3048 -0.2032)
							(mid -0.275042 -0.275042)
							(end -0.2032 -0.3048)
						)
						(arc
							(start 0.2032 -0.3048)
							(mid 0.275042 -0.275042)
							(end 0.3048 -0.2032)
						)
					)
					(width 0)
					(fill yes)
				)
			)
		)
	)
	(footprint ""
		(layer "B.Cu")
		(at 183.69534 -53.3019)
		(property "Reference" "TP167"
			(at 0 0 0)
			(layer "B.SilkS")
			(hide yes)
			(effects
				(font
					(size 1.27 1.27)
				)
				(justify mirror)
			)
		)
		(property "Value" "TPAD28-2-GP"
			(at 0.0127 -1.6637 0)
			(unlocked yes)
			(layer "B.Fab")
			(hide yes)
			(effects
				(font
					(size 1.016 1.016)
					(thickness 0.1524)
				)
				(justify mirror)
			)
		)
		(property "Device Type" "TPAD28"
			(at 0.0127 -3.1877 0)
			(unlocked yes)
			(layer "B.Fab")
			(hide yes)
			(effects
				(font
					(size 1.016 1.016)
					(thickness 0.1524)
				)
				(justify mirror)
			)
		)
		(duplicate_pad_numbers_are_jumpers no)
		(fp_poly
			(pts
				(arc
					(start 0.3556 0)
					(mid -0.3556 0)
					(end 0.3556 0)
				)
			)
			(stroke
				(width 0)
				(type default)
			)
			(fill no)
			(layer "B.CrtYd")
		)
		(fp_poly
			(pts
				(arc
					(start 0.6096 0)
					(mid -0.6096 0)
					(end 0.6096 0)
				)
			)
			(stroke
				(width 0)
				(type default)
			)
			(fill no)
			(layer "B.Fab")
		)
		(pad "1" smd circle
			(at 0 0 180)
			(size 0.7112 0.7112)
			(layers "B.Cu" "B.Mask" "B.Paste")
			(net "XM_WP")
		)
	)
	(footprint ""
		(layer "B.Cu")
		(at 39.723314 -150.106888)
		(property "Reference" "TP62"
			(at 0 0 0)
			(layer "B.SilkS")
			(hide yes)
			(effects
				(font
					(size 1.27 1.27)
				)
				(justify mirror)
			)
		)
		(property "Value" "TPAD28-2-GP"
			(at 0.0127 -1.6637 0)
			(unlocked yes)
			(layer "B.Fab")
			(hide yes)
			(effects
				(font
					(size 1.016 1.016)
					(thickness 0.1524)
				)
				(justify mirror)
			)
		)
		(property "Device Type" "TPAD28"
			(at 0.0127 -3.1877 0)
			(unlocked yes)
			(layer "B.Fab")
			(hide yes)
			(effects
				(font
					(size 1.016 1.016)
					(thickness 0.1524)
				)
				(justify mirror)
			)
		)
		(duplicate_pad_numbers_are_jumpers no)
		(fp_poly
			(pts
				(arc
					(start 0.3556 0)
					(mid -0.3556 0)
					(end 0.3556 0)
				)
			)
			(stroke
				(width 0)
				(type default)
			)
			(fill no)
			(layer "B.CrtYd")
		)
		(fp_poly
			(pts
				(arc
					(start 0.6096 0)
					(mid -0.6096 0)
					(end 0.6096 0)
				)
			)
			(stroke
				(width 0)
				(type default)
			)
			(fill no)
			(layer "B.Fab")
		)
		(pad "1" smd circle
			(at 0 0 180)
			(size 0.7112 0.7112)
			(layers "B.Cu" "B.Mask" "B.Paste")
			(net "TP_BMC_GPION2")
		)
	)
	(footprint ""
		(layer "B.Cu")
		(at 51.03114 -142.61846 180)
		(property "Reference" "R357"
			(at 0 0 0)
			(layer "B.SilkS")
			(hide yes)
			(effects
				(font
					(size 1.27 1.27)
				)
				(justify mirror)
			)
		)
		(property "Value" "4K7R2F-GP"
			(at -0.064008 -3.993896 180)
			(unlocked yes)
			(layer "B.Fab")
			(hide yes)
			(effects
				(font
					(size 1.016 1.016)
					(thickness 0.1524)
				)
				(justify mirror)
			)
		)
		(property "Device Type" "R402H16"
			(at -0.064008 -5.517896 180)
			(unlocked yes)
			(layer "B.Fab")
			(hide yes)
			(effects
				(font
					(size 1.016 1.016)
					(thickness 0.1524)
				)
				(justify mirror)
			)
		)
		(duplicate_pad_numbers_are_jumpers no)
		(fp_line
			(start 0.508 -0.9398)
			(end 0.508 0.9398)
			(stroke
				(width 0.1524)
				(type default)
			)
			(layer "B.SilkS")
		)
		(fp_line
			(start -0.508 -0.9398)
			(end 0.508 -0.9398)
			(stroke
				(width 0.1524)
				(type default)
			)
			(layer "B.SilkS")
		)
		(fp_rect
			(start 0.508 0.9398)
			(end -0.508 -0.9398)
			(stroke
				(width 0)
				(type default)
			)
			(fill no)
			(layer "B.CrtYd")
		)
		(fp_rect
			(start 0.508 0.9398)
			(end -0.508 -0.9398)
			(stroke
				(width 0)
				(type default)
			)
			(fill no)
			(layer "B.Fab")
		)
		(pad "1" smd custom
			(at 0 -0.4445)
			(size 0.1397 0.1397)
			(layers "B.Cu" "B.Mask" "B.Paste")
			(net "P3V3_STBY")
			(options
				(clearance outline)
				(anchor circle)
			)
			(primitives
				(gr_poly
					(pts
						(arc
							(start -0.1778 0.2794)
							(mid -0.249642 0.249642)
							(end -0.2794 0.1778)
						)
						(arc
							(start -0.2794 -0.1778)
							(mid -0.249642 -0.249642)
							(end -0.1778 -0.2794)
						)
						(arc
							(start 0.1778 -0.2794)
							(mid 0.249642 -0.249642)
							(end 0.2794 -0.1778)
						)
						(arc
							(start 0.2794 0.1778)
							(mid 0.249642 0.249642)
							(end 0.1778 0.2794)
						)
					)
					(width 0)
					(fill yes)
				)
			)
		)
		(pad "2" smd custom
			(at 0 0.4445)
			(size 0.1397 0.1397)
			(layers "B.Cu" "B.Mask" "B.Paste")
			(net "JTAG_BMC_TRST_N")
			(options
				(clearance outline)
				(anchor circle)
			)
			(primitives
				(gr_poly
					(pts
						(arc
							(start -0.1778 0.2794)
							(mid -0.249642 0.249642)
							(end -0.2794 0.1778)
						)
						(arc
							(start -0.2794 -0.1778)
							(mid -0.249642 -0.249642)
							(end -0.1778 -0.2794)
						)
						(arc
							(start 0.1778 -0.2794)
							(mid 0.249642 -0.249642)
							(end 0.2794 -0.1778)
						)
						(arc
							(start 0.2794 0.1778)
							(mid 0.249642 0.249642)
							(end 0.1778 0.2794)
						)
					)
					(width 0)
					(fill yes)
				)
			)
		)
	)
	(footprint ""
		(layer "B.Cu")
		(at 159.893 -48.895)
		(property "Reference" "R748"
			(at 0 0 0)
			(layer "B.SilkS")
			(hide yes)
			(effects
				(font
					(size 1.27 1.27)
				)
				(justify mirror)
			)
		)
		(property "Value" "10KR2F-2-GP"
			(at -0.064008 -3.993896 0)
			(unlocked yes)
			(layer "B.Fab")
			(hide yes)
			(effects
				(font
					(size 1.016 1.016)
					(thickness 0.1524)
				)
				(justify mirror)
			)
		)
		(property "Device Type" "R402H16"
			(at -0.064008 -5.517896 0)
			(unlocked yes)
			(layer "B.Fab")
			(hide yes)
			(effects
				(font
					(size 1.016 1.016)
					(thickness 0.1524)
				)
				(justify mirror)
			)
		)
		(duplicate_pad_numbers_are_jumpers no)
		(fp_line
			(start -0.508 -0.9398)
			(end 0.508 -0.9398)
			(stroke
				(width 0.1524)
				(type default)
			)
			(layer "B.SilkS")
		)
		(fp_line
			(start 0.508 -0.9398)
			(end 0.508 0.9398)
			(stroke
				(width 0.1524)
				(type default)
			)
			(layer "B.SilkS")
		)
		(fp_rect
			(start 0.508 0.9398)
			(end -0.508 -0.9398)
			(stroke
				(width 0)
				(type default)
			)
			(fill no)
			(layer "B.CrtYd")
		)
		(fp_rect
			(start 0.508 0.9398)
			(end -0.508 -0.9398)
			(stroke
				(width 0)
				(type default)
			)
			(fill no)
			(layer "B.Fab")
		)
		(pad "1" smd custom
			(at 0 -0.4445 180)
			(size 0.1397 0.1397)
			(layers "B.Cu" "B.Mask" "B.Paste")
			(net "BYTE_N")
			(options
				(clearance outline)
				(anchor circle)
			)
			(primitives
				(gr_poly
					(pts
						(arc
							(start -0.1778 0.2794)
							(mid -0.249642 0.249642)
							(end -0.2794 0.1778)
						)
						(arc
							(start -0.2794 -0.1778)
							(mid -0.249642 -0.249642)
							(end -0.1778 -0.2794)
						)
						(arc
							(start 0.1778 -0.2794)
							(mid 0.249642 -0.249642)
							(end 0.2794 -0.1778)
						)
						(arc
							(start 0.2794 0.1778)
							(mid 0.249642 0.249642)
							(end 0.1778 0.2794)
						)
					)
					(width 0)
					(fill yes)
				)
			)
		)
		(pad "2" smd custom
			(at 0 0.4445 180)
			(size 0.1397 0.1397)
			(layers "B.Cu" "B.Mask" "B.Paste")
			(net "GND")
			(options
				(clearance outline)
				(anchor circle)
			)
			(primitives
				(gr_poly
					(pts
						(arc
							(start -0.1778 0.2794)
							(mid -0.249642 0.249642)
							(end -0.2794 0.1778)
						)
						(arc
							(start -0.2794 -0.1778)
							(mid -0.249642 -0.249642)
							(end -0.1778 -0.2794)
						)
						(arc
							(start 0.1778 -0.2794)
							(mid 0.249642 -0.249642)
							(end 0.2794 -0.1778)
						)
						(arc
							(start 0.2794 0.1778)
							(mid 0.249642 0.249642)
							(end 0.1778 0.2794)
						)
					)
					(width 0)
					(fill yes)
				)
			)
		)
	)
	(footprint ""
		(layer "B.Cu")
		(at 190.8556 -63.7794 90)
		(property "Reference" "C413"
			(at 0 0 90)
			(layer "B.SilkS")
			(hide yes)
			(effects
				(font
					(size 1.27 1.27)
				)
				(justify mirror)
			)
		)
		(property "Value" "SCD1U6D3V1KX-GP"
			(at 2.8321 -1.7399 90)
			(unlocked yes)
			(layer "B.Fab")
			(hide yes)
			(effects
				(font
					(size 1.016 1.016)
					(thickness 0.1524)
				)
				(justify mirror)
			)
		)
		(property "Device Type" "C0201H13"
			(at 2.8321 -3.2639 90)
			(unlocked yes)
			(layer "B.Fab")
			(hide yes)
			(effects
				(font
					(size 1.016 1.016)
					(thickness 0.1524)
				)
				(justify mirror)
			)
		)
		(duplicate_pad_numbers_are_jumpers no)
		(fp_rect
			(start 0.2794 0.6477)
			(end -0.2794 -0.6477)
			(stroke
				(width 0)
				(type default)
			)
			(fill no)
			(layer "B.CrtYd")
		)
		(fp_rect
			(start 0.2794 0.6477)
			(end -0.2794 -0.6477)
			(stroke
				(width 0)
				(type default)
			)
			(fill no)
			(layer "B.Fab")
		)
		(pad "1" smd custom
			(at 0 -0.2794 270)
			(size 0.0762 0.0762)
			(layers "B.Cu" "B.Mask" "B.Paste")
			(net "P0V975")
			(options
				(clearance outline)
				(anchor circle)
			)
			(primitives
				(gr_poly
					(pts
						(arc
							(start 0.1524 0.127)
							(mid 0.137521 0.162921)
							(end 0.1016 0.1778)
						)
						(arc
							(start -0.1016 0.1778)
							(mid -0.137521 0.162921)
							(end -0.1524 0.127)
						)
						(arc
							(start -0.1524 -0.127)
							(mid -0.137521 -0.162921)
							(end -0.1016 -0.1778)
						)
						(arc
							(start 0.1016 -0.1778)
							(mid 0.137521 -0.162921)
							(end 0.1524 -0.127)
						)
					)
					(width 0)
					(fill yes)
				)
			)
		)
		(pad "2" smd custom
			(at 0 0.2794 270)
			(size 0.0762 0.0762)
			(layers "B.Cu" "B.Mask" "B.Paste")
			(net "GND")
			(options
				(clearance outline)
				(anchor circle)
			)
			(primitives
				(gr_poly
					(pts
						(arc
							(start 0.1524 0.127)
							(mid 0.137521 0.162921)
							(end 0.1016 0.1778)
						)
						(arc
							(start -0.1016 0.1778)
							(mid -0.137521 0.162921)
							(end -0.1524 0.127)
						)
						(arc
							(start -0.1524 -0.127)
							(mid -0.137521 -0.162921)
							(end -0.1016 -0.1778)
						)
						(arc
							(start 0.1016 -0.1778)
							(mid 0.137521 -0.162921)
							(end 0.1524 -0.127)
						)
					)
					(width 0)
					(fill yes)
				)
			)
		)
	)
	(footprint ""
		(layer "B.Cu")
		(at 43.483022 -161.366962 -90)
		(property "Reference" "R311"
			(at 0 0 90)
			(layer "B.SilkS")
			(hide yes)
			(effects
				(font
					(size 1.27 1.27)
				)
				(justify mirror)
			)
		)
		(property "Value" "4K7R2F-GP"
			(at -0.064008 -3.993896 270)
			(unlocked yes)
			(layer "B.Fab")
			(hide yes)
			(effects
				(font
					(size 1.016 1.016)
					(thickness 0.1524)
				)
				(justify mirror)
			)
		)
		(property "Device Type" "R402H16"
			(at -0.064008 -5.517896 270)
			(unlocked yes)
			(layer "B.Fab")
			(hide yes)
			(effects
				(font
					(size 1.016 1.016)
					(thickness 0.1524)
				)
				(justify mirror)
			)
		)
		(duplicate_pad_numbers_are_jumpers no)
		(fp_line
			(start -0.508 -0.9398)
			(end 0.508 -0.9398)
			(stroke
				(width 0.1524)
				(type default)
			)
			(layer "B.SilkS")
		)
		(fp_line
			(start 0.508 -0.9398)
			(end 0.508 0.9398)
			(stroke
				(width 0.1524)
				(type default)
			)
			(layer "B.SilkS")
		)
		(fp_rect
			(start 0.508 0.9398)
			(end -0.508 -0.9398)
			(stroke
				(width 0)
				(type default)
			)
			(fill no)
			(layer "B.CrtYd")
		)
		(fp_rect
			(start 0.508 0.9398)
			(end -0.508 -0.9398)
			(stroke
				(width 0)
				(type default)
			)
			(fill no)
			(layer "B.Fab")
		)
		(pad "1" smd custom
			(at 0 -0.4445 90)
			(size 0.1397 0.1397)
			(layers "B.Cu" "B.Mask" "B.Paste")
			(net "BOARD_REV_2")
			(options
				(clearance outline)
				(anchor circle)
			)
			(primitives
				(gr_poly
					(pts
						(arc
							(start -0.1778 0.2794)
							(mid -0.249642 0.249642)
							(end -0.2794 0.1778)
						)
						(arc
							(start -0.2794 -0.1778)
							(mid -0.249642 -0.249642)
							(end -0.1778 -0.2794)
						)
						(arc
							(start 0.1778 -0.2794)
							(mid 0.249642 -0.249642)
							(end 0.2794 -0.1778)
						)
						(arc
							(start 0.2794 0.1778)
							(mid 0.249642 0.249642)
							(end 0.1778 0.2794)
						)
					)
					(width 0)
					(fill yes)
				)
			)
		)
		(pad "2" smd custom
			(at 0 0.4445 90)
			(size 0.1397 0.1397)
			(layers "B.Cu" "B.Mask" "B.Paste")
			(net "P3V3_STBY")
			(options
				(clearance outline)
				(anchor circle)
			)
			(primitives
				(gr_poly
					(pts
						(arc
							(start -0.1778 0.2794)
							(mid -0.249642 0.249642)
							(end -0.2794 0.1778)
						)
						(arc
							(start -0.2794 -0.1778)
							(mid -0.249642 -0.249642)
							(end -0.1778 -0.2794)
						)
						(arc
							(start 0.1778 -0.2794)
							(mid 0.249642 -0.249642)
							(end 0.2794 -0.1778)
						)
						(arc
							(start 0.2794 0.1778)
							(mid 0.249642 0.249642)
							(end 0.1778 0.2794)
						)
					)
					(width 0)
					(fill yes)
				)
			)
		)
	)
	(footprint ""
		(layer "B.Cu")
		(at 86.3346 -176.8094 -90)
		(property "Reference" "R92"
			(at 0 0 90)
			(layer "B.SilkS")
			(hide yes)
			(effects
				(font
					(size 1.27 1.27)
				)
				(justify mirror)
			)
		)
		(property "Value" "0R2J-2-GP"
			(at -0.064008 -3.993896 270)
			(unlocked yes)
			(layer "B.Fab")
			(hide yes)
			(effects
				(font
					(size 1.016 1.016)
					(thickness 0.1524)
				)
				(justify mirror)
			)
		)
		(property "Device Type" "R402H16"
			(at -0.064008 -5.517896 270)
			(unlocked yes)
			(layer "B.Fab")
			(hide yes)
			(effects
				(font
					(size 1.016 1.016)
					(thickness 0.1524)
				)
				(justify mirror)
			)
		)
		(duplicate_pad_numbers_are_jumpers no)
		(fp_line
			(start -0.508 -0.9398)
			(end 0.508 -0.9398)
			(stroke
				(width 0.1524)
				(type default)
			)
			(layer "B.SilkS")
		)
		(fp_line
			(start 0.508 -0.9398)
			(end 0.508 0.9398)
			(stroke
				(width 0.1524)
				(type default)
			)
			(layer "B.SilkS")
		)
		(fp_rect
			(start 0.508 0.9398)
			(end -0.508 -0.9398)
			(stroke
				(width 0)
				(type default)
			)
			(fill no)
			(layer "B.CrtYd")
		)
		(fp_rect
			(start 0.508 0.9398)
			(end -0.508 -0.9398)
			(stroke
				(width 0)
				(type default)
			)
			(fill no)
			(layer "B.Fab")
		)
		(pad "1" smd custom
			(at 0 -0.4445 90)
			(size 0.1397 0.1397)
			(layers "B.Cu" "B.Mask" "B.Paste")
			(net "I2C_BMC_COMP_SCL_R")
			(options
				(clearance outline)
				(anchor circle)
			)
			(primitives
				(gr_poly
					(pts
						(arc
							(start -0.1778 0.2794)
							(mid -0.249642 0.249642)
							(end -0.2794 0.1778)
						)
						(arc
							(start -0.2794 -0.1778)
							(mid -0.249642 -0.249642)
							(end -0.1778 -0.2794)
						)
						(arc
							(start 0.1778 -0.2794)
							(mid 0.249642 -0.249642)
							(end 0.2794 -0.1778)
						)
						(arc
							(start 0.2794 0.1778)
							(mid 0.249642 0.249642)
							(end 0.1778 0.2794)
						)
					)
					(width 0)
					(fill yes)
				)
			)
		)
		(pad "2" smd custom
			(at 0 0.4445 90)
			(size 0.1397 0.1397)
			(layers "B.Cu" "B.Mask" "B.Paste")
			(net "I2C_BMC_COMP_SCL")
			(options
				(clearance outline)
				(anchor circle)
			)
			(primitives
				(gr_poly
					(pts
						(arc
							(start -0.1778 0.2794)
							(mid -0.249642 0.249642)
							(end -0.2794 0.1778)
						)
						(arc
							(start -0.2794 -0.1778)
							(mid -0.249642 -0.249642)
							(end -0.1778 -0.2794)
						)
						(arc
							(start 0.1778 -0.2794)
							(mid 0.249642 -0.249642)
							(end 0.2794 -0.1778)
						)
						(arc
							(start 0.2794 0.1778)
							(mid 0.249642 0.249642)
							(end 0.1778 0.2794)
						)
					)
					(width 0)
					(fill yes)
				)
			)
		)
	)
	(footprint ""
		(layer "B.Cu")
		(at 40.884856 -182.948072)
		(property "Reference" "C178"
			(at 0 0 0)
			(layer "B.SilkS")
			(hide yes)
			(effects
				(font
					(size 1.27 1.27)
				)
				(justify mirror)
			)
		)
		(property "Value" "SCD1U50V3KX-GP"
			(at 0 -2.8194 0)
			(unlocked yes)
			(layer "B.Fab")
			(hide yes)
			(effects
				(font
					(size 1.016 1.016)
					(thickness 0.1524)
				)
				(justify mirror)
			)
		)
		(property "Device Type" "C603H36"
			(at 0 -4.3434 0)
			(unlocked yes)
			(layer "B.Fab")
			(hide yes)
			(effects
				(font
					(size 1.016 1.016)
					(thickness 0.1524)
				)
				(justify mirror)
			)
		)
		(duplicate_pad_numbers_are_jumpers no)
		(fp_line
			(start -0.508 0)
			(end 0.508 0)
			(stroke
				(width 0.2032)
				(type default)
			)
			(layer "B.SilkS")
		)
		(fp_rect
			(start 0.5842 1.3335)
			(end -0.5842 -1.3335)
			(stroke
				(width 0)
				(type default)
			)
			(fill no)
			(layer "B.CrtYd")
		)
		(fp_rect
			(start 0.5842 1.3335)
			(end -0.5842 -1.3335)
			(stroke
				(width 0)
				(type default)
			)
			(fill no)
			(layer "B.Fab")
		)
		(pad "1" smd custom
			(at 0 -0.762 180)
			(size 0.2159 0.2159)
			(layers "B.Cu" "B.Mask" "B.Paste")
			(net "P3V3_VBST_RC")
			(options
				(clearance outline)
				(anchor circle)
			)
			(primitives
				(gr_poly
					(pts
						(arc
							(start -0.3302 0.4318)
							(mid -0.402042 0.402042)
							(end -0.4318 0.3302)
						)
						(arc
							(start -0.4318 -0.3302)
							(mid -0.402042 -0.402042)
							(end -0.3302 -0.4318)
						)
						(arc
							(start 0.3302 -0.4318)
							(mid 0.402042 -0.402042)
							(end 0.4318 -0.3302)
						)
						(arc
							(start 0.4318 0.3302)
							(mid 0.402042 0.402042)
							(end 0.3302 0.4318)
						)
					)
					(width 0)
					(fill yes)
				)
			)
		)
		(pad "2" smd custom
			(at 0 0.762 180)
			(size 0.2159 0.2159)
			(layers "B.Cu" "B.Mask" "B.Paste")
			(net "P3V3_STBY_LL")
			(options
				(clearance outline)
				(anchor circle)
			)
			(primitives
				(gr_poly
					(pts
						(arc
							(start -0.3302 0.4318)
							(mid -0.402042 0.402042)
							(end -0.4318 0.3302)
						)
						(arc
							(start -0.4318 -0.3302)
							(mid -0.402042 -0.402042)
							(end -0.3302 -0.4318)
						)
						(arc
							(start 0.3302 -0.4318)
							(mid 0.402042 -0.402042)
							(end 0.4318 -0.3302)
						)
						(arc
							(start 0.4318 0.3302)
							(mid 0.402042 0.402042)
							(end 0.3302 0.4318)
						)
					)
					(width 0)
					(fill yes)
				)
			)
		)
	)
	(footprint ""
		(layer "B.Cu")
		(at 204.763624 -52.924202 -90)
		(property "Reference" "C340"
			(at 0 0 90)
			(layer "B.SilkS")
			(hide yes)
			(effects
				(font
					(size 1.27 1.27)
				)
				(justify mirror)
			)
		)
		(property "Value" "SC1U6D3V1MX-GP"
			(at -1.9177 2.0193 270)
			(unlocked yes)
			(layer "B.Fab")
			(hide yes)
			(effects
				(font
					(size 1.016 1.016)
					(thickness 0.1524)
				)
				(justify mirror)
			)
		)
		(property "Device Type" "C0201H14"
			(at -1.9177 0.4953 270)
			(unlocked yes)
			(layer "B.Fab")
			(hide yes)
			(effects
				(font
					(size 1.016 1.016)
					(thickness 0.1524)
				)
				(justify mirror)
			)
		)
		(duplicate_pad_numbers_are_jumpers no)
		(fp_rect
			(start 0.1524 0.3048)
			(end -0.1524 -0.3048)
			(stroke
				(width 0)
				(type default)
			)
			(fill no)
			(layer "B.CrtYd")
		)
		(fp_poly
			(pts
				(xy 0.2794 0.6477) (xy 0.2794 -0.6477) (xy -0.2794 -0.6477) (xy -0.2794 -0.1905) (xy -0.1524 -0.1905)
				(xy -0.1524 -0.3048) (xy 0.1524 -0.3048) (xy 0.1524 0.3048) (xy -0.1524 0.3048) (xy -0.1524 -0.1778)
				(xy -0.2794 -0.1778) (xy -0.2794 0.6477)
			)
			(stroke
				(width 0)
				(type default)
			)
			(fill no)
			(layer "B.CrtYd")
		)
		(fp_rect
			(start 0.2794 0.6477)
			(end -0.2794 -0.6477)
			(stroke
				(width 0)
				(type default)
			)
			(fill no)
			(layer "B.Fab")
		)
		(pad "1" smd custom
			(at 0 -0.2794 90)
			(size 0.0762 0.0762)
			(layers "B.Cu" "B.Mask" "B.Paste")
			(net "SHELL_PLL_VDD")
			(options
				(clearance outline)
				(anchor circle)
			)
			(primitives
				(gr_poly
					(pts
						(arc
							(start 0.1524 0.127)
							(mid 0.137521 0.162921)
							(end 0.1016 0.1778)
						)
						(arc
							(start -0.1016 0.1778)
							(mid -0.137521 0.162921)
							(end -0.1524 0.127)
						)
						(arc
							(start -0.1524 -0.127)
							(mid -0.137521 -0.162921)
							(end -0.1016 -0.1778)
						)
						(arc
							(start 0.1016 -0.1778)
							(mid 0.137521 -0.162921)
							(end 0.1524 -0.127)
						)
					)
					(width 0)
					(fill yes)
				)
			)
		)
		(pad "2" smd custom
			(at 0 0.2794 90)
			(size 0.0762 0.0762)
			(layers "B.Cu" "B.Mask" "B.Paste")
			(net "GND")
			(options
				(clearance outline)
				(anchor circle)
			)
			(primitives
				(gr_poly
					(pts
						(arc
							(start 0.1524 0.127)
							(mid 0.137521 0.162921)
							(end 0.1016 0.1778)
						)
						(arc
							(start -0.1016 0.1778)
							(mid -0.137521 0.162921)
							(end -0.1524 0.127)
						)
						(arc
							(start -0.1524 -0.127)
							(mid -0.137521 -0.162921)
							(end -0.1016 -0.1778)
						)
						(arc
							(start 0.1016 -0.1778)
							(mid 0.137521 -0.162921)
							(end 0.1524 -0.127)
						)
					)
					(width 0)
					(fill yes)
				)
			)
		)
	)
	(footprint ""
		(layer "B.Cu")
		(at 54.0766 -164.973 90)
		(property "Reference" "C124"
			(at 0 0 90)
			(layer "B.SilkS")
			(hide yes)
			(effects
				(font
					(size 1.27 1.27)
				)
				(justify mirror)
			)
		)
		(property "Value" "SCD1U25V2KX-2-GP"
			(at -1.1811 -2.7051 90)
			(unlocked yes)
			(layer "B.Fab")
			(hide yes)
			(effects
				(font
					(size 1.016 1.016)
					(thickness 0.1524)
				)
				(justify mirror)
			)
		)
		(property "Device Type" "C402H22"
			(at -1.1811 -4.2291 90)
			(unlocked yes)
			(layer "B.Fab")
			(hide yes)
			(effects
				(font
					(size 1.016 1.016)
					(thickness 0.1524)
				)
				(justify mirror)
			)
		)
		(duplicate_pad_numbers_are_jumpers no)
		(fp_rect
			(start 0.4318 0.9525)
			(end -0.4318 -0.9525)
			(stroke
				(width 0)
				(type default)
			)
			(fill no)
			(layer "B.CrtYd")
		)
		(fp_rect
			(start 0.4318 0.9525)
			(end -0.4318 -0.9525)
			(stroke
				(width 0)
				(type default)
			)
			(fill no)
			(layer "B.Fab")
		)
		(pad "1" smd custom
			(at 0 -0.4445 270)
			(size 0.1524 0.1524)
			(layers "B.Cu" "B.Mask" "B.Paste")
			(net "ADC_P0V975")
			(options
				(clearance outline)
				(anchor circle)
			)
			(primitives
				(gr_poly
					(pts
						(arc
							(start 0.3048 0.2032)
							(mid 0.275042 0.275042)
							(end 0.2032 0.3048)
						)
						(arc
							(start -0.2032 0.3048)
							(mid -0.275042 0.275042)
							(end -0.3048 0.2032)
						)
						(arc
							(start -0.3048 -0.2032)
							(mid -0.275042 -0.275042)
							(end -0.2032 -0.3048)
						)
						(arc
							(start 0.2032 -0.3048)
							(mid 0.275042 -0.275042)
							(end 0.3048 -0.2032)
						)
					)
					(width 0)
					(fill yes)
				)
			)
		)
		(pad "2" smd custom
			(at 0 0.4445 270)
			(size 0.1524 0.1524)
			(layers "B.Cu" "B.Mask" "B.Paste")
			(net "GND")
			(options
				(clearance outline)
				(anchor circle)
			)
			(primitives
				(gr_poly
					(pts
						(arc
							(start 0.3048 0.2032)
							(mid 0.275042 0.275042)
							(end 0.2032 0.3048)
						)
						(arc
							(start -0.2032 0.3048)
							(mid -0.275042 0.275042)
							(end -0.3048 0.2032)
						)
						(arc
							(start -0.3048 -0.2032)
							(mid -0.275042 -0.275042)
							(end -0.2032 -0.3048)
						)
						(arc
							(start 0.2032 -0.3048)
							(mid 0.275042 -0.275042)
							(end 0.3048 -0.2032)
						)
					)
					(width 0)
					(fill yes)
				)
			)
		)
	)
	(footprint ""
		(layer "B.Cu")
		(at 36.039298 -143.075914)
		(property "Reference" "C60"
			(at 0 0 0)
			(layer "B.SilkS")
			(hide yes)
			(effects
				(font
					(size 1.27 1.27)
				)
				(justify mirror)
			)
		)
		(property "Value" "SC1U16V3KX-5GP"
			(at 0 -2.8194 0)
			(unlocked yes)
			(layer "B.Fab")
			(hide yes)
			(effects
				(font
					(size 1.016 1.016)
					(thickness 0.1524)
				)
				(justify mirror)
			)
		)
		(property "Device Type" "C603H36"
			(at 0 -4.3434 0)
			(unlocked yes)
			(layer "B.Fab")
			(hide yes)
			(effects
				(font
					(size 1.016 1.016)
					(thickness 0.1524)
				)
				(justify mirror)
			)
		)
		(duplicate_pad_numbers_are_jumpers no)
		(fp_line
			(start -0.508 0)
			(end 0.508 0)
			(stroke
				(width 0.2032)
				(type default)
			)
			(layer "B.SilkS")
		)
		(fp_rect
			(start 0.5842 1.3335)
			(end -0.5842 -1.3335)
			(stroke
				(width 0)
				(type default)
			)
			(fill no)
			(layer "B.CrtYd")
		)
		(fp_rect
			(start 0.5842 1.3335)
			(end -0.5842 -1.3335)
			(stroke
				(width 0)
				(type default)
			)
			(fill no)
			(layer "B.Fab")
		)
		(pad "1" smd custom
			(at 0 -0.762 180)
			(size 0.2159 0.2159)
			(layers "B.Cu" "B.Mask" "B.Paste")
			(net "P1V2_STBY")
			(options
				(clearance outline)
				(anchor circle)
			)
			(primitives
				(gr_poly
					(pts
						(arc
							(start -0.3302 0.4318)
							(mid -0.402042 0.402042)
							(end -0.4318 0.3302)
						)
						(arc
							(start -0.4318 -0.3302)
							(mid -0.402042 -0.402042)
							(end -0.3302 -0.4318)
						)
						(arc
							(start 0.3302 -0.4318)
							(mid 0.402042 -0.402042)
							(end 0.4318 -0.3302)
						)
						(arc
							(start 0.4318 0.3302)
							(mid 0.402042 0.402042)
							(end 0.3302 0.4318)
						)
					)
					(width 0)
					(fill yes)
				)
			)
		)
		(pad "2" smd custom
			(at 0 0.762 180)
			(size 0.2159 0.2159)
			(layers "B.Cu" "B.Mask" "B.Paste")
			(net "GND")
			(options
				(clearance outline)
				(anchor circle)
			)
			(primitives
				(gr_poly
					(pts
						(arc
							(start -0.3302 0.4318)
							(mid -0.402042 0.402042)
							(end -0.4318 0.3302)
						)
						(arc
							(start -0.4318 -0.3302)
							(mid -0.402042 -0.402042)
							(end -0.3302 -0.4318)
						)
						(arc
							(start 0.3302 -0.4318)
							(mid 0.402042 -0.402042)
							(end 0.4318 -0.3302)
						)
						(arc
							(start 0.4318 0.3302)
							(mid 0.402042 0.402042)
							(end 0.3302 0.4318)
						)
					)
					(width 0)
					(fill yes)
				)
			)
		)
	)
	(footprint ""
		(layer "B.Cu")
		(at 193.9671 -63.2206 90)
		(property "Reference" "C403"
			(at 0 0 90)
			(layer "B.SilkS")
			(hide yes)
			(effects
				(font
					(size 1.27 1.27)
				)
				(justify mirror)
			)
		)
		(property "Value" "SCD1U6D3V1KX-GP"
			(at 2.8321 -1.7399 90)
			(unlocked yes)
			(layer "B.Fab")
			(hide yes)
			(effects
				(font
					(size 1.016 1.016)
					(thickness 0.1524)
				)
				(justify mirror)
			)
		)
		(property "Device Type" "C0201H13"
			(at 2.8321 -3.2639 90)
			(unlocked yes)
			(layer "B.Fab")
			(hide yes)
			(effects
				(font
					(size 1.016 1.016)
					(thickness 0.1524)
				)
				(justify mirror)
			)
		)
		(duplicate_pad_numbers_are_jumpers no)
		(fp_rect
			(start 0.2794 0.6477)
			(end -0.2794 -0.6477)
			(stroke
				(width 0)
				(type default)
			)
			(fill no)
			(layer "B.CrtYd")
		)
		(fp_rect
			(start 0.2794 0.6477)
			(end -0.2794 -0.6477)
			(stroke
				(width 0)
				(type default)
			)
			(fill no)
			(layer "B.Fab")
		)
		(pad "1" smd custom
			(at 0 -0.2794 270)
			(size 0.0762 0.0762)
			(layers "B.Cu" "B.Mask" "B.Paste")
			(net "P0V975")
			(options
				(clearance outline)
				(anchor circle)
			)
			(primitives
				(gr_poly
					(pts
						(arc
							(start 0.1524 0.127)
							(mid 0.137521 0.162921)
							(end 0.1016 0.1778)
						)
						(arc
							(start -0.1016 0.1778)
							(mid -0.137521 0.162921)
							(end -0.1524 0.127)
						)
						(arc
							(start -0.1524 -0.127)
							(mid -0.137521 -0.162921)
							(end -0.1016 -0.1778)
						)
						(arc
							(start 0.1016 -0.1778)
							(mid 0.137521 -0.162921)
							(end 0.1524 -0.127)
						)
					)
					(width 0)
					(fill yes)
				)
			)
		)
		(pad "2" smd custom
			(at 0 0.2794 270)
			(size 0.0762 0.0762)
			(layers "B.Cu" "B.Mask" "B.Paste")
			(net "GND")
			(options
				(clearance outline)
				(anchor circle)
			)
			(primitives
				(gr_poly
					(pts
						(arc
							(start 0.1524 0.127)
							(mid 0.137521 0.162921)
							(end 0.1016 0.1778)
						)
						(arc
							(start -0.1016 0.1778)
							(mid -0.137521 0.162921)
							(end -0.1524 0.127)
						)
						(arc
							(start -0.1524 -0.127)
							(mid -0.137521 -0.162921)
							(end -0.1016 -0.1778)
						)
						(arc
							(start 0.1016 -0.1778)
							(mid 0.137521 -0.162921)
							(end 0.1524 -0.127)
						)
					)
					(width 0)
					(fill yes)
				)
			)
		)
	)
	(footprint ""
		(layer "B.Cu")
		(at 96.980756 -159.78632 90)
		(property "Reference" "C8"
			(at 0 0 90)
			(layer "B.SilkS")
			(hide yes)
			(effects
				(font
					(size 1.27 1.27)
				)
				(justify mirror)
			)
		)
		(property "Value" "SC1U16V3KX-5GP"
			(at 0 -2.8194 90)
			(unlocked yes)
			(layer "B.Fab")
			(hide yes)
			(effects
				(font
					(size 1.016 1.016)
					(thickness 0.1524)
				)
				(justify mirror)
			)
		)
		(property "Device Type" "C603H36"
			(at 0 -4.3434 90)
			(unlocked yes)
			(layer "B.Fab")
			(hide yes)
			(effects
				(font
					(size 1.016 1.016)
					(thickness 0.1524)
				)
				(justify mirror)
			)
		)
		(duplicate_pad_numbers_are_jumpers no)
		(fp_line
			(start -0.508 0)
			(end 0.508 0)
			(stroke
				(width 0.2032)
				(type default)
			)
			(layer "B.SilkS")
		)
		(fp_rect
			(start 0.5842 1.3335)
			(end -0.5842 -1.3335)
			(stroke
				(width 0)
				(type default)
			)
			(fill no)
			(layer "B.CrtYd")
		)
		(fp_rect
			(start 0.5842 1.3335)
			(end -0.5842 -1.3335)
			(stroke
				(width 0)
				(type default)
			)
			(fill no)
			(layer "B.Fab")
		)
		(pad "1" smd custom
			(at 0 -0.762 270)
			(size 0.2159 0.2159)
			(layers "B.Cu" "B.Mask" "B.Paste")
			(net "USB_RESET_N")
			(options
				(clearance outline)
				(anchor circle)
			)
			(primitives
				(gr_poly
					(pts
						(arc
							(start -0.3302 0.4318)
							(mid -0.402042 0.402042)
							(end -0.4318 0.3302)
						)
						(arc
							(start -0.4318 -0.3302)
							(mid -0.402042 -0.402042)
							(end -0.3302 -0.4318)
						)
						(arc
							(start 0.3302 -0.4318)
							(mid 0.402042 -0.402042)
							(end 0.4318 -0.3302)
						)
						(arc
							(start 0.4318 0.3302)
							(mid 0.402042 0.402042)
							(end 0.3302 0.4318)
						)
					)
					(width 0)
					(fill yes)
				)
			)
		)
		(pad "2" smd custom
			(at 0 0.762 270)
			(size 0.2159 0.2159)
			(layers "B.Cu" "B.Mask" "B.Paste")
			(net "GND")
			(options
				(clearance outline)
				(anchor circle)
			)
			(primitives
				(gr_poly
					(pts
						(arc
							(start -0.3302 0.4318)
							(mid -0.402042 0.402042)
							(end -0.4318 0.3302)
						)
						(arc
							(start -0.4318 -0.3302)
							(mid -0.402042 -0.402042)
							(end -0.3302 -0.4318)
						)
						(arc
							(start 0.3302 -0.4318)
							(mid 0.402042 -0.402042)
							(end 0.4318 -0.3302)
						)
						(arc
							(start 0.4318 0.3302)
							(mid 0.402042 0.402042)
							(end 0.3302 0.4318)
						)
					)
					(width 0)
					(fill yes)
				)
			)
		)
	)
	(footprint ""
		(layer "B.Cu")
		(at 204.778864 -52.33543 -90)
		(property "Reference" "C341"
			(at 0 0 90)
			(layer "B.SilkS")
			(hide yes)
			(effects
				(font
					(size 1.27 1.27)
				)
				(justify mirror)
			)
		)
		(property "Value" "SCD1U6D3V1KX-GP"
			(at 2.8321 -1.7399 270)
			(unlocked yes)
			(layer "B.Fab")
			(hide yes)
			(effects
				(font
					(size 1.016 1.016)
					(thickness 0.1524)
				)
				(justify mirror)
			)
		)
		(property "Device Type" "C0201H13"
			(at 2.8321 -3.2639 270)
			(unlocked yes)
			(layer "B.Fab")
			(hide yes)
			(effects
				(font
					(size 1.016 1.016)
					(thickness 0.1524)
				)
				(justify mirror)
			)
		)
		(duplicate_pad_numbers_are_jumpers no)
		(fp_rect
			(start 0.2794 0.6477)
			(end -0.2794 -0.6477)
			(stroke
				(width 0)
				(type default)
			)
			(fill no)
			(layer "B.CrtYd")
		)
		(fp_rect
			(start 0.2794 0.6477)
			(end -0.2794 -0.6477)
			(stroke
				(width 0)
				(type default)
			)
			(fill no)
			(layer "B.Fab")
		)
		(pad "1" smd custom
			(at 0 -0.2794 90)
			(size 0.0762 0.0762)
			(layers "B.Cu" "B.Mask" "B.Paste")
			(net "SHELL_PLL_VDD")
			(options
				(clearance outline)
				(anchor circle)
			)
			(primitives
				(gr_poly
					(pts
						(arc
							(start 0.1524 0.127)
							(mid 0.137521 0.162921)
							(end 0.1016 0.1778)
						)
						(arc
							(start -0.1016 0.1778)
							(mid -0.137521 0.162921)
							(end -0.1524 0.127)
						)
						(arc
							(start -0.1524 -0.127)
							(mid -0.137521 -0.162921)
							(end -0.1016 -0.1778)
						)
						(arc
							(start 0.1016 -0.1778)
							(mid 0.137521 -0.162921)
							(end 0.1524 -0.127)
						)
					)
					(width 0)
					(fill yes)
				)
			)
		)
		(pad "2" smd custom
			(at 0 0.2794 90)
			(size 0.0762 0.0762)
			(layers "B.Cu" "B.Mask" "B.Paste")
			(net "GND")
			(options
				(clearance outline)
				(anchor circle)
			)
			(primitives
				(gr_poly
					(pts
						(arc
							(start 0.1524 0.127)
							(mid 0.137521 0.162921)
							(end 0.1016 0.1778)
						)
						(arc
							(start -0.1016 0.1778)
							(mid -0.137521 0.162921)
							(end -0.1524 0.127)
						)
						(arc
							(start -0.1524 -0.127)
							(mid -0.137521 -0.162921)
							(end -0.1016 -0.1778)
						)
						(arc
							(start 0.1016 -0.1778)
							(mid 0.137521 -0.162921)
							(end 0.1524 -0.127)
						)
					)
					(width 0)
					(fill yes)
				)
			)
		)
	)
	(footprint ""
		(layer "B.Cu")
		(at 51.74996 -158.69412 90)
		(property "Reference" "R192"
			(at 0 0 90)
			(layer "B.SilkS")
			(hide yes)
			(effects
				(font
					(size 1.27 1.27)
				)
				(justify mirror)
			)
		)
		(property "Value" "2K2R2F-GP"
			(at -0.064008 -3.993896 90)
			(unlocked yes)
			(layer "B.Fab")
			(hide yes)
			(effects
				(font
					(size 1.016 1.016)
					(thickness 0.1524)
				)
				(justify mirror)
			)
		)
		(property "Device Type" "R402H16"
			(at -0.064008 -5.517896 90)
			(unlocked yes)
			(layer "B.Fab")
			(hide yes)
			(effects
				(font
					(size 1.016 1.016)
					(thickness 0.1524)
				)
				(justify mirror)
			)
		)
		(duplicate_pad_numbers_are_jumpers no)
		(fp_line
			(start 0.508 -0.9398)
			(end 0.508 0.9398)
			(stroke
				(width 0.1524)
				(type default)
			)
			(layer "B.SilkS")
		)
		(fp_line
			(start -0.508 -0.9398)
			(end 0.508 -0.9398)
			(stroke
				(width 0.1524)
				(type default)
			)
			(layer "B.SilkS")
		)
		(fp_rect
			(start 0.508 0.9398)
			(end -0.508 -0.9398)
			(stroke
				(width 0)
				(type default)
			)
			(fill no)
			(layer "B.CrtYd")
		)
		(fp_rect
			(start 0.508 0.9398)
			(end -0.508 -0.9398)
			(stroke
				(width 0)
				(type default)
			)
			(fill no)
			(layer "B.Fab")
		)
		(pad "1" smd custom
			(at 0 -0.4445 270)
			(size 0.1397 0.1397)
			(layers "B.Cu" "B.Mask" "B.Paste")
			(net "I2C_MEZZ_OOB_SDA")
			(options
				(clearance outline)
				(anchor circle)
			)
			(primitives
				(gr_poly
					(pts
						(arc
							(start -0.1778 0.2794)
							(mid -0.249642 0.249642)
							(end -0.2794 0.1778)
						)
						(arc
							(start -0.2794 -0.1778)
							(mid -0.249642 -0.249642)
							(end -0.1778 -0.2794)
						)
						(arc
							(start 0.1778 -0.2794)
							(mid 0.249642 -0.249642)
							(end 0.2794 -0.1778)
						)
						(arc
							(start 0.2794 0.1778)
							(mid 0.249642 0.249642)
							(end 0.1778 0.2794)
						)
					)
					(width 0)
					(fill yes)
				)
			)
		)
		(pad "2" smd custom
			(at 0 0.4445 270)
			(size 0.1397 0.1397)
			(layers "B.Cu" "B.Mask" "B.Paste")
			(net "P3V3_STBY")
			(options
				(clearance outline)
				(anchor circle)
			)
			(primitives
				(gr_poly
					(pts
						(arc
							(start -0.1778 0.2794)
							(mid -0.249642 0.249642)
							(end -0.2794 0.1778)
						)
						(arc
							(start -0.2794 -0.1778)
							(mid -0.249642 -0.249642)
							(end -0.1778 -0.2794)
						)
						(arc
							(start 0.1778 -0.2794)
							(mid 0.249642 -0.249642)
							(end 0.2794 -0.1778)
						)
						(arc
							(start 0.2794 0.1778)
							(mid 0.249642 0.249642)
							(end 0.1778 0.2794)
						)
					)
					(width 0)
					(fill yes)
				)
			)
		)
	)
	(footprint ""
		(layer "B.Cu")
		(at 44.139866 -148.180298 -90)
		(property "Reference" "C55"
			(at 0 0 90)
			(layer "B.SilkS")
			(hide yes)
			(effects
				(font
					(size 1.27 1.27)
				)
				(justify mirror)
			)
		)
		(property "Value" "SCD1U16V2KX-3GP"
			(at -1.1811 -2.7051 270)
			(unlocked yes)
			(layer "B.Fab")
			(hide yes)
			(effects
				(font
					(size 1.016 1.016)
					(thickness 0.1524)
				)
				(justify mirror)
			)
		)
		(property "Device Type" "C402H22"
			(at -1.1811 -4.2291 270)
			(unlocked yes)
			(layer "B.Fab")
			(hide yes)
			(effects
				(font
					(size 1.016 1.016)
					(thickness 0.1524)
				)
				(justify mirror)
			)
		)
		(duplicate_pad_numbers_are_jumpers no)
		(fp_rect
			(start 0.4318 0.9525)
			(end -0.4318 -0.9525)
			(stroke
				(width 0)
				(type default)
			)
			(fill no)
			(layer "B.CrtYd")
		)
		(fp_rect
			(start 0.4318 0.9525)
			(end -0.4318 -0.9525)
			(stroke
				(width 0)
				(type default)
			)
			(fill no)
			(layer "B.Fab")
		)
		(pad "1" smd custom
			(at 0 -0.4445 90)
			(size 0.1524 0.1524)
			(layers "B.Cu" "B.Mask" "B.Paste")
			(net "GND")
			(options
				(clearance outline)
				(anchor circle)
			)
			(primitives
				(gr_poly
					(pts
						(arc
							(start 0.3048 0.2032)
							(mid 0.275042 0.275042)
							(end 0.2032 0.3048)
						)
						(arc
							(start -0.2032 0.3048)
							(mid -0.275042 0.275042)
							(end -0.3048 0.2032)
						)
						(arc
							(start -0.3048 -0.2032)
							(mid -0.275042 -0.275042)
							(end -0.2032 -0.3048)
						)
						(arc
							(start 0.2032 -0.3048)
							(mid 0.275042 -0.275042)
							(end 0.3048 -0.2032)
						)
					)
					(width 0)
					(fill yes)
				)
			)
		)
		(pad "2" smd custom
			(at 0 0.4445 90)
			(size 0.1524 0.1524)
			(layers "B.Cu" "B.Mask" "B.Paste")
			(net "DDR_VREF")
			(options
				(clearance outline)
				(anchor circle)
			)
			(primitives
				(gr_poly
					(pts
						(arc
							(start 0.3048 0.2032)
							(mid 0.275042 0.275042)
							(end 0.2032 0.3048)
						)
						(arc
							(start -0.2032 0.3048)
							(mid -0.275042 0.275042)
							(end -0.3048 0.2032)
						)
						(arc
							(start -0.3048 -0.2032)
							(mid -0.275042 -0.275042)
							(end -0.2032 -0.3048)
						)
						(arc
							(start 0.2032 -0.3048)
							(mid 0.275042 -0.275042)
							(end 0.3048 -0.2032)
						)
					)
					(width 0)
					(fill yes)
				)
			)
		)
	)
	(footprint ""
		(layer "B.Cu")
		(at 22.014942 -129.1082 180)
		(property "Reference" "R260"
			(at 0 0 0)
			(layer "B.SilkS")
			(hide yes)
			(effects
				(font
					(size 1.27 1.27)
				)
				(justify mirror)
			)
		)
		(property "Value" "120R2F-GP"
			(at -0.064008 -3.993896 180)
			(unlocked yes)
			(layer "B.Fab")
			(hide yes)
			(effects
				(font
					(size 1.016 1.016)
					(thickness 0.1524)
				)
				(justify mirror)
			)
		)
		(property "Device Type" "R402H16"
			(at -0.064008 -5.517896 180)
			(unlocked yes)
			(layer "B.Fab")
			(hide yes)
			(effects
				(font
					(size 1.016 1.016)
					(thickness 0.1524)
				)
				(justify mirror)
			)
		)
		(duplicate_pad_numbers_are_jumpers no)
		(fp_line
			(start 0.508 -0.9398)
			(end 0.508 0.9398)
			(stroke
				(width 0.1524)
				(type default)
			)
			(layer "B.SilkS")
		)
		(fp_line
			(start -0.508 -0.9398)
			(end 0.508 -0.9398)
			(stroke
				(width 0.1524)
				(type default)
			)
			(layer "B.SilkS")
		)
		(fp_rect
			(start 0.508 0.9398)
			(end -0.508 -0.9398)
			(stroke
				(width 0)
				(type default)
			)
			(fill no)
			(layer "B.CrtYd")
		)
		(fp_rect
			(start 0.508 0.9398)
			(end -0.508 -0.9398)
			(stroke
				(width 0)
				(type default)
			)
			(fill no)
			(layer "B.Fab")
		)
		(pad "1" smd custom
			(at 0 -0.4445)
			(size 0.1397 0.1397)
			(layers "B.Cu" "B.Mask" "B.Paste")
			(net "GND")
			(options
				(clearance outline)
				(anchor circle)
			)
			(primitives
				(gr_poly
					(pts
						(arc
							(start -0.1778 0.2794)
							(mid -0.249642 0.249642)
							(end -0.2794 0.1778)
						)
						(arc
							(start -0.2794 -0.1778)
							(mid -0.249642 -0.249642)
							(end -0.1778 -0.2794)
						)
						(arc
							(start 0.1778 -0.2794)
							(mid 0.249642 -0.249642)
							(end 0.2794 -0.1778)
						)
						(arc
							(start 0.2794 0.1778)
							(mid 0.249642 0.249642)
							(end 0.1778 0.2794)
						)
					)
					(width 0)
					(fill yes)
				)
			)
		)
		(pad "2" smd custom
			(at 0 0.4445)
			(size 0.1397 0.1397)
			(layers "B.Cu" "B.Mask" "B.Paste")
			(net "MEMA_13")
			(options
				(clearance outline)
				(anchor circle)
			)
			(primitives
				(gr_poly
					(pts
						(arc
							(start -0.1778 0.2794)
							(mid -0.249642 0.249642)
							(end -0.2794 0.1778)
						)
						(arc
							(start -0.2794 -0.1778)
							(mid -0.249642 -0.249642)
							(end -0.1778 -0.2794)
						)
						(arc
							(start 0.1778 -0.2794)
							(mid 0.249642 -0.249642)
							(end 0.2794 -0.1778)
						)
						(arc
							(start 0.2794 0.1778)
							(mid 0.249642 0.249642)
							(end 0.1778 0.2794)
						)
					)
					(width 0)
					(fill yes)
				)
			)
		)
	)
	(footprint ""
		(layer "B.Cu")
		(at 49.6316 -132.6642)
		(property "Reference" "C110"
			(at 0 0 0)
			(layer "B.SilkS")
			(hide yes)
			(effects
				(font
					(size 1.27 1.27)
				)
				(justify mirror)
			)
		)
		(property "Value" "SC1U16V3KX-5GP"
			(at 0 -2.8194 0)
			(unlocked yes)
			(layer "B.Fab")
			(hide yes)
			(effects
				(font
					(size 1.016 1.016)
					(thickness 0.1524)
				)
				(justify mirror)
			)
		)
		(property "Device Type" "C603H36"
			(at 0 -4.3434 0)
			(unlocked yes)
			(layer "B.Fab")
			(hide yes)
			(effects
				(font
					(size 1.016 1.016)
					(thickness 0.1524)
				)
				(justify mirror)
			)
		)
		(duplicate_pad_numbers_are_jumpers no)
		(fp_line
			(start -0.508 0)
			(end 0.508 0)
			(stroke
				(width 0.2032)
				(type default)
			)
			(layer "B.SilkS")
		)
		(fp_rect
			(start 0.5842 1.3335)
			(end -0.5842 -1.3335)
			(stroke
				(width 0)
				(type default)
			)
			(fill no)
			(layer "B.CrtYd")
		)
		(fp_rect
			(start 0.5842 1.3335)
			(end -0.5842 -1.3335)
			(stroke
				(width 0)
				(type default)
			)
			(fill no)
			(layer "B.Fab")
		)
		(pad "1" smd custom
			(at 0 -0.762 180)
			(size 0.2159 0.2159)
			(layers "B.Cu" "B.Mask" "B.Paste")
			(net "P1V15_STBY")
			(options
				(clearance outline)
				(anchor circle)
			)
			(primitives
				(gr_poly
					(pts
						(arc
							(start -0.3302 0.4318)
							(mid -0.402042 0.402042)
							(end -0.4318 0.3302)
						)
						(arc
							(start -0.4318 -0.3302)
							(mid -0.402042 -0.402042)
							(end -0.3302 -0.4318)
						)
						(arc
							(start 0.3302 -0.4318)
							(mid 0.402042 -0.402042)
							(end 0.4318 -0.3302)
						)
						(arc
							(start 0.4318 0.3302)
							(mid 0.402042 0.402042)
							(end 0.3302 0.4318)
						)
					)
					(width 0)
					(fill yes)
				)
			)
		)
		(pad "2" smd custom
			(at 0 0.762 180)
			(size 0.2159 0.2159)
			(layers "B.Cu" "B.Mask" "B.Paste")
			(net "GND")
			(options
				(clearance outline)
				(anchor circle)
			)
			(primitives
				(gr_poly
					(pts
						(arc
							(start -0.3302 0.4318)
							(mid -0.402042 0.402042)
							(end -0.4318 0.3302)
						)
						(arc
							(start -0.4318 -0.3302)
							(mid -0.402042 -0.402042)
							(end -0.3302 -0.4318)
						)
						(arc
							(start 0.3302 -0.4318)
							(mid 0.402042 -0.402042)
							(end 0.4318 -0.3302)
						)
						(arc
							(start 0.4318 0.3302)
							(mid 0.402042 0.402042)
							(end 0.3302 0.4318)
						)
					)
					(width 0)
					(fill yes)
				)
			)
		)
	)
	(footprint ""
		(layer "B.Cu")
		(at 12.11199 -139.579604 90)
		(property "Reference" "R234"
			(at 0 0 90)
			(layer "B.SilkS")
			(hide yes)
			(effects
				(font
					(size 1.27 1.27)
				)
				(justify mirror)
			)
		)
		(property "Value" "120R2F-GP"
			(at -0.064008 -3.993896 90)
			(unlocked yes)
			(layer "B.Fab")
			(hide yes)
			(effects
				(font
					(size 1.016 1.016)
					(thickness 0.1524)
				)
				(justify mirror)
			)
		)
		(property "Device Type" "R402H16"
			(at -0.064008 -5.517896 90)
			(unlocked yes)
			(layer "B.Fab")
			(hide yes)
			(effects
				(font
					(size 1.016 1.016)
					(thickness 0.1524)
				)
				(justify mirror)
			)
		)
		(duplicate_pad_numbers_are_jumpers no)
		(fp_line
			(start 0.508 -0.9398)
			(end 0.508 0.9398)
			(stroke
				(width 0.1524)
				(type default)
			)
			(layer "B.SilkS")
		)
		(fp_line
			(start -0.508 -0.9398)
			(end 0.508 -0.9398)
			(stroke
				(width 0.1524)
				(type default)
			)
			(layer "B.SilkS")
		)
		(fp_rect
			(start 0.508 0.9398)
			(end -0.508 -0.9398)
			(stroke
				(width 0)
				(type default)
			)
			(fill no)
			(layer "B.CrtYd")
		)
		(fp_rect
			(start 0.508 0.9398)
			(end -0.508 -0.9398)
			(stroke
				(width 0)
				(type default)
			)
			(fill no)
			(layer "B.Fab")
		)
		(pad "1" smd custom
			(at 0 -0.4445 270)
			(size 0.1397 0.1397)
			(layers "B.Cu" "B.Mask" "B.Paste")
			(net "MEMA_0")
			(options
				(clearance outline)
				(anchor circle)
			)
			(primitives
				(gr_poly
					(pts
						(arc
							(start -0.1778 0.2794)
							(mid -0.249642 0.249642)
							(end -0.2794 0.1778)
						)
						(arc
							(start -0.2794 -0.1778)
							(mid -0.249642 -0.249642)
							(end -0.1778 -0.2794)
						)
						(arc
							(start 0.1778 -0.2794)
							(mid 0.249642 -0.249642)
							(end 0.2794 -0.1778)
						)
						(arc
							(start 0.2794 0.1778)
							(mid 0.249642 0.249642)
							(end 0.1778 0.2794)
						)
					)
					(width 0)
					(fill yes)
				)
			)
		)
		(pad "2" smd custom
			(at 0 0.4445 270)
			(size 0.1397 0.1397)
			(layers "B.Cu" "B.Mask" "B.Paste")
			(net "P1V2_STBY")
			(options
				(clearance outline)
				(anchor circle)
			)
			(primitives
				(gr_poly
					(pts
						(arc
							(start -0.1778 0.2794)
							(mid -0.249642 0.249642)
							(end -0.2794 0.1778)
						)
						(arc
							(start -0.2794 -0.1778)
							(mid -0.249642 -0.249642)
							(end -0.1778 -0.2794)
						)
						(arc
							(start 0.1778 -0.2794)
							(mid 0.249642 -0.249642)
							(end 0.2794 -0.1778)
						)
						(arc
							(start 0.2794 0.1778)
							(mid 0.249642 0.249642)
							(end 0.1778 0.2794)
						)
					)
					(width 0)
					(fill yes)
				)
			)
		)
	)
	(footprint ""
		(layer "B.Cu")
		(at 204.4446 -69.5452 90)
		(property "Reference" "C379"
			(at 0 0 90)
			(layer "B.SilkS")
			(hide yes)
			(effects
				(font
					(size 1.27 1.27)
				)
				(justify mirror)
			)
		)
		(property "Value" "SCD1U6D3V1KX-GP"
			(at 2.8321 -1.7399 90)
			(unlocked yes)
			(layer "B.Fab")
			(hide yes)
			(effects
				(font
					(size 1.016 1.016)
					(thickness 0.1524)
				)
				(justify mirror)
			)
		)
		(property "Device Type" "C0201H13"
			(at 2.8321 -3.2639 90)
			(unlocked yes)
			(layer "B.Fab")
			(hide yes)
			(effects
				(font
					(size 1.016 1.016)
					(thickness 0.1524)
				)
				(justify mirror)
			)
		)
		(duplicate_pad_numbers_are_jumpers no)
		(fp_rect
			(start 0.2794 0.6477)
			(end -0.2794 -0.6477)
			(stroke
				(width 0)
				(type default)
			)
			(fill no)
			(layer "B.CrtYd")
		)
		(fp_rect
			(start 0.2794 0.6477)
			(end -0.2794 -0.6477)
			(stroke
				(width 0)
				(type default)
			)
			(fill no)
			(layer "B.Fab")
		)
		(pad "1" smd custom
			(at 0 -0.2794 270)
			(size 0.0762 0.0762)
			(layers "B.Cu" "B.Mask" "B.Paste")
			(net "SAS0_AVDD")
			(options
				(clearance outline)
				(anchor circle)
			)
			(primitives
				(gr_poly
					(pts
						(arc
							(start 0.1524 0.127)
							(mid 0.137521 0.162921)
							(end 0.1016 0.1778)
						)
						(arc
							(start -0.1016 0.1778)
							(mid -0.137521 0.162921)
							(end -0.1524 0.127)
						)
						(arc
							(start -0.1524 -0.127)
							(mid -0.137521 -0.162921)
							(end -0.1016 -0.1778)
						)
						(arc
							(start 0.1016 -0.1778)
							(mid 0.137521 -0.162921)
							(end 0.1524 -0.127)
						)
					)
					(width 0)
					(fill yes)
				)
			)
		)
		(pad "2" smd custom
			(at 0 0.2794 270)
			(size 0.0762 0.0762)
			(layers "B.Cu" "B.Mask" "B.Paste")
			(net "GND")
			(options
				(clearance outline)
				(anchor circle)
			)
			(primitives
				(gr_poly
					(pts
						(arc
							(start 0.1524 0.127)
							(mid 0.137521 0.162921)
							(end 0.1016 0.1778)
						)
						(arc
							(start -0.1016 0.1778)
							(mid -0.137521 0.162921)
							(end -0.1524 0.127)
						)
						(arc
							(start -0.1524 -0.127)
							(mid -0.137521 -0.162921)
							(end -0.1016 -0.1778)
						)
						(arc
							(start 0.1016 -0.1778)
							(mid 0.137521 -0.162921)
							(end 0.1524 -0.127)
						)
					)
					(width 0)
					(fill yes)
				)
			)
		)
	)
	(footprint ""
		(layer "B.Cu")
		(at 91.8972 -152.8318 180)
		(property "Reference" "C10"
			(at 0 0 0)
			(layer "B.SilkS")
			(hide yes)
			(effects
				(font
					(size 1.27 1.27)
				)
				(justify mirror)
			)
		)
		(property "Value" "SC1U16V2KX-7-GP"
			(at -1.7526 -1.6002 180)
			(unlocked yes)
			(layer "B.Fab")
			(hide yes)
			(effects
				(font
					(size 1.016 1.016)
					(thickness 0.1524)
				)
				(justify mirror)
			)
		)
		(property "Device Type" "C402-TO0D2H24"
			(at -1.7526 -3.1242 180)
			(unlocked yes)
			(layer "B.Fab")
			(hide yes)
			(effects
				(font
					(size 1.016 1.016)
					(thickness 0.1524)
				)
				(justify mirror)
			)
		)
		(duplicate_pad_numbers_are_jumpers no)
		(fp_rect
			(start 0.4826 0.889)
			(end -0.4826 -0.889)
			(stroke
				(width 0)
				(type default)
			)
			(fill no)
			(layer "B.CrtYd")
		)
		(fp_rect
			(start 0.4826 0.889)
			(end -0.4826 -0.889)
			(stroke
				(width 0)
				(type default)
			)
			(fill no)
			(layer "B.Fab")
		)
		(pad "1" smd custom
			(at 0 -0.4572)
			(size 0.1524 0.1524)
			(layers "B.Cu" "B.Mask" "B.Paste")
			(net "P3V3_STBY")
			(options
				(clearance outline)
				(anchor circle)
			)
			(primitives
				(gr_poly
					(pts
						(arc
							(start -0.254 -0.3048)
							(mid -0.325842 -0.275042)
							(end -0.3556 -0.2032)
						)
						(arc
							(start -0.3556 0.2032)
							(mid -0.325842 0.275042)
							(end -0.254 0.3048)
						)
						(arc
							(start 0.254 0.3048)
							(mid 0.325842 0.275042)
							(end 0.3556 0.2032)
						)
						(arc
							(start 0.3556 -0.2032)
							(mid 0.325842 -0.275042)
							(end 0.254 -0.3048)
						)
					)
					(width 0)
					(fill yes)
				)
			)
		)
		(pad "2" smd custom
			(at 0 0.4572)
			(size 0.1524 0.1524)
			(layers "B.Cu" "B.Mask" "B.Paste")
			(net "GND")
			(options
				(clearance outline)
				(anchor circle)
			)
			(primitives
				(gr_poly
					(pts
						(arc
							(start -0.254 -0.3048)
							(mid -0.325842 -0.275042)
							(end -0.3556 -0.2032)
						)
						(arc
							(start -0.3556 0.2032)
							(mid -0.325842 0.275042)
							(end -0.254 0.3048)
						)
						(arc
							(start 0.254 0.3048)
							(mid 0.325842 0.275042)
							(end 0.3556 0.2032)
						)
						(arc
							(start 0.3556 -0.2032)
							(mid 0.325842 -0.275042)
							(end 0.254 -0.3048)
						)
					)
					(width 0)
					(fill yes)
				)
			)
		)
	)
	(footprint ""
		(layer "B.Cu")
		(at 95.377 -179.324)
		(property "Reference" "R101"
			(at 0 0 0)
			(layer "B.SilkS")
			(hide yes)
			(effects
				(font
					(size 1.27 1.27)
				)
				(justify mirror)
			)
		)
		(property "Value" "0R2J-2-GP"
			(at -0.064008 -3.993896 0)
			(unlocked yes)
			(layer "B.Fab")
			(hide yes)
			(effects
				(font
					(size 1.016 1.016)
					(thickness 0.1524)
				)
				(justify mirror)
			)
		)
		(property "Device Type" "R402H16"
			(at -0.064008 -5.517896 0)
			(unlocked yes)
			(layer "B.Fab")
			(hide yes)
			(effects
				(font
					(size 1.016 1.016)
					(thickness 0.1524)
				)
				(justify mirror)
			)
		)
		(duplicate_pad_numbers_are_jumpers no)
		(fp_line
			(start -0.508 -0.9398)
			(end 0.508 -0.9398)
			(stroke
				(width 0.1524)
				(type default)
			)
			(layer "B.SilkS")
		)
		(fp_line
			(start 0.508 -0.9398)
			(end 0.508 0.9398)
			(stroke
				(width 0.1524)
				(type default)
			)
			(layer "B.SilkS")
		)
		(fp_rect
			(start 0.508 0.9398)
			(end -0.508 -0.9398)
			(stroke
				(width 0)
				(type default)
			)
			(fill no)
			(layer "B.CrtYd")
		)
		(fp_rect
			(start 0.508 0.9398)
			(end -0.508 -0.9398)
			(stroke
				(width 0)
				(type default)
			)
			(fill no)
			(layer "B.Fab")
		)
		(pad "1" smd custom
			(at 0 -0.4445 180)
			(size 0.1397 0.1397)
			(layers "B.Cu" "B.Mask" "B.Paste")
			(net "I2C_COMP_ALERT_N")
			(options
				(clearance outline)
				(anchor circle)
			)
			(primitives
				(gr_poly
					(pts
						(arc
							(start -0.1778 0.2794)
							(mid -0.249642 0.249642)
							(end -0.2794 0.1778)
						)
						(arc
							(start -0.2794 -0.1778)
							(mid -0.249642 -0.249642)
							(end -0.1778 -0.2794)
						)
						(arc
							(start 0.1778 -0.2794)
							(mid 0.249642 -0.249642)
							(end 0.2794 -0.1778)
						)
						(arc
							(start 0.2794 0.1778)
							(mid 0.249642 0.249642)
							(end 0.1778 0.2794)
						)
					)
					(width 0)
					(fill yes)
				)
			)
		)
		(pad "2" smd custom
			(at 0 0.4445 180)
			(size 0.1397 0.1397)
			(layers "B.Cu" "B.Mask" "B.Paste")
			(net "I2C_BMC_COMP_ALERT_N_R")
			(options
				(clearance outline)
				(anchor circle)
			)
			(primitives
				(gr_poly
					(pts
						(arc
							(start -0.1778 0.2794)
							(mid -0.249642 0.249642)
							(end -0.2794 0.1778)
						)
						(arc
							(start -0.2794 -0.1778)
							(mid -0.249642 -0.249642)
							(end -0.1778 -0.2794)
						)
						(arc
							(start 0.1778 -0.2794)
							(mid 0.249642 -0.249642)
							(end 0.2794 -0.1778)
						)
						(arc
							(start 0.2794 0.1778)
							(mid 0.249642 0.249642)
							(end 0.1778 0.2794)
						)
					)
					(width 0)
					(fill yes)
				)
			)
		)
	)
	(footprint ""
		(layer "B.Cu")
		(at 175.41748 -81.51876 180)
		(property "Reference" "C363"
			(at 0 0 0)
			(layer "B.SilkS")
			(hide yes)
			(effects
				(font
					(size 1.27 1.27)
				)
				(justify mirror)
			)
		)
		(property "Value" "SC22U6D3V3MX-9-GP-U"
			(at 0 -2.8194 180)
			(unlocked yes)
			(layer "B.Fab")
			(hide yes)
			(effects
				(font
					(size 1.016 1.016)
					(thickness 0.1524)
				)
				(justify mirror)
			)
		)
		(property "Device Type" "C603H40"
			(at 0 -4.3434 180)
			(unlocked yes)
			(layer "B.Fab")
			(hide yes)
			(effects
				(font
					(size 1.016 1.016)
					(thickness 0.1524)
				)
				(justify mirror)
			)
		)
		(duplicate_pad_numbers_are_jumpers no)
		(fp_line
			(start -0.508 0)
			(end 0.508 0)
			(stroke
				(width 0.2032)
				(type default)
			)
			(layer "B.SilkS")
		)
		(fp_rect
			(start 0.5842 1.3335)
			(end -0.5842 -1.3335)
			(stroke
				(width 0)
				(type default)
			)
			(fill no)
			(layer "B.CrtYd")
		)
		(fp_rect
			(start 0.5842 1.3335)
			(end -0.5842 -1.3335)
			(stroke
				(width 0)
				(type default)
			)
			(fill no)
			(layer "B.Fab")
		)
		(pad "1" smd custom
			(at 0 -0.762)
			(size 0.2159 0.2159)
			(layers "B.Cu" "B.Mask" "B.Paste")
			(net "PCE_AVDD")
			(options
				(clearance outline)
				(anchor circle)
			)
			(primitives
				(gr_poly
					(pts
						(arc
							(start -0.3302 0.4318)
							(mid -0.402042 0.402042)
							(end -0.4318 0.3302)
						)
						(arc
							(start -0.4318 -0.3302)
							(mid -0.402042 -0.402042)
							(end -0.3302 -0.4318)
						)
						(arc
							(start 0.3302 -0.4318)
							(mid 0.402042 -0.402042)
							(end 0.4318 -0.3302)
						)
						(arc
							(start 0.4318 0.3302)
							(mid 0.402042 0.402042)
							(end 0.3302 0.4318)
						)
					)
					(width 0)
					(fill yes)
				)
			)
		)
		(pad "2" smd custom
			(at 0 0.762)
			(size 0.2159 0.2159)
			(layers "B.Cu" "B.Mask" "B.Paste")
			(net "GND")
			(options
				(clearance outline)
				(anchor circle)
			)
			(primitives
				(gr_poly
					(pts
						(arc
							(start -0.3302 0.4318)
							(mid -0.402042 0.402042)
							(end -0.4318 0.3302)
						)
						(arc
							(start -0.4318 -0.3302)
							(mid -0.402042 -0.402042)
							(end -0.3302 -0.4318)
						)
						(arc
							(start 0.3302 -0.4318)
							(mid 0.402042 -0.402042)
							(end 0.4318 -0.3302)
						)
						(arc
							(start 0.4318 0.3302)
							(mid 0.402042 0.402042)
							(end 0.3302 0.4318)
						)
					)
					(width 0)
					(fill yes)
				)
			)
		)
	)
	(footprint ""
		(layer "B.Cu")
		(at 181.302406 -72.17029)
		(property "Reference" "TP118"
			(at 0 0 0)
			(layer "B.SilkS")
			(hide yes)
			(effects
				(font
					(size 1.27 1.27)
				)
				(justify mirror)
			)
		)
		(property "Value" "TPAD28-2-GP"
			(at 0.0127 -1.6637 0)
			(unlocked yes)
			(layer "B.Fab")
			(hide yes)
			(effects
				(font
					(size 1.016 1.016)
					(thickness 0.1524)
				)
				(justify mirror)
			)
		)
		(property "Device Type" "TPAD28"
			(at 0.0127 -3.1877 0)
			(unlocked yes)
			(layer "B.Fab")
			(hide yes)
			(effects
				(font
					(size 1.016 1.016)
					(thickness 0.1524)
				)
				(justify mirror)
			)
		)
		(duplicate_pad_numbers_are_jumpers no)
		(fp_poly
			(pts
				(arc
					(start 0.3556 0)
					(mid -0.3556 0)
					(end 0.3556 0)
				)
			)
			(stroke
				(width 0)
				(type default)
			)
			(fill no)
			(layer "B.CrtYd")
		)
		(fp_poly
			(pts
				(arc
					(start 0.6096 0)
					(mid -0.6096 0)
					(end 0.6096 0)
				)
			)
			(stroke
				(width 0)
				(type default)
			)
			(fill no)
			(layer "B.Fab")
		)
		(pad "1" smd circle
			(at 0 0 180)
			(size 0.7112 0.7112)
			(layers "B.Cu" "B.Mask" "B.Paste")
			(net "IOC_GPIO_29")
		)
	)
	(footprint ""
		(layer "B.Cu")
		(at 95.863664 -157.607762 -90)
		(property "Reference" "R22"
			(at 0 0 90)
			(layer "B.SilkS")
			(hide yes)
			(effects
				(font
					(size 1.27 1.27)
				)
				(justify mirror)
			)
		)
		(property "Value" "4K7R2F-GP"
			(at -0.064008 -3.993896 270)
			(unlocked yes)
			(layer "B.Fab")
			(hide yes)
			(effects
				(font
					(size 1.016 1.016)
					(thickness 0.1524)
				)
				(justify mirror)
			)
		)
		(property "Device Type" "R402H16"
			(at -0.064008 -5.517896 270)
			(unlocked yes)
			(layer "B.Fab")
			(hide yes)
			(effects
				(font
					(size 1.016 1.016)
					(thickness 0.1524)
				)
				(justify mirror)
			)
		)
		(duplicate_pad_numbers_are_jumpers no)
		(fp_line
			(start -0.508 -0.9398)
			(end 0.508 -0.9398)
			(stroke
				(width 0.1524)
				(type default)
			)
			(layer "B.SilkS")
		)
		(fp_line
			(start 0.508 -0.9398)
			(end 0.508 0.9398)
			(stroke
				(width 0.1524)
				(type default)
			)
			(layer "B.SilkS")
		)
		(fp_rect
			(start 0.508 0.9398)
			(end -0.508 -0.9398)
			(stroke
				(width 0)
				(type default)
			)
			(fill no)
			(layer "B.CrtYd")
		)
		(fp_rect
			(start 0.508 0.9398)
			(end -0.508 -0.9398)
			(stroke
				(width 0)
				(type default)
			)
			(fill no)
			(layer "B.Fab")
		)
		(pad "1" smd custom
			(at 0 -0.4445 90)
			(size 0.1397 0.1397)
			(layers "B.Cu" "B.Mask" "B.Paste")
			(net "CFG_SEL1")
			(options
				(clearance outline)
				(anchor circle)
			)
			(primitives
				(gr_poly
					(pts
						(arc
							(start -0.1778 0.2794)
							(mid -0.249642 0.249642)
							(end -0.2794 0.1778)
						)
						(arc
							(start -0.2794 -0.1778)
							(mid -0.249642 -0.249642)
							(end -0.1778 -0.2794)
						)
						(arc
							(start 0.1778 -0.2794)
							(mid 0.249642 -0.249642)
							(end 0.2794 -0.1778)
						)
						(arc
							(start 0.2794 0.1778)
							(mid 0.249642 0.249642)
							(end 0.1778 0.2794)
						)
					)
					(width 0)
					(fill yes)
				)
			)
		)
		(pad "2" smd custom
			(at 0 0.4445 90)
			(size 0.1397 0.1397)
			(layers "B.Cu" "B.Mask" "B.Paste")
			(net "GND")
			(options
				(clearance outline)
				(anchor circle)
			)
			(primitives
				(gr_poly
					(pts
						(arc
							(start -0.1778 0.2794)
							(mid -0.249642 0.249642)
							(end -0.2794 0.1778)
						)
						(arc
							(start -0.2794 -0.1778)
							(mid -0.249642 -0.249642)
							(end -0.1778 -0.2794)
						)
						(arc
							(start 0.1778 -0.2794)
							(mid 0.249642 -0.249642)
							(end 0.2794 -0.1778)
						)
						(arc
							(start 0.2794 0.1778)
							(mid 0.249642 0.249642)
							(end 0.1778 0.2794)
						)
					)
					(width 0)
					(fill yes)
				)
			)
		)
	)
	(footprint ""
		(layer "B.Cu")
		(at 61.4426 -136.906 90)
		(property "Reference" "R739"
			(at 0 0 90)
			(layer "B.SilkS")
			(hide yes)
			(effects
				(font
					(size 1.27 1.27)
				)
				(justify mirror)
			)
		)
		(property "Value" "10KR2F-2-GP"
			(at -0.064008 -3.993896 90)
			(unlocked yes)
			(layer "B.Fab")
			(hide yes)
			(effects
				(font
					(size 1.016 1.016)
					(thickness 0.1524)
				)
				(justify mirror)
			)
		)
		(property "Device Type" "R402H16"
			(at -0.064008 -5.517896 90)
			(unlocked yes)
			(layer "B.Fab")
			(hide yes)
			(effects
				(font
					(size 1.016 1.016)
					(thickness 0.1524)
				)
				(justify mirror)
			)
		)
		(duplicate_pad_numbers_are_jumpers no)
		(fp_line
			(start 0.508 -0.9398)
			(end 0.508 0.9398)
			(stroke
				(width 0.1524)
				(type default)
			)
			(layer "B.SilkS")
		)
		(fp_line
			(start -0.508 -0.9398)
			(end 0.508 -0.9398)
			(stroke
				(width 0.1524)
				(type default)
			)
			(layer "B.SilkS")
		)
		(fp_rect
			(start 0.508 0.9398)
			(end -0.508 -0.9398)
			(stroke
				(width 0)
				(type default)
			)
			(fill no)
			(layer "B.CrtYd")
		)
		(fp_rect
			(start 0.508 0.9398)
			(end -0.508 -0.9398)
			(stroke
				(width 0)
				(type default)
			)
			(fill no)
			(layer "B.Fab")
		)
		(pad "1" smd custom
			(at 0 -0.4445 270)
			(size 0.1397 0.1397)
			(layers "B.Cu" "B.Mask" "B.Paste")
			(net "TP_BMC_GPIOA0")
			(options
				(clearance outline)
				(anchor circle)
			)
			(primitives
				(gr_poly
					(pts
						(arc
							(start -0.1778 0.2794)
							(mid -0.249642 0.249642)
							(end -0.2794 0.1778)
						)
						(arc
							(start -0.2794 -0.1778)
							(mid -0.249642 -0.249642)
							(end -0.1778 -0.2794)
						)
						(arc
							(start 0.1778 -0.2794)
							(mid 0.249642 -0.249642)
							(end 0.2794 -0.1778)
						)
						(arc
							(start 0.2794 0.1778)
							(mid 0.249642 0.249642)
							(end 0.1778 0.2794)
						)
					)
					(width 0)
					(fill yes)
				)
			)
		)
		(pad "2" smd custom
			(at 0 0.4445 270)
			(size 0.1397 0.1397)
			(layers "B.Cu" "B.Mask" "B.Paste")
			(net "GND")
			(options
				(clearance outline)
				(anchor circle)
			)
			(primitives
				(gr_poly
					(pts
						(arc
							(start -0.1778 0.2794)
							(mid -0.249642 0.249642)
							(end -0.2794 0.1778)
						)
						(arc
							(start -0.2794 -0.1778)
							(mid -0.249642 -0.249642)
							(end -0.1778 -0.2794)
						)
						(arc
							(start 0.1778 -0.2794)
							(mid 0.249642 -0.249642)
							(end 0.2794 -0.1778)
						)
						(arc
							(start 0.2794 0.1778)
							(mid 0.249642 0.249642)
							(end 0.1778 0.2794)
						)
					)
					(width 0)
					(fill yes)
				)
			)
		)
	)
	(footprint ""
		(layer "B.Cu")
		(at 92.9894 -132.0546 -90)
		(property "Reference" "U100"
			(at 0 0 90)
			(layer "B.SilkS")
			(hide yes)
			(effects
				(font
					(size 1.27 1.27)
				)
				(justify mirror)
			)
		)
		(property "Value" "SNLVC1G126DCKR-GP"
			(at 2.3368 -8.6868 270)
			(unlocked yes)
			(layer "B.Fab")
			(hide yes)
			(effects
				(font
					(size 1.016 1.016)
					(thickness 0.1524)
				)
				(justify mirror)
			)
		)
		(property "Device Type" "SC70-5H44"
			(at 2.3114 -10.414 270)
			(unlocked yes)
			(layer "B.Fab")
			(hide yes)
			(effects
				(font
					(size 1.016 1.016)
					(thickness 0.1524)
				)
				(justify mirror)
			)
		)
		(duplicate_pad_numbers_are_jumpers no)
		(fp_line
			(start -1.27 1.7018)
			(end 1.27 1.7018)
			(stroke
				(width 0.1524)
				(type default)
			)
			(layer "B.SilkS")
		)
		(fp_line
			(start 1.27 1.7018)
			(end 1.27 -1.7018)
			(stroke
				(width 0.1524)
				(type default)
			)
			(layer "B.SilkS")
		)
		(fp_line
			(start -1.27 -1.7018)
			(end -1.27 1.7018)
			(stroke
				(width 0.1524)
				(type default)
			)
			(layer "B.SilkS")
		)
		(fp_line
			(start 1.27 -1.7018)
			(end -1.27 -1.7018)
			(stroke
				(width 0.1524)
				(type default)
			)
			(layer "B.SilkS")
		)
		(fp_line
			(start -1.3843 -1.8034)
			(end -1.3843 -1.1176)
			(stroke
				(width 0.3302)
				(type default)
			)
			(layer "B.SilkS")
		)
		(fp_line
			(start -0.6604 -1.8034)
			(end -1.3843 -1.8034)
			(stroke
				(width 0.3302)
				(type default)
			)
			(layer "B.SilkS")
		)
		(fp_rect
			(start 1.524 1.9558)
			(end -1.524 -1.9558)
			(stroke
				(width 0)
				(type default)
			)
			(fill no)
			(layer "B.CrtYd")
		)
		(fp_poly
			(pts
				(xy 1.524 -1.9558) (xy -1.524 -1.9558) (xy -1.524 1.9558) (xy 1.524 1.9558)
			)
			(stroke
				(width 0)
				(type default)
			)
			(fill no)
			(layer "B.Fab")
		)
		(pad "1" smd rect
			(at -0.65024 -0.8255 90)
			(size 0.4064 1.2192)
			(layers "B.Cu" "B.Mask" "B.Paste")
			(net "DEBUG_CARD_PRSNT")
		)
		(pad "2" smd rect
			(at 0 -0.8255 90)
			(size 0.4064 1.2192)
			(layers "B.Cu" "B.Mask" "B.Paste")
			(net "DEBUG_UART_IOM_TX")
		)
		(pad "3" smd rect
			(at 0.65024 -0.8255 90)
			(size 0.4064 1.2192)
			(layers "B.Cu" "B.Mask" "B.Paste")
			(net "GND")
		)
		(pad "4" smd rect
			(at 0.65024 0.8255 90)
			(size 0.4064 1.2192)
			(layers "B.Cu" "B.Mask" "B.Paste")
			(net "UART_IOM_TX")
		)
		(pad "5" smd rect
			(at -0.65024 0.8255 90)
			(size 0.4064 1.2192)
			(layers "B.Cu" "B.Mask" "B.Paste")
			(net "P3V3_STBY")
		)
	)
	(footprint ""
		(layer "B.Cu")
		(at 59.563 -162.0266 -90)
		(property "Reference" "R406"
			(at 0 0 90)
			(layer "B.SilkS")
			(hide yes)
			(effects
				(font
					(size 1.27 1.27)
				)
				(justify mirror)
			)
		)
		(property "Value" "1KR2F-3-GP"
			(at -0.064008 -3.993896 270)
			(unlocked yes)
			(layer "B.Fab")
			(hide yes)
			(effects
				(font
					(size 1.016 1.016)
					(thickness 0.1524)
				)
				(justify mirror)
			)
		)
		(property "Device Type" "R402H16"
			(at -0.064008 -5.517896 270)
			(unlocked yes)
			(layer "B.Fab")
			(hide yes)
			(effects
				(font
					(size 1.016 1.016)
					(thickness 0.1524)
				)
				(justify mirror)
			)
		)
		(duplicate_pad_numbers_are_jumpers no)
		(fp_line
			(start -0.508 -0.9398)
			(end 0.508 -0.9398)
			(stroke
				(width 0.1524)
				(type default)
			)
			(layer "B.SilkS")
		)
		(fp_line
			(start 0.508 -0.9398)
			(end 0.508 0.9398)
			(stroke
				(width 0.1524)
				(type default)
			)
			(layer "B.SilkS")
		)
		(fp_rect
			(start 0.508 0.9398)
			(end -0.508 -0.9398)
			(stroke
				(width 0)
				(type default)
			)
			(fill no)
			(layer "B.CrtYd")
		)
		(fp_rect
			(start 0.508 0.9398)
			(end -0.508 -0.9398)
			(stroke
				(width 0)
				(type default)
			)
			(fill no)
			(layer "B.Fab")
		)
		(pad "1" smd custom
			(at 0 -0.4445 90)
			(size 0.1397 0.1397)
			(layers "B.Cu" "B.Mask" "B.Paste")
			(net "ADC_P1V8")
			(options
				(clearance outline)
				(anchor circle)
			)
			(primitives
				(gr_poly
					(pts
						(arc
							(start -0.1778 0.2794)
							(mid -0.249642 0.249642)
							(end -0.2794 0.1778)
						)
						(arc
							(start -0.2794 -0.1778)
							(mid -0.249642 -0.249642)
							(end -0.1778 -0.2794)
						)
						(arc
							(start 0.1778 -0.2794)
							(mid 0.249642 -0.249642)
							(end 0.2794 -0.1778)
						)
						(arc
							(start 0.2794 0.1778)
							(mid 0.249642 0.249642)
							(end 0.1778 0.2794)
						)
					)
					(width 0)
					(fill yes)
				)
			)
		)
		(pad "2" smd custom
			(at 0 0.4445 90)
			(size 0.1397 0.1397)
			(layers "B.Cu" "B.Mask" "B.Paste")
			(net "GND")
			(options
				(clearance outline)
				(anchor circle)
			)
			(primitives
				(gr_poly
					(pts
						(arc
							(start -0.1778 0.2794)
							(mid -0.249642 0.249642)
							(end -0.2794 0.1778)
						)
						(arc
							(start -0.2794 -0.1778)
							(mid -0.249642 -0.249642)
							(end -0.1778 -0.2794)
						)
						(arc
							(start 0.1778 -0.2794)
							(mid 0.249642 -0.249642)
							(end 0.2794 -0.1778)
						)
						(arc
							(start 0.2794 0.1778)
							(mid 0.249642 0.249642)
							(end 0.1778 0.2794)
						)
					)
					(width 0)
					(fill yes)
				)
			)
		)
	)
	(footprint ""
		(layer "B.Cu")
		(at 55.801514 -141.504416)
		(property "Reference" "TP73"
			(at 0 0 0)
			(layer "B.SilkS")
			(hide yes)
			(effects
				(font
					(size 1.27 1.27)
				)
				(justify mirror)
			)
		)
		(property "Value" "TPAD28-2-GP"
			(at 0.0127 -1.6637 0)
			(unlocked yes)
			(layer "B.Fab")
			(hide yes)
			(effects
				(font
					(size 1.016 1.016)
					(thickness 0.1524)
				)
				(justify mirror)
			)
		)
		(property "Device Type" "TPAD28"
			(at 0.0127 -3.1877 0)
			(unlocked yes)
			(layer "B.Fab")
			(hide yes)
			(effects
				(font
					(size 1.016 1.016)
					(thickness 0.1524)
				)
				(justify mirror)
			)
		)
		(duplicate_pad_numbers_are_jumpers no)
		(fp_poly
			(pts
				(arc
					(start 0.3556 0)
					(mid -0.3556 0)
					(end 0.3556 0)
				)
			)
			(stroke
				(width 0)
				(type default)
			)
			(fill no)
			(layer "B.CrtYd")
		)
		(fp_poly
			(pts
				(arc
					(start 0.6096 0)
					(mid -0.6096 0)
					(end 0.6096 0)
				)
			)
			(stroke
				(width 0)
				(type default)
			)
			(fill no)
			(layer "B.Fab")
		)
		(pad "1" smd circle
			(at 0 0 180)
			(size 0.7112 0.7112)
			(layers "B.Cu" "B.Mask" "B.Paste")
			(net "TP_BMC_GPIOI5")
		)
	)
	(footprint ""
		(layer "B.Cu")
		(at 202.394566 -59.01055)
		(property "Reference" "C455"
			(at 0 0 0)
			(layer "B.SilkS")
			(hide yes)
			(effects
				(font
					(size 1.27 1.27)
				)
				(justify mirror)
			)
		)
		(property "Value" "SCD1U16V2KX-3GP"
			(at -1.1811 -2.7051 0)
			(unlocked yes)
			(layer "B.Fab")
			(hide yes)
			(effects
				(font
					(size 1.016 1.016)
					(thickness 0.1524)
				)
				(justify mirror)
			)
		)
		(property "Device Type" "C402H22"
			(at -1.1811 -4.2291 0)
			(unlocked yes)
			(layer "B.Fab")
			(hide yes)
			(effects
				(font
					(size 1.016 1.016)
					(thickness 0.1524)
				)
				(justify mirror)
			)
		)
		(duplicate_pad_numbers_are_jumpers no)
		(fp_rect
			(start 0.4318 0.9525)
			(end -0.4318 -0.9525)
			(stroke
				(width 0)
				(type default)
			)
			(fill no)
			(layer "B.CrtYd")
		)
		(fp_rect
			(start 0.4318 0.9525)
			(end -0.4318 -0.9525)
			(stroke
				(width 0)
				(type default)
			)
			(fill no)
			(layer "B.Fab")
		)
		(pad "1" smd custom
			(at 0 -0.4445 180)
			(size 0.1524 0.1524)
			(layers "B.Cu" "B.Mask" "B.Paste")
			(net "P1V8")
			(options
				(clearance outline)
				(anchor circle)
			)
			(primitives
				(gr_poly
					(pts
						(arc
							(start 0.3048 0.2032)
							(mid 0.275042 0.275042)
							(end 0.2032 0.3048)
						)
						(arc
							(start -0.2032 0.3048)
							(mid -0.275042 0.275042)
							(end -0.3048 0.2032)
						)
						(arc
							(start -0.3048 -0.2032)
							(mid -0.275042 -0.275042)
							(end -0.2032 -0.3048)
						)
						(arc
							(start 0.2032 -0.3048)
							(mid 0.275042 -0.275042)
							(end 0.3048 -0.2032)
						)
					)
					(width 0)
					(fill yes)
				)
			)
		)
		(pad "2" smd custom
			(at 0 0.4445 180)
			(size 0.1524 0.1524)
			(layers "B.Cu" "B.Mask" "B.Paste")
			(net "GND")
			(options
				(clearance outline)
				(anchor circle)
			)
			(primitives
				(gr_poly
					(pts
						(arc
							(start 0.3048 0.2032)
							(mid 0.275042 0.275042)
							(end 0.2032 0.3048)
						)
						(arc
							(start -0.2032 0.3048)
							(mid -0.275042 0.275042)
							(end -0.3048 0.2032)
						)
						(arc
							(start -0.3048 -0.2032)
							(mid -0.275042 -0.275042)
							(end -0.2032 -0.3048)
						)
						(arc
							(start 0.2032 -0.3048)
							(mid 0.275042 -0.275042)
							(end 0.3048 -0.2032)
						)
					)
					(width 0)
					(fill yes)
				)
			)
		)
	)
	(footprint ""
		(layer "B.Cu")
		(at 60.96 -143.9418 90)
		(property "Reference" "R153"
			(at 0 0 90)
			(layer "B.SilkS")
			(hide yes)
			(effects
				(font
					(size 1.27 1.27)
				)
				(justify mirror)
			)
		)
		(property "Value" "0R2J-2-GP"
			(at -0.064008 -3.993896 90)
			(unlocked yes)
			(layer "B.Fab")
			(hide yes)
			(effects
				(font
					(size 1.016 1.016)
					(thickness 0.1524)
				)
				(justify mirror)
			)
		)
		(property "Device Type" "R402H16"
			(at -0.064008 -5.517896 90)
			(unlocked yes)
			(layer "B.Fab")
			(hide yes)
			(effects
				(font
					(size 1.016 1.016)
					(thickness 0.1524)
				)
				(justify mirror)
			)
		)
		(duplicate_pad_numbers_are_jumpers no)
		(fp_line
			(start 0.508 -0.9398)
			(end 0.508 0.9398)
			(stroke
				(width 0.1524)
				(type default)
			)
			(layer "B.SilkS")
		)
		(fp_line
			(start -0.508 -0.9398)
			(end 0.508 -0.9398)
			(stroke
				(width 0.1524)
				(type default)
			)
			(layer "B.SilkS")
		)
		(fp_rect
			(start 0.508 0.9398)
			(end -0.508 -0.9398)
			(stroke
				(width 0)
				(type default)
			)
			(fill no)
			(layer "B.CrtYd")
		)
		(fp_rect
			(start 0.508 0.9398)
			(end -0.508 -0.9398)
			(stroke
				(width 0)
				(type default)
			)
			(fill no)
			(layer "B.Fab")
		)
		(pad "1" smd custom
			(at 0 -0.4445 270)
			(size 0.1397 0.1397)
			(layers "B.Cu" "B.Mask" "B.Paste")
			(net "BMC_SMB10_DAT")
			(options
				(clearance outline)
				(anchor circle)
			)
			(primitives
				(gr_poly
					(pts
						(arc
							(start -0.1778 0.2794)
							(mid -0.249642 0.249642)
							(end -0.2794 0.1778)
						)
						(arc
							(start -0.2794 -0.1778)
							(mid -0.249642 -0.249642)
							(end -0.1778 -0.2794)
						)
						(arc
							(start 0.1778 -0.2794)
							(mid 0.249642 -0.249642)
							(end 0.2794 -0.1778)
						)
						(arc
							(start 0.2794 0.1778)
							(mid 0.249642 0.249642)
							(end 0.1778 0.2794)
						)
					)
					(width 0)
					(fill yes)
				)
			)
		)
		(pad "2" smd custom
			(at 0 0.4445 270)
			(size 0.1397 0.1397)
			(layers "B.Cu" "B.Mask" "B.Paste")
			(net "I2C_EXP_LOC_SDA_OUT")
			(options
				(clearance outline)
				(anchor circle)
			)
			(primitives
				(gr_poly
					(pts
						(arc
							(start -0.1778 0.2794)
							(mid -0.249642 0.249642)
							(end -0.2794 0.1778)
						)
						(arc
							(start -0.2794 -0.1778)
							(mid -0.249642 -0.249642)
							(end -0.1778 -0.2794)
						)
						(arc
							(start 0.1778 -0.2794)
							(mid 0.249642 -0.249642)
							(end 0.2794 -0.1778)
						)
						(arc
							(start 0.2794 0.1778)
							(mid 0.249642 0.249642)
							(end 0.1778 0.2794)
						)
					)
					(width 0)
					(fill yes)
				)
			)
		)
	)
	(footprint ""
		(layer "B.Cu")
		(at 44.35602 -157.98546 90)
		(property "Reference" "L5"
			(at 0 0 90)
			(layer "B.SilkS")
			(hide yes)
			(effects
				(font
					(size 1.27 1.27)
				)
				(justify mirror)
			)
		)
		(property "Value" "MMZ2012S601ATA1N-GP"
			(at 0 -4.2418 90)
			(unlocked yes)
			(layer "B.Fab")
			(hide yes)
			(effects
				(font
					(size 1.016 1.016)
					(thickness 0.1524)
				)
				(justify mirror)
			)
		)
		(property "Device Type" "L805H42"
			(at 0 -5.7912 90)
			(unlocked yes)
			(layer "B.Fab")
			(hide yes)
			(effects
				(font
					(size 1.016 1.016)
					(thickness 0.1524)
				)
				(justify mirror)
			)
		)
		(duplicate_pad_numbers_are_jumpers no)
		(fp_line
			(start 0.889 -1.7018)
			(end -0.889 -1.7018)
			(stroke
				(width 0.1524)
				(type default)
			)
			(layer "B.SilkS")
		)
		(fp_line
			(start -0.889 -1.7018)
			(end -0.889 1.7018)
			(stroke
				(width 0.1524)
				(type default)
			)
			(layer "B.SilkS")
		)
		(fp_line
			(start 0.889 1.7018)
			(end 0.889 -1.7018)
			(stroke
				(width 0.1524)
				(type default)
			)
			(layer "B.SilkS")
		)
		(fp_line
			(start -0.889 1.7018)
			(end 0.889 1.7018)
			(stroke
				(width 0.1524)
				(type default)
			)
			(layer "B.SilkS")
		)
		(fp_rect
			(start 0.9652 1.778)
			(end -0.9652 -1.778)
			(stroke
				(width 0)
				(type default)
			)
			(fill no)
			(layer "B.CrtYd")
		)
		(fp_rect
			(start 0.9652 1.778)
			(end -0.9652 -1.778)
			(stroke
				(width 0)
				(type default)
			)
			(fill no)
			(layer "B.Fab")
		)
		(pad "1" smd rect
			(at 0 -0.9652 270)
			(size 1.397 1.143)
			(layers "B.Cu" "B.Mask" "B.Paste")
			(net "P1V15_STBY")
		)
		(pad "2" smd rect
			(at 0 0.9652 270)
			(size 1.397 1.143)
			(layers "B.Cu" "B.Mask" "B.Paste")
			(net "V1PLLAV11")
		)
	)
	(footprint ""
		(layer "B.Cu")
		(at 192.405 -50.6222 -90)
		(property "Reference" "C331"
			(at 0 0 90)
			(layer "B.SilkS")
			(hide yes)
			(effects
				(font
					(size 1.27 1.27)
				)
				(justify mirror)
			)
		)
		(property "Value" "SC10U6D3V5KX-4GP"
			(at 0.0762 -6.1214 270)
			(unlocked yes)
			(layer "B.Fab")
			(hide yes)
			(effects
				(font
					(size 1.016 1.016)
					(thickness 0.1524)
				)
				(justify mirror)
			)
		)
		(property "Device Type" "C805H58"
			(at 0.0762 -8.1534 270)
			(unlocked yes)
			(layer "B.Fab")
			(hide yes)
			(effects
				(font
					(size 1.016 1.016)
					(thickness 0.1524)
				)
				(justify mirror)
			)
		)
		(duplicate_pad_numbers_are_jumpers no)
		(fp_line
			(start -0.635 0)
			(end 0.635 0)
			(stroke
				(width 0.508)
				(type default)
			)
			(layer "B.SilkS")
		)
		(fp_rect
			(start 0.9652 1.778)
			(end -0.9652 -1.778)
			(stroke
				(width 0)
				(type default)
			)
			(fill no)
			(layer "B.CrtYd")
		)
		(fp_poly
			(pts
				(xy 0.9652 -1.778) (xy -0.9652 -1.778) (xy -0.9652 1.778) (xy 0.9652 1.778)
			)
			(stroke
				(width 0)
				(type default)
			)
			(fill no)
			(layer "B.Fab")
		)
		(pad "1" smd rect
			(at 0 -0.9652 90)
			(size 1.397 1.143)
			(layers "B.Cu" "B.Mask" "B.Paste")
			(net "HM40ADC_VDDA")
		)
		(pad "2" smd rect
			(at 0 0.9652 90)
			(size 1.397 1.143)
			(layers "B.Cu" "B.Mask" "B.Paste")
			(net "GND")
		)
	)
	(footprint ""
		(layer "B.Cu")
		(at 24.4602 -179.2478 -90)
		(property "Reference" "C179"
			(at 0 0 90)
			(layer "B.SilkS")
			(hide yes)
			(effects
				(font
					(size 1.27 1.27)
				)
				(justify mirror)
			)
		)
		(property "Value" "SC4D7U25V5KX-1-GP"
			(at 0.0762 -6.1214 270)
			(unlocked yes)
			(layer "B.Fab")
			(hide yes)
			(effects
				(font
					(size 1.016 1.016)
					(thickness 0.1524)
				)
				(justify mirror)
			)
		)
		(property "Device Type" "C805H58"
			(at 0.0762 -8.1534 270)
			(unlocked yes)
			(layer "B.Fab")
			(hide yes)
			(effects
				(font
					(size 1.016 1.016)
					(thickness 0.1524)
				)
				(justify mirror)
			)
		)
		(duplicate_pad_numbers_are_jumpers no)
		(fp_line
			(start -0.635 0)
			(end 0.635 0)
			(stroke
				(width 0.508)
				(type default)
			)
			(layer "B.SilkS")
		)
		(fp_rect
			(start 0.9652 1.778)
			(end -0.9652 -1.778)
			(stroke
				(width 0)
				(type default)
			)
			(fill no)
			(layer "B.CrtYd")
		)
		(fp_poly
			(pts
				(xy 0.9652 -1.778) (xy -0.9652 -1.778) (xy -0.9652 1.778) (xy 0.9652 1.778)
			)
			(stroke
				(width 0)
				(type default)
			)
			(fill no)
			(layer "B.Fab")
		)
		(pad "1" smd rect
			(at 0 -0.9652 90)
			(size 1.397 1.143)
			(layers "B.Cu" "B.Mask" "B.Paste")
			(net "P12V_STBY_VDD_PU2")
		)
		(pad "2" smd rect
			(at 0 0.9652 90)
			(size 1.397 1.143)
			(layers "B.Cu" "B.Mask" "B.Paste")
			(net "GND")
		)
	)
	(footprint ""
		(layer "B.Cu")
		(at 91.5162 -142.2654)
		(property "Reference" "R722"
			(at 0 0 0)
			(layer "B.SilkS")
			(hide yes)
			(effects
				(font
					(size 1.27 1.27)
				)
				(justify mirror)
			)
		)
		(property "Value" "10KR2J-3-GP"
			(at -0.064008 -3.993896 0)
			(unlocked yes)
			(layer "B.Fab")
			(hide yes)
			(effects
				(font
					(size 1.016 1.016)
					(thickness 0.1524)
				)
				(justify mirror)
			)
		)
		(property "Device Type" "R402H16"
			(at -0.064008 -5.517896 0)
			(unlocked yes)
			(layer "B.Fab")
			(hide yes)
			(effects
				(font
					(size 1.016 1.016)
					(thickness 0.1524)
				)
				(justify mirror)
			)
		)
		(duplicate_pad_numbers_are_jumpers no)
		(fp_line
			(start -0.508 -0.9398)
			(end 0.508 -0.9398)
			(stroke
				(width 0.1524)
				(type default)
			)
			(layer "B.SilkS")
		)
		(fp_line
			(start 0.508 -0.9398)
			(end 0.508 0.9398)
			(stroke
				(width 0.1524)
				(type default)
			)
			(layer "B.SilkS")
		)
		(fp_rect
			(start 0.508 0.9398)
			(end -0.508 -0.9398)
			(stroke
				(width 0)
				(type default)
			)
			(fill no)
			(layer "B.CrtYd")
		)
		(fp_rect
			(start 0.508 0.9398)
			(end -0.508 -0.9398)
			(stroke
				(width 0)
				(type default)
			)
			(fill no)
			(layer "B.Fab")
		)
		(pad "1" smd custom
			(at 0 -0.4445 180)
			(size 0.1397 0.1397)
			(layers "B.Cu" "B.Mask" "B.Paste")
			(net "DB_PRSNT_BMC_N")
			(options
				(clearance outline)
				(anchor circle)
			)
			(primitives
				(gr_poly
					(pts
						(arc
							(start -0.1778 0.2794)
							(mid -0.249642 0.249642)
							(end -0.2794 0.1778)
						)
						(arc
							(start -0.2794 -0.1778)
							(mid -0.249642 -0.249642)
							(end -0.1778 -0.2794)
						)
						(arc
							(start 0.1778 -0.2794)
							(mid 0.249642 -0.249642)
							(end 0.2794 -0.1778)
						)
						(arc
							(start 0.2794 0.1778)
							(mid 0.249642 0.249642)
							(end 0.1778 0.2794)
						)
					)
					(width 0)
					(fill yes)
				)
			)
		)
		(pad "2" smd custom
			(at 0 0.4445 180)
			(size 0.1397 0.1397)
			(layers "B.Cu" "B.Mask" "B.Paste")
			(net "P3V3_STBY")
			(options
				(clearance outline)
				(anchor circle)
			)
			(primitives
				(gr_poly
					(pts
						(arc
							(start -0.1778 0.2794)
							(mid -0.249642 0.249642)
							(end -0.2794 0.1778)
						)
						(arc
							(start -0.2794 -0.1778)
							(mid -0.249642 -0.249642)
							(end -0.1778 -0.2794)
						)
						(arc
							(start 0.1778 -0.2794)
							(mid 0.249642 -0.249642)
							(end 0.2794 -0.1778)
						)
						(arc
							(start 0.2794 0.1778)
							(mid 0.249642 0.249642)
							(end 0.1778 0.2794)
						)
					)
					(width 0)
					(fill yes)
				)
			)
		)
	)
	(footprint ""
		(layer "B.Cu")
		(at 181.87924 -78.56728)
		(property "Reference" "TP104"
			(at 0 0 0)
			(layer "B.SilkS")
			(hide yes)
			(effects
				(font
					(size 1.27 1.27)
				)
				(justify mirror)
			)
		)
		(property "Value" "TPAD28-2-GP"
			(at 0.0127 -1.6637 0)
			(unlocked yes)
			(layer "B.Fab")
			(hide yes)
			(effects
				(font
					(size 1.016 1.016)
					(thickness 0.1524)
				)
				(justify mirror)
			)
		)
		(property "Device Type" "TPAD28"
			(at 0.0127 -3.1877 0)
			(unlocked yes)
			(layer "B.Fab")
			(hide yes)
			(effects
				(font
					(size 1.016 1.016)
					(thickness 0.1524)
				)
				(justify mirror)
			)
		)
		(duplicate_pad_numbers_are_jumpers no)
		(fp_poly
			(pts
				(arc
					(start 0.3556 0)
					(mid -0.3556 0)
					(end 0.3556 0)
				)
			)
			(stroke
				(width 0)
				(type default)
			)
			(fill no)
			(layer "B.CrtYd")
		)
		(fp_poly
			(pts
				(arc
					(start 0.6096 0)
					(mid -0.6096 0)
					(end 0.6096 0)
				)
			)
			(stroke
				(width 0)
				(type default)
			)
			(fill no)
			(layer "B.Fab")
		)
		(pad "1" smd circle
			(at 0 0 180)
			(size 0.7112 0.7112)
			(layers "B.Cu" "B.Mask" "B.Paste")
			(net "IOC_GPIO_19")
		)
	)
	(footprint ""
		(layer "B.Cu")
		(at 41.69029 -122.367548 -90)
		(property "Reference" "C506"
			(at 0 0 90)
			(layer "B.SilkS")
			(hide yes)
			(effects
				(font
					(size 1.27 1.27)
				)
				(justify mirror)
			)
		)
		(property "Value" "SCD1U16V2KX-3GP"
			(at -1.1811 -2.7051 270)
			(unlocked yes)
			(layer "B.Fab")
			(hide yes)
			(effects
				(font
					(size 1.016 1.016)
					(thickness 0.1524)
				)
				(justify mirror)
			)
		)
		(property "Device Type" "C402H22"
			(at -1.1811 -4.2291 270)
			(unlocked yes)
			(layer "B.Fab")
			(hide yes)
			(effects
				(font
					(size 1.016 1.016)
					(thickness 0.1524)
				)
				(justify mirror)
			)
		)
		(duplicate_pad_numbers_are_jumpers no)
		(fp_rect
			(start 0.4318 0.9525)
			(end -0.4318 -0.9525)
			(stroke
				(width 0)
				(type default)
			)
			(fill no)
			(layer "B.CrtYd")
		)
		(fp_rect
			(start 0.4318 0.9525)
			(end -0.4318 -0.9525)
			(stroke
				(width 0)
				(type default)
			)
			(fill no)
			(layer "B.Fab")
		)
		(pad "1" smd custom
			(at 0 -0.4445 90)
			(size 0.1524 0.1524)
			(layers "B.Cu" "B.Mask" "B.Paste")
			(net "P3V3_STBY")
			(options
				(clearance outline)
				(anchor circle)
			)
			(primitives
				(gr_poly
					(pts
						(arc
							(start 0.3048 0.2032)
							(mid 0.275042 0.275042)
							(end 0.2032 0.3048)
						)
						(arc
							(start -0.2032 0.3048)
							(mid -0.275042 0.275042)
							(end -0.3048 0.2032)
						)
						(arc
							(start -0.3048 -0.2032)
							(mid -0.275042 -0.275042)
							(end -0.2032 -0.3048)
						)
						(arc
							(start 0.2032 -0.3048)
							(mid 0.275042 -0.275042)
							(end 0.3048 -0.2032)
						)
					)
					(width 0)
					(fill yes)
				)
			)
		)
		(pad "2" smd custom
			(at 0 0.4445 90)
			(size 0.1524 0.1524)
			(layers "B.Cu" "B.Mask" "B.Paste")
			(net "GND")
			(options
				(clearance outline)
				(anchor circle)
			)
			(primitives
				(gr_poly
					(pts
						(arc
							(start 0.3048 0.2032)
							(mid 0.275042 0.275042)
							(end 0.2032 0.3048)
						)
						(arc
							(start -0.2032 0.3048)
							(mid -0.275042 0.275042)
							(end -0.3048 0.2032)
						)
						(arc
							(start -0.3048 -0.2032)
							(mid -0.275042 -0.275042)
							(end -0.2032 -0.3048)
						)
						(arc
							(start 0.2032 -0.3048)
							(mid 0.275042 -0.275042)
							(end 0.3048 -0.2032)
						)
					)
					(width 0)
					(fill yes)
				)
			)
		)
	)
	(footprint ""
		(layer "B.Cu")
		(at 203.511404 -92.851224 180)
		(property "Reference" "C357"
			(at 0 0 0)
			(layer "B.SilkS")
			(hide yes)
			(effects
				(font
					(size 1.27 1.27)
				)
				(justify mirror)
			)
		)
		(property "Value" "SC10U6D3V5KX-4GP"
			(at 0.0762 -6.1214 180)
			(unlocked yes)
			(layer "B.Fab")
			(hide yes)
			(effects
				(font
					(size 1.016 1.016)
					(thickness 0.1524)
				)
				(justify mirror)
			)
		)
		(property "Device Type" "C805H58"
			(at 0.0762 -8.1534 180)
			(unlocked yes)
			(layer "B.Fab")
			(hide yes)
			(effects
				(font
					(size 1.016 1.016)
					(thickness 0.1524)
				)
				(justify mirror)
			)
		)
		(duplicate_pad_numbers_are_jumpers no)
		(fp_line
			(start -0.635 0)
			(end 0.635 0)
			(stroke
				(width 0.508)
				(type default)
			)
			(layer "B.SilkS")
		)
		(fp_rect
			(start 0.9652 1.778)
			(end -0.9652 -1.778)
			(stroke
				(width 0)
				(type default)
			)
			(fill no)
			(layer "B.CrtYd")
		)
		(fp_poly
			(pts
				(xy 0.9652 -1.778) (xy -0.9652 -1.778) (xy -0.9652 1.778) (xy 0.9652 1.778)
			)
			(stroke
				(width 0)
				(type default)
			)
			(fill no)
			(layer "B.Fab")
		)
		(pad "1" smd rect
			(at 0 -0.9652)
			(size 1.397 1.143)
			(layers "B.Cu" "B.Mask" "B.Paste")
			(net "PCE_VDDH")
		)
		(pad "2" smd rect
			(at 0 0.9652)
			(size 1.397 1.143)
			(layers "B.Cu" "B.Mask" "B.Paste")
			(net "GND")
		)
	)
	(footprint ""
		(layer "B.Cu")
		(at 47.93234 -157.99308 90)
		(property "Reference" "C89"
			(at 0 0 90)
			(layer "B.SilkS")
			(hide yes)
			(effects
				(font
					(size 1.27 1.27)
				)
				(justify mirror)
			)
		)
		(property "Value" "SC4D7U25V5KX-1-GP"
			(at 0.0762 -6.1214 90)
			(unlocked yes)
			(layer "B.Fab")
			(hide yes)
			(effects
				(font
					(size 1.016 1.016)
					(thickness 0.1524)
				)
				(justify mirror)
			)
		)
		(property "Device Type" "C805H58"
			(at 0.0762 -8.1534 90)
			(unlocked yes)
			(layer "B.Fab")
			(hide yes)
			(effects
				(font
					(size 1.016 1.016)
					(thickness 0.1524)
				)
				(justify mirror)
			)
		)
		(duplicate_pad_numbers_are_jumpers no)
		(fp_line
			(start -0.635 0)
			(end 0.635 0)
			(stroke
				(width 0.508)
				(type default)
			)
			(layer "B.SilkS")
		)
		(fp_rect
			(start 0.9652 1.778)
			(end -0.9652 -1.778)
			(stroke
				(width 0)
				(type default)
			)
			(fill no)
			(layer "B.CrtYd")
		)
		(fp_poly
			(pts
				(xy 0.9652 -1.778) (xy -0.9652 -1.778) (xy -0.9652 1.778) (xy 0.9652 1.778)
			)
			(stroke
				(width 0)
				(type default)
			)
			(fill no)
			(layer "B.Fab")
		)
		(pad "1" smd rect
			(at 0 -0.9652 270)
			(size 1.397 1.143)
			(layers "B.Cu" "B.Mask" "B.Paste")
			(net "DACAV33")
		)
		(pad "2" smd rect
			(at 0 0.9652 270)
			(size 1.397 1.143)
			(layers "B.Cu" "B.Mask" "B.Paste")
			(net "GND")
		)
	)
	(footprint ""
		(layer "B.Cu")
		(at 47.272194 -131.694174 180)
		(property "Reference" "R613"
			(at 0 0 0)
			(layer "B.SilkS")
			(hide yes)
			(effects
				(font
					(size 1.27 1.27)
				)
				(justify mirror)
			)
		)
		(property "Value" "0R2J-2-GP"
			(at -0.064008 -3.993896 180)
			(unlocked yes)
			(layer "B.Fab")
			(hide yes)
			(effects
				(font
					(size 1.016 1.016)
					(thickness 0.1524)
				)
				(justify mirror)
			)
		)
		(property "Device Type" "R402H16"
			(at -0.064008 -5.517896 180)
			(unlocked yes)
			(layer "B.Fab")
			(hide yes)
			(effects
				(font
					(size 1.016 1.016)
					(thickness 0.1524)
				)
				(justify mirror)
			)
		)
		(duplicate_pad_numbers_are_jumpers no)
		(fp_line
			(start 0.508 -0.9398)
			(end 0.508 0.9398)
			(stroke
				(width 0.1524)
				(type default)
			)
			(layer "B.SilkS")
		)
		(fp_line
			(start -0.508 -0.9398)
			(end 0.508 -0.9398)
			(stroke
				(width 0.1524)
				(type default)
			)
			(layer "B.SilkS")
		)
		(fp_rect
			(start 0.508 0.9398)
			(end -0.508 -0.9398)
			(stroke
				(width 0)
				(type default)
			)
			(fill no)
			(layer "B.CrtYd")
		)
		(fp_rect
			(start 0.508 0.9398)
			(end -0.508 -0.9398)
			(stroke
				(width 0)
				(type default)
			)
			(fill no)
			(layer "B.Fab")
		)
		(pad "1" smd custom
			(at 0 -0.4445)
			(size 0.1397 0.1397)
			(layers "B.Cu" "B.Mask" "B.Paste")
			(net "PCIE_COMP_TO_IOM_RST_4")
			(options
				(clearance outline)
				(anchor circle)
			)
			(primitives
				(gr_poly
					(pts
						(arc
							(start -0.1778 0.2794)
							(mid -0.249642 0.249642)
							(end -0.2794 0.1778)
						)
						(arc
							(start -0.2794 -0.1778)
							(mid -0.249642 -0.249642)
							(end -0.1778 -0.2794)
						)
						(arc
							(start 0.1778 -0.2794)
							(mid 0.249642 -0.249642)
							(end 0.2794 -0.1778)
						)
						(arc
							(start 0.2794 0.1778)
							(mid 0.249642 0.249642)
							(end 0.1778 0.2794)
						)
					)
					(width 0)
					(fill yes)
				)
			)
		)
		(pad "2" smd custom
			(at 0 0.4445)
			(size 0.1397 0.1397)
			(layers "B.Cu" "B.Mask" "B.Paste")
			(net "PLTRST_R")
			(options
				(clearance outline)
				(anchor circle)
			)
			(primitives
				(gr_poly
					(pts
						(arc
							(start -0.1778 0.2794)
							(mid -0.249642 0.249642)
							(end -0.2794 0.1778)
						)
						(arc
							(start -0.2794 -0.1778)
							(mid -0.249642 -0.249642)
							(end -0.1778 -0.2794)
						)
						(arc
							(start 0.1778 -0.2794)
							(mid 0.249642 -0.249642)
							(end 0.2794 -0.1778)
						)
						(arc
							(start 0.2794 0.1778)
							(mid 0.249642 0.249642)
							(end 0.1778 0.2794)
						)
					)
					(width 0)
					(fill yes)
				)
			)
		)
	)
	(footprint ""
		(layer "B.Cu")
		(at 204.772768 -46.281086 90)
		(property "Reference" "R681"
			(at 0 0 90)
			(layer "B.SilkS")
			(hide yes)
			(effects
				(font
					(size 1.27 1.27)
				)
				(justify mirror)
			)
		)
		(property "Value" "10R2F-L-GP"
			(at -0.064008 -3.993896 90)
			(unlocked yes)
			(layer "B.Fab")
			(hide yes)
			(effects
				(font
					(size 1.016 1.016)
					(thickness 0.1524)
				)
				(justify mirror)
			)
		)
		(property "Device Type" "R402H14"
			(at -0.064008 -5.517896 90)
			(unlocked yes)
			(layer "B.Fab")
			(hide yes)
			(effects
				(font
					(size 1.016 1.016)
					(thickness 0.1524)
				)
				(justify mirror)
			)
		)
		(duplicate_pad_numbers_are_jumpers no)
		(fp_line
			(start 0.508 -0.9398)
			(end 0.508 0.9398)
			(stroke
				(width 0.1524)
				(type default)
			)
			(layer "B.SilkS")
		)
		(fp_line
			(start -0.508 -0.9398)
			(end 0.508 -0.9398)
			(stroke
				(width 0.1524)
				(type default)
			)
			(layer "B.SilkS")
		)
		(fp_rect
			(start 0.508 0.9398)
			(end -0.508 -0.9398)
			(stroke
				(width 0)
				(type default)
			)
			(fill no)
			(layer "B.CrtYd")
		)
		(fp_rect
			(start 0.508 0.9398)
			(end -0.508 -0.9398)
			(stroke
				(width 0)
				(type default)
			)
			(fill no)
			(layer "B.Fab")
		)
		(pad "1" smd custom
			(at 0 -0.4445 270)
			(size 0.1397 0.1397)
			(layers "B.Cu" "B.Mask" "B.Paste")
			(net "P1V8")
			(options
				(clearance outline)
				(anchor circle)
			)
			(primitives
				(gr_poly
					(pts
						(arc
							(start -0.1778 0.2794)
							(mid -0.249642 0.249642)
							(end -0.2794 0.1778)
						)
						(arc
							(start -0.2794 -0.1778)
							(mid -0.249642 -0.249642)
							(end -0.1778 -0.2794)
						)
						(arc
							(start 0.1778 -0.2794)
							(mid 0.249642 -0.249642)
							(end 0.2794 -0.1778)
						)
						(arc
							(start 0.2794 0.1778)
							(mid 0.249642 0.249642)
							(end 0.1778 0.2794)
						)
					)
					(width 0)
					(fill yes)
				)
			)
		)
		(pad "2" smd custom
			(at 0 0.4445 270)
			(size 0.1397 0.1397)
			(layers "B.Cu" "B.Mask" "B.Paste")
			(net "SHELL_PLL_VDD")
			(options
				(clearance outline)
				(anchor circle)
			)
			(primitives
				(gr_poly
					(pts
						(arc
							(start -0.1778 0.2794)
							(mid -0.249642 0.249642)
							(end -0.2794 0.1778)
						)
						(arc
							(start -0.2794 -0.1778)
							(mid -0.249642 -0.249642)
							(end -0.1778 -0.2794)
						)
						(arc
							(start 0.1778 -0.2794)
							(mid 0.249642 -0.249642)
							(end 0.2794 -0.1778)
						)
						(arc
							(start 0.2794 0.1778)
							(mid 0.249642 0.249642)
							(end 0.1778 0.2794)
						)
					)
					(width 0)
					(fill yes)
				)
			)
		)
	)
	(footprint ""
		(layer "B.Cu")
		(at 130.12166 -14.217142)
		(property "Reference" "R448"
			(at 0 0 0)
			(layer "B.SilkS")
			(hide yes)
			(effects
				(font
					(size 1.27 1.27)
				)
				(justify mirror)
			)
		)
		(property "Value" "5K1R2F-3-GP"
			(at -0.064008 -3.993896 0)
			(unlocked yes)
			(layer "B.Fab")
			(hide yes)
			(effects
				(font
					(size 1.016 1.016)
					(thickness 0.1524)
				)
				(justify mirror)
			)
		)
		(property "Device Type" "R402H16"
			(at -0.064008 -5.517896 0)
			(unlocked yes)
			(layer "B.Fab")
			(hide yes)
			(effects
				(font
					(size 1.016 1.016)
					(thickness 0.1524)
				)
				(justify mirror)
			)
		)
		(duplicate_pad_numbers_are_jumpers no)
		(fp_line
			(start -0.508 -0.9398)
			(end 0.508 -0.9398)
			(stroke
				(width 0.1524)
				(type default)
			)
			(layer "B.SilkS")
		)
		(fp_line
			(start 0.508 -0.9398)
			(end 0.508 0.9398)
			(stroke
				(width 0.1524)
				(type default)
			)
			(layer "B.SilkS")
		)
		(fp_rect
			(start 0.508 0.9398)
			(end -0.508 -0.9398)
			(stroke
				(width 0)
				(type default)
			)
			(fill no)
			(layer "B.CrtYd")
		)
		(fp_rect
			(start 0.508 0.9398)
			(end -0.508 -0.9398)
			(stroke
				(width 0)
				(type default)
			)
			(fill no)
			(layer "B.Fab")
		)
		(pad "1" smd custom
			(at 0 -0.4445 180)
			(size 0.1397 0.1397)
			(layers "B.Cu" "B.Mask" "B.Paste")
			(net "MB0_CM_UV_R")
			(options
				(clearance outline)
				(anchor circle)
			)
			(primitives
				(gr_poly
					(pts
						(arc
							(start -0.1778 0.2794)
							(mid -0.249642 0.249642)
							(end -0.2794 0.1778)
						)
						(arc
							(start -0.2794 -0.1778)
							(mid -0.249642 -0.249642)
							(end -0.1778 -0.2794)
						)
						(arc
							(start 0.1778 -0.2794)
							(mid 0.249642 -0.249642)
							(end 0.2794 -0.1778)
						)
						(arc
							(start 0.2794 0.1778)
							(mid 0.249642 0.249642)
							(end 0.1778 0.2794)
						)
					)
					(width 0)
					(fill yes)
				)
			)
		)
		(pad "2" smd custom
			(at 0 0.4445 180)
			(size 0.1397 0.1397)
			(layers "B.Cu" "B.Mask" "B.Paste")
			(net "AGND_CURRENT_MON")
			(options
				(clearance outline)
				(anchor circle)
			)
			(primitives
				(gr_poly
					(pts
						(arc
							(start -0.1778 0.2794)
							(mid -0.249642 0.249642)
							(end -0.2794 0.1778)
						)
						(arc
							(start -0.2794 -0.1778)
							(mid -0.249642 -0.249642)
							(end -0.1778 -0.2794)
						)
						(arc
							(start 0.1778 -0.2794)
							(mid 0.249642 -0.249642)
							(end 0.2794 -0.1778)
						)
						(arc
							(start 0.2794 0.1778)
							(mid 0.249642 0.249642)
							(end 0.1778 0.2794)
						)
					)
					(width 0)
					(fill yes)
				)
			)
		)
	)
	(footprint ""
		(layer "B.Cu")
		(at 203.7334 -56.9468 180)
		(property "Reference" "R591"
			(at 0 0 0)
			(layer "B.SilkS")
			(hide yes)
			(effects
				(font
					(size 1.27 1.27)
				)
				(justify mirror)
			)
		)
		(property "Value" "2K2R2F-GP"
			(at -0.064008 -3.993896 180)
			(unlocked yes)
			(layer "B.Fab")
			(hide yes)
			(effects
				(font
					(size 1.016 1.016)
					(thickness 0.1524)
				)
				(justify mirror)
			)
		)
		(property "Device Type" "R402H16"
			(at -0.064008 -5.517896 180)
			(unlocked yes)
			(layer "B.Fab")
			(hide yes)
			(effects
				(font
					(size 1.016 1.016)
					(thickness 0.1524)
				)
				(justify mirror)
			)
		)
		(duplicate_pad_numbers_are_jumpers no)
		(fp_line
			(start 0.508 -0.9398)
			(end 0.508 0.9398)
			(stroke
				(width 0.1524)
				(type default)
			)
			(layer "B.SilkS")
		)
		(fp_line
			(start -0.508 -0.9398)
			(end 0.508 -0.9398)
			(stroke
				(width 0.1524)
				(type default)
			)
			(layer "B.SilkS")
		)
		(fp_rect
			(start 0.508 0.9398)
			(end -0.508 -0.9398)
			(stroke
				(width 0)
				(type default)
			)
			(fill no)
			(layer "B.CrtYd")
		)
		(fp_rect
			(start 0.508 0.9398)
			(end -0.508 -0.9398)
			(stroke
				(width 0)
				(type default)
			)
			(fill no)
			(layer "B.Fab")
		)
		(pad "1" smd custom
			(at 0 -0.4445)
			(size 0.1397 0.1397)
			(layers "B.Cu" "B.Mask" "B.Paste")
			(net "P1V8")
			(options
				(clearance outline)
				(anchor circle)
			)
			(primitives
				(gr_poly
					(pts
						(arc
							(start -0.1778 0.2794)
							(mid -0.249642 0.249642)
							(end -0.2794 0.1778)
						)
						(arc
							(start -0.2794 -0.1778)
							(mid -0.249642 -0.249642)
							(end -0.1778 -0.2794)
						)
						(arc
							(start 0.1778 -0.2794)
							(mid 0.249642 -0.249642)
							(end 0.2794 -0.1778)
						)
						(arc
							(start 0.2794 0.1778)
							(mid 0.249642 0.249642)
							(end 0.1778 0.2794)
						)
					)
					(width 0)
					(fill yes)
				)
			)
		)
		(pad "2" smd custom
			(at 0 0.4445)
			(size 0.1397 0.1397)
			(layers "B.Cu" "B.Mask" "B.Paste")
			(net "SIO_LOAD_0")
			(options
				(clearance outline)
				(anchor circle)
			)
			(primitives
				(gr_poly
					(pts
						(arc
							(start -0.1778 0.2794)
							(mid -0.249642 0.249642)
							(end -0.2794 0.1778)
						)
						(arc
							(start -0.2794 -0.1778)
							(mid -0.249642 -0.249642)
							(end -0.1778 -0.2794)
						)
						(arc
							(start 0.1778 -0.2794)
							(mid 0.249642 -0.249642)
							(end 0.2794 -0.1778)
						)
						(arc
							(start 0.2794 0.1778)
							(mid 0.249642 0.249642)
							(end 0.1778 0.2794)
						)
					)
					(width 0)
					(fill yes)
				)
			)
		)
	)
	(footprint ""
		(layer "B.Cu")
		(at 155.321 -91.1606 90)
		(property "Reference" "C327"
			(at 0 0 90)
			(layer "B.SilkS")
			(hide yes)
			(effects
				(font
					(size 1.27 1.27)
				)
				(justify mirror)
			)
		)
		(property "Value" "SCD1U16V2KX-3GP"
			(at -1.1811 -2.7051 90)
			(unlocked yes)
			(layer "B.Fab")
			(hide yes)
			(effects
				(font
					(size 1.016 1.016)
					(thickness 0.1524)
				)
				(justify mirror)
			)
		)
		(property "Device Type" "C402H22"
			(at -1.1811 -4.2291 90)
			(unlocked yes)
			(layer "B.Fab")
			(hide yes)
			(effects
				(font
					(size 1.016 1.016)
					(thickness 0.1524)
				)
				(justify mirror)
			)
		)
		(duplicate_pad_numbers_are_jumpers no)
		(fp_rect
			(start 0.4318 0.9525)
			(end -0.4318 -0.9525)
			(stroke
				(width 0)
				(type default)
			)
			(fill no)
			(layer "B.CrtYd")
		)
		(fp_rect
			(start 0.4318 0.9525)
			(end -0.4318 -0.9525)
			(stroke
				(width 0)
				(type default)
			)
			(fill no)
			(layer "B.Fab")
		)
		(pad "1" smd custom
			(at 0 -0.4445 270)
			(size 0.1524 0.1524)
			(layers "B.Cu" "B.Mask" "B.Paste")
			(net "P1V8_STBY")
			(options
				(clearance outline)
				(anchor circle)
			)
			(primitives
				(gr_poly
					(pts
						(arc
							(start 0.3048 0.2032)
							(mid 0.275042 0.275042)
							(end 0.2032 0.3048)
						)
						(arc
							(start -0.2032 0.3048)
							(mid -0.275042 0.275042)
							(end -0.3048 0.2032)
						)
						(arc
							(start -0.3048 -0.2032)
							(mid -0.275042 -0.275042)
							(end -0.2032 -0.3048)
						)
						(arc
							(start 0.2032 -0.3048)
							(mid 0.275042 -0.275042)
							(end 0.3048 -0.2032)
						)
					)
					(width 0)
					(fill yes)
				)
			)
		)
		(pad "2" smd custom
			(at 0 0.4445 270)
			(size 0.1524 0.1524)
			(layers "B.Cu" "B.Mask" "B.Paste")
			(net "GND")
			(options
				(clearance outline)
				(anchor circle)
			)
			(primitives
				(gr_poly
					(pts
						(arc
							(start 0.3048 0.2032)
							(mid 0.275042 0.275042)
							(end 0.2032 0.3048)
						)
						(arc
							(start -0.2032 0.3048)
							(mid -0.275042 0.275042)
							(end -0.3048 0.2032)
						)
						(arc
							(start -0.3048 -0.2032)
							(mid -0.275042 -0.275042)
							(end -0.2032 -0.3048)
						)
						(arc
							(start 0.2032 -0.3048)
							(mid 0.275042 -0.275042)
							(end 0.3048 -0.2032)
						)
					)
					(width 0)
					(fill yes)
				)
			)
		)
	)
	(footprint ""
		(layer "B.Cu")
		(at 191.68999 -19.812 -90)
		(property "Reference" "C487"
			(at 0 0 90)
			(layer "B.SilkS")
			(hide yes)
			(effects
				(font
					(size 1.27 1.27)
				)
				(justify mirror)
			)
		)
		(property "Value" "SCD01U16V1KX-GP"
			(at 2.8321 -1.7399 270)
			(unlocked yes)
			(layer "B.Fab")
			(hide yes)
			(effects
				(font
					(size 1.016 1.016)
					(thickness 0.1524)
				)
				(justify mirror)
			)
		)
		(property "Device Type" "C0201H13"
			(at 2.8321 -3.2639 270)
			(unlocked yes)
			(layer "B.Fab")
			(hide yes)
			(effects
				(font
					(size 1.016 1.016)
					(thickness 0.1524)
				)
				(justify mirror)
			)
		)
		(duplicate_pad_numbers_are_jumpers no)
		(fp_rect
			(start 0.2794 0.6477)
			(end -0.2794 -0.6477)
			(stroke
				(width 0)
				(type default)
			)
			(fill no)
			(layer "B.CrtYd")
		)
		(fp_rect
			(start 0.2794 0.6477)
			(end -0.2794 -0.6477)
			(stroke
				(width 0)
				(type default)
			)
			(fill no)
			(layer "B.Fab")
		)
		(pad "1" smd custom
			(at 0 -0.2794 90)
			(size 0.0762 0.0762)
			(layers "B.Cu" "B.Mask" "B.Paste")
			(net "PHY_CON_A_TO_IOC_0_DP")
			(options
				(clearance outline)
				(anchor circle)
			)
			(primitives
				(gr_poly
					(pts
						(arc
							(start 0.1524 0.127)
							(mid 0.137521 0.162921)
							(end 0.1016 0.1778)
						)
						(arc
							(start -0.1016 0.1778)
							(mid -0.137521 0.162921)
							(end -0.1524 0.127)
						)
						(arc
							(start -0.1524 -0.127)
							(mid -0.137521 -0.162921)
							(end -0.1016 -0.1778)
						)
						(arc
							(start 0.1016 -0.1778)
							(mid 0.137521 -0.162921)
							(end 0.1524 -0.127)
						)
					)
					(width 0)
					(fill yes)
				)
			)
		)
		(pad "2" smd custom
			(at 0 0.2794 90)
			(size 0.0762 0.0762)
			(layers "B.Cu" "B.Mask" "B.Paste")
			(net "PHY_CON_A_TO_IOC_0_DP_C")
			(options
				(clearance outline)
				(anchor circle)
			)
			(primitives
				(gr_poly
					(pts
						(arc
							(start 0.1524 0.127)
							(mid 0.137521 0.162921)
							(end 0.1016 0.1778)
						)
						(arc
							(start -0.1016 0.1778)
							(mid -0.137521 0.162921)
							(end -0.1524 0.127)
						)
						(arc
							(start -0.1524 -0.127)
							(mid -0.137521 -0.162921)
							(end -0.1016 -0.1778)
						)
						(arc
							(start 0.1016 -0.1778)
							(mid 0.137521 -0.162921)
							(end 0.1524 -0.127)
						)
					)
					(width 0)
					(fill yes)
				)
			)
		)
	)
	(footprint ""
		(layer "B.Cu")
		(at 85.415628 -99.121722 180)
		(property "Reference" "Q25"
			(at 0 0 0)
			(layer "B.SilkS")
			(hide yes)
			(effects
				(font
					(size 1.27 1.27)
				)
				(justify mirror)
			)
		)
		(property "Value" "2N7002K-1-GP"
			(at -0.127 -8.9662 180)
			(unlocked yes)
			(layer "B.Fab")
			(hide yes)
			(effects
				(font
					(size 1.016 1.016)
					(thickness 0.1524)
				)
				(justify mirror)
			)
		)
		(property "Device Type" "SOT23DGS2D4H44"
			(at -0.127 -10.4902 180)
			(unlocked yes)
			(layer "B.Fab")
			(hide yes)
			(effects
				(font
					(size 1.016 1.016)
					(thickness 0.1524)
				)
				(justify mirror)
			)
		)
		(duplicate_pad_numbers_are_jumpers no)
		(fp_line
			(start 1.651 1.778)
			(end -1.651 1.778)
			(stroke
				(width 0.1524)
				(type default)
			)
			(layer "B.SilkS")
		)
		(fp_line
			(start 1.651 -1.778)
			(end 1.651 1.778)
			(stroke
				(width 0.1524)
				(type default)
			)
			(layer "B.SilkS")
		)
		(fp_line
			(start -1.651 1.778)
			(end -1.651 -1.778)
			(stroke
				(width 0.1524)
				(type default)
			)
			(layer "B.SilkS")
		)
		(fp_line
			(start -1.651 -1.778)
			(end 1.651 -1.778)
			(stroke
				(width 0.1524)
				(type default)
			)
			(layer "B.SilkS")
		)
		(fp_poly
			(pts
				(xy 1.778 1.8796) (xy 1.778 -1.8796) (xy -1.778 -1.8796) (xy -1.778 1.8796)
			)
			(stroke
				(width 0)
				(type default)
			)
			(fill no)
			(layer "B.CrtYd")
		)
		(fp_poly
			(pts
				(xy 1.778 1.8796) (xy 1.778 -1.8796) (xy -1.778 -1.8796) (xy -1.778 1.8796)
			)
			(stroke
				(width 0)
				(type default)
			)
			(fill no)
			(layer "B.Fab")
		)
		(pad "D" smd custom
			(at 0 -0.9525)
			(size 0.1905 0.1905)
			(layers "B.Cu" "B.Mask" "B.Paste")
			(net "CONN_A_PRSNTA")
			(options
				(clearance outline)
				(anchor circle)
			)
			(primitives
				(gr_poly
					(pts
						(arc
							(start -0.1778 -0.5715)
							(mid -0.321484 -0.511984)
							(end -0.381 -0.3683)
						)
						(arc
							(start -0.381 0.3683)
							(mid -0.321484 0.511984)
							(end -0.1778 0.5715)
						)
						(arc
							(start 0.1778 0.5715)
							(mid 0.321484 0.511984)
							(end 0.381 0.3683)
						)
						(arc
							(start 0.381 -0.3683)
							(mid 0.321484 -0.511984)
							(end 0.1778 -0.5715)
						)
					)
					(width 0)
					(fill yes)
				)
			)
		)
		(pad "G" smd custom
			(at 0.98425 0.9525)
			(size 0.1905 0.1905)
			(layers "B.Cu" "B.Mask" "B.Paste")
			(net "MEZZ_A_PRSNT_120_N")
			(options
				(clearance outline)
				(anchor circle)
			)
			(primitives
				(gr_poly
					(pts
						(arc
							(start -0.1778 -0.5715)
							(mid -0.321484 -0.511984)
							(end -0.381 -0.3683)
						)
						(arc
							(start -0.381 0.3683)
							(mid -0.321484 0.511984)
							(end -0.1778 0.5715)
						)
						(arc
							(start 0.1778 0.5715)
							(mid 0.321484 0.511984)
							(end 0.381 0.3683)
						)
						(arc
							(start 0.381 -0.3683)
							(mid 0.321484 -0.511984)
							(end 0.1778 -0.5715)
						)
					)
					(width 0)
					(fill yes)
				)
			)
		)
		(pad "S" smd custom
			(at -0.98425 0.9525)
			(size 0.1905 0.1905)
			(layers "B.Cu" "B.Mask" "B.Paste")
			(net "GND")
			(options
				(clearance outline)
				(anchor circle)
			)
			(primitives
				(gr_poly
					(pts
						(arc
							(start -0.1778 -0.5715)
							(mid -0.321484 -0.511984)
							(end -0.381 -0.3683)
						)
						(arc
							(start -0.381 0.3683)
							(mid -0.321484 0.511984)
							(end -0.1778 0.5715)
						)
						(arc
							(start 0.1778 0.5715)
							(mid 0.321484 0.511984)
							(end 0.381 0.3683)
						)
						(arc
							(start 0.381 -0.3683)
							(mid 0.321484 -0.511984)
							(end 0.1778 -0.5715)
						)
					)
					(width 0)
					(fill yes)
				)
			)
		)
	)
	(footprint ""
		(layer "B.Cu")
		(at 119.4562 -15.6972 90)
		(property "Reference" "Q20"
			(at 0 0 90)
			(layer "B.SilkS")
			(hide yes)
			(effects
				(font
					(size 1.27 1.27)
				)
				(justify mirror)
			)
		)
		(property "Value" "2N7002K-1-GP"
			(at -0.127 -8.9662 90)
			(unlocked yes)
			(layer "B.Fab")
			(hide yes)
			(effects
				(font
					(size 1.016 1.016)
					(thickness 0.1524)
				)
				(justify mirror)
			)
		)
		(property "Device Type" "SOT23DGS2D4H44"
			(at -0.127 -10.4902 90)
			(unlocked yes)
			(layer "B.Fab")
			(hide yes)
			(effects
				(font
					(size 1.016 1.016)
					(thickness 0.1524)
				)
				(justify mirror)
			)
		)
		(duplicate_pad_numbers_are_jumpers no)
		(fp_line
			(start 1.651 -1.778)
			(end 1.651 1.778)
			(stroke
				(width 0.1524)
				(type default)
			)
			(layer "B.SilkS")
		)
		(fp_line
			(start -1.651 -1.778)
			(end 1.651 -1.778)
			(stroke
				(width 0.1524)
				(type default)
			)
			(layer "B.SilkS")
		)
		(fp_line
			(start 1.651 1.778)
			(end -1.651 1.778)
			(stroke
				(width 0.1524)
				(type default)
			)
			(layer "B.SilkS")
		)
		(fp_line
			(start -1.651 1.778)
			(end -1.651 -1.778)
			(stroke
				(width 0.1524)
				(type default)
			)
			(layer "B.SilkS")
		)
		(fp_poly
			(pts
				(xy 1.778 1.8796) (xy 1.778 -1.8796) (xy -1.778 -1.8796) (xy -1.778 1.8796)
			)
			(stroke
				(width 0)
				(type default)
			)
			(fill no)
			(layer "B.CrtYd")
		)
		(fp_poly
			(pts
				(xy 1.778 1.8796) (xy 1.778 -1.8796) (xy -1.778 -1.8796) (xy -1.778 1.8796)
			)
			(stroke
				(width 0)
				(type default)
			)
			(fill no)
			(layer "B.Fab")
		)
		(pad "D" smd custom
			(at 0 -0.9525 270)
			(size 0.1905 0.1905)
			(layers "B.Cu" "B.Mask" "B.Paste")
			(net "IOM_ADM1278_EN")
			(options
				(clearance outline)
				(anchor circle)
			)
			(primitives
				(gr_poly
					(pts
						(arc
							(start -0.1778 -0.5715)
							(mid -0.321484 -0.511984)
							(end -0.381 -0.3683)
						)
						(arc
							(start -0.381 0.3683)
							(mid -0.321484 0.511984)
							(end -0.1778 0.5715)
						)
						(arc
							(start 0.1778 0.5715)
							(mid 0.321484 0.511984)
							(end 0.381 0.3683)
						)
						(arc
							(start 0.381 -0.3683)
							(mid 0.321484 -0.511984)
							(end 0.1778 -0.5715)
						)
					)
					(width 0)
					(fill yes)
				)
			)
		)
		(pad "G" smd custom
			(at 0.98425 0.9525 270)
			(size 0.1905 0.1905)
			(layers "B.Cu" "B.Mask" "B.Paste")
			(net "IOM_MATED_N")
			(options
				(clearance outline)
				(anchor circle)
			)
			(primitives
				(gr_poly
					(pts
						(arc
							(start -0.1778 -0.5715)
							(mid -0.321484 -0.511984)
							(end -0.381 -0.3683)
						)
						(arc
							(start -0.381 0.3683)
							(mid -0.321484 0.511984)
							(end -0.1778 0.5715)
						)
						(arc
							(start 0.1778 0.5715)
							(mid 0.321484 0.511984)
							(end 0.381 0.3683)
						)
						(arc
							(start 0.381 -0.3683)
							(mid 0.321484 -0.511984)
							(end 0.1778 -0.5715)
						)
					)
					(width 0)
					(fill yes)
				)
			)
		)
		(pad "S" smd custom
			(at -0.98425 0.9525 270)
			(size 0.1905 0.1905)
			(layers "B.Cu" "B.Mask" "B.Paste")
			(net "GND")
			(options
				(clearance outline)
				(anchor circle)
			)
			(primitives
				(gr_poly
					(pts
						(arc
							(start -0.1778 -0.5715)
							(mid -0.321484 -0.511984)
							(end -0.381 -0.3683)
						)
						(arc
							(start -0.381 0.3683)
							(mid -0.321484 0.511984)
							(end -0.1778 0.5715)
						)
						(arc
							(start 0.1778 0.5715)
							(mid 0.321484 0.511984)
							(end 0.381 0.3683)
						)
						(arc
							(start 0.381 -0.3683)
							(mid 0.321484 -0.511984)
							(end 0.1778 -0.5715)
						)
					)
					(width 0)
					(fill yes)
				)
			)
		)
	)
	(footprint ""
		(layer "B.Cu")
		(at 192.4177 -63.2206 90)
		(property "Reference" "C418"
			(at 0 0 90)
			(layer "B.SilkS")
			(hide yes)
			(effects
				(font
					(size 1.27 1.27)
				)
				(justify mirror)
			)
		)
		(property "Value" "SCD1U6D3V1KX-GP"
			(at 2.8321 -1.7399 90)
			(unlocked yes)
			(layer "B.Fab")
			(hide yes)
			(effects
				(font
					(size 1.016 1.016)
					(thickness 0.1524)
				)
				(justify mirror)
			)
		)
		(property "Device Type" "C0201H13"
			(at 2.8321 -3.2639 90)
			(unlocked yes)
			(layer "B.Fab")
			(hide yes)
			(effects
				(font
					(size 1.016 1.016)
					(thickness 0.1524)
				)
				(justify mirror)
			)
		)
		(duplicate_pad_numbers_are_jumpers no)
		(fp_rect
			(start 0.2794 0.6477)
			(end -0.2794 -0.6477)
			(stroke
				(width 0)
				(type default)
			)
			(fill no)
			(layer "B.CrtYd")
		)
		(fp_rect
			(start 0.2794 0.6477)
			(end -0.2794 -0.6477)
			(stroke
				(width 0)
				(type default)
			)
			(fill no)
			(layer "B.Fab")
		)
		(pad "1" smd custom
			(at 0 -0.2794 270)
			(size 0.0762 0.0762)
			(layers "B.Cu" "B.Mask" "B.Paste")
			(net "P0V975")
			(options
				(clearance outline)
				(anchor circle)
			)
			(primitives
				(gr_poly
					(pts
						(arc
							(start 0.1524 0.127)
							(mid 0.137521 0.162921)
							(end 0.1016 0.1778)
						)
						(arc
							(start -0.1016 0.1778)
							(mid -0.137521 0.162921)
							(end -0.1524 0.127)
						)
						(arc
							(start -0.1524 -0.127)
							(mid -0.137521 -0.162921)
							(end -0.1016 -0.1778)
						)
						(arc
							(start 0.1016 -0.1778)
							(mid 0.137521 -0.162921)
							(end 0.1524 -0.127)
						)
					)
					(width 0)
					(fill yes)
				)
			)
		)
		(pad "2" smd custom
			(at 0 0.2794 270)
			(size 0.0762 0.0762)
			(layers "B.Cu" "B.Mask" "B.Paste")
			(net "GND")
			(options
				(clearance outline)
				(anchor circle)
			)
			(primitives
				(gr_poly
					(pts
						(arc
							(start 0.1524 0.127)
							(mid 0.137521 0.162921)
							(end 0.1016 0.1778)
						)
						(arc
							(start -0.1016 0.1778)
							(mid -0.137521 0.162921)
							(end -0.1524 0.127)
						)
						(arc
							(start -0.1524 -0.127)
							(mid -0.137521 -0.162921)
							(end -0.1016 -0.1778)
						)
						(arc
							(start 0.1016 -0.1778)
							(mid 0.137521 -0.162921)
							(end 0.1524 -0.127)
						)
					)
					(width 0)
					(fill yes)
				)
			)
		)
	)
	(footprint ""
		(layer "B.Cu")
		(at 194.0814 -66.6115 90)
		(property "Reference" "C424"
			(at 0 0 90)
			(layer "B.SilkS")
			(hide yes)
			(effects
				(font
					(size 1.27 1.27)
				)
				(justify mirror)
			)
		)
		(property "Value" "SC1KP50V2KX-1GP"
			(at -1.1811 -2.7051 90)
			(unlocked yes)
			(layer "B.Fab")
			(hide yes)
			(effects
				(font
					(size 1.016 1.016)
					(thickness 0.1524)
				)
				(justify mirror)
			)
		)
		(property "Device Type" "C402H22"
			(at -1.1811 -4.2291 90)
			(unlocked yes)
			(layer "B.Fab")
			(hide yes)
			(effects
				(font
					(size 1.016 1.016)
					(thickness 0.1524)
				)
				(justify mirror)
			)
		)
		(duplicate_pad_numbers_are_jumpers no)
		(fp_rect
			(start 0.4318 0.9525)
			(end -0.4318 -0.9525)
			(stroke
				(width 0)
				(type default)
			)
			(fill no)
			(layer "B.CrtYd")
		)
		(fp_rect
			(start 0.4318 0.9525)
			(end -0.4318 -0.9525)
			(stroke
				(width 0)
				(type default)
			)
			(fill no)
			(layer "B.Fab")
		)
		(pad "1" smd custom
			(at 0 -0.4445 270)
			(size 0.1524 0.1524)
			(layers "B.Cu" "B.Mask" "B.Paste")
			(net "P0V975")
			(options
				(clearance outline)
				(anchor circle)
			)
			(primitives
				(gr_poly
					(pts
						(arc
							(start 0.3048 0.2032)
							(mid 0.275042 0.275042)
							(end 0.2032 0.3048)
						)
						(arc
							(start -0.2032 0.3048)
							(mid -0.275042 0.275042)
							(end -0.3048 0.2032)
						)
						(arc
							(start -0.3048 -0.2032)
							(mid -0.275042 -0.275042)
							(end -0.2032 -0.3048)
						)
						(arc
							(start 0.2032 -0.3048)
							(mid 0.275042 -0.275042)
							(end 0.3048 -0.2032)
						)
					)
					(width 0)
					(fill yes)
				)
			)
		)
		(pad "2" smd custom
			(at 0 0.4445 270)
			(size 0.1524 0.1524)
			(layers "B.Cu" "B.Mask" "B.Paste")
			(net "GND")
			(options
				(clearance outline)
				(anchor circle)
			)
			(primitives
				(gr_poly
					(pts
						(arc
							(start 0.3048 0.2032)
							(mid 0.275042 0.275042)
							(end 0.2032 0.3048)
						)
						(arc
							(start -0.2032 0.3048)
							(mid -0.275042 0.275042)
							(end -0.3048 0.2032)
						)
						(arc
							(start -0.3048 -0.2032)
							(mid -0.275042 -0.275042)
							(end -0.2032 -0.3048)
						)
						(arc
							(start 0.2032 -0.3048)
							(mid 0.275042 -0.275042)
							(end 0.3048 -0.2032)
						)
					)
					(width 0)
					(fill yes)
				)
			)
		)
	)
	(footprint ""
		(layer "B.Cu")
		(at 206.40802 -63.304166 -90)
		(property "Reference" "TP129"
			(at 0 0 90)
			(layer "B.SilkS")
			(hide yes)
			(effects
				(font
					(size 1.27 1.27)
				)
				(justify mirror)
			)
		)
		(property "Value" "TPAD28-2-GP"
			(at 0.0127 -1.6637 270)
			(unlocked yes)
			(layer "B.Fab")
			(hide yes)
			(effects
				(font
					(size 1.016 1.016)
					(thickness 0.1524)
				)
				(justify mirror)
			)
		)
		(property "Device Type" "TPAD28"
			(at 0.0127 -3.1877 270)
			(unlocked yes)
			(layer "B.Fab")
			(hide yes)
			(effects
				(font
					(size 1.016 1.016)
					(thickness 0.1524)
				)
				(justify mirror)
			)
		)
		(duplicate_pad_numbers_are_jumpers no)
		(fp_poly
			(pts
				(arc
					(start 0 -0.3556)
					(mid 0 0.3556)
					(end 0 -0.3556)
				)
			)
			(stroke
				(width 0)
				(type default)
			)
			(fill no)
			(layer "B.CrtYd")
		)
		(fp_poly
			(pts
				(arc
					(start 0 -0.6096)
					(mid 0 0.6096)
					(end 0 -0.6096)
				)
			)
			(stroke
				(width 0)
				(type default)
			)
			(fill no)
			(layer "B.Fab")
		)
		(pad "1" smd circle
			(at 0 0 90)
			(size 0.7112 0.7112)
			(layers "B.Cu" "B.Mask" "B.Paste")
			(net "IOC_SIO_BLINK")
		)
	)
	(footprint ""
		(layer "B.Cu")
		(at 60.793884 -158.261304 180)
		(property "Reference" "L4"
			(at 0 0 0)
			(layer "B.SilkS")
			(hide yes)
			(effects
				(font
					(size 1.27 1.27)
				)
				(justify mirror)
			)
		)
		(property "Value" "MMZ2012S601ATA1N-GP"
			(at 0 -4.2418 180)
			(unlocked yes)
			(layer "B.Fab")
			(hide yes)
			(effects
				(font
					(size 1.016 1.016)
					(thickness 0.1524)
				)
				(justify mirror)
			)
		)
		(property "Device Type" "L805H42"
			(at 0 -5.7912 180)
			(unlocked yes)
			(layer "B.Fab")
			(hide yes)
			(effects
				(font
					(size 1.016 1.016)
					(thickness 0.1524)
				)
				(justify mirror)
			)
		)
		(duplicate_pad_numbers_are_jumpers no)
		(fp_line
			(start 0.889 1.7018)
			(end 0.889 -1.7018)
			(stroke
				(width 0.1524)
				(type default)
			)
			(layer "B.SilkS")
		)
		(fp_line
			(start 0.889 -1.7018)
			(end -0.889 -1.7018)
			(stroke
				(width 0.1524)
				(type default)
			)
			(layer "B.SilkS")
		)
		(fp_line
			(start -0.889 1.7018)
			(end 0.889 1.7018)
			(stroke
				(width 0.1524)
				(type default)
			)
			(layer "B.SilkS")
		)
		(fp_line
			(start -0.889 -1.7018)
			(end -0.889 1.7018)
			(stroke
				(width 0.1524)
				(type default)
			)
			(layer "B.SilkS")
		)
		(fp_rect
			(start 0.9652 1.778)
			(end -0.9652 -1.778)
			(stroke
				(width 0)
				(type default)
			)
			(fill no)
			(layer "B.CrtYd")
		)
		(fp_rect
			(start 0.9652 1.778)
			(end -0.9652 -1.778)
			(stroke
				(width 0)
				(type default)
			)
			(fill no)
			(layer "B.Fab")
		)
		(pad "1" smd rect
			(at 0 -0.9652)
			(size 1.397 1.143)
			(layers "B.Cu" "B.Mask" "B.Paste")
			(net "P3V3_STBY")
		)
		(pad "2" smd rect
			(at 0 0.9652)
			(size 1.397 1.143)
			(layers "B.Cu" "B.Mask" "B.Paste")
			(net "VPLLAV33")
		)
	)
	(footprint ""
		(layer "B.Cu")
		(at 96.52 -152.4254 180)
		(property "Reference" "R42"
			(at 0 0 0)
			(layer "B.SilkS")
			(hide yes)
			(effects
				(font
					(size 1.27 1.27)
				)
				(justify mirror)
			)
		)
		(property "Value" "4K7R2F-GP"
			(at -0.064008 -3.993896 180)
			(unlocked yes)
			(layer "B.Fab")
			(hide yes)
			(effects
				(font
					(size 1.016 1.016)
					(thickness 0.1524)
				)
				(justify mirror)
			)
		)
		(property "Device Type" "R402H16"
			(at -0.064008 -5.517896 180)
			(unlocked yes)
			(layer "B.Fab")
			(hide yes)
			(effects
				(font
					(size 1.016 1.016)
					(thickness 0.1524)
				)
				(justify mirror)
			)
		)
		(duplicate_pad_numbers_are_jumpers no)
		(fp_line
			(start 0.508 -0.9398)
			(end 0.508 0.9398)
			(stroke
				(width 0.1524)
				(type default)
			)
			(layer "B.SilkS")
		)
		(fp_line
			(start -0.508 -0.9398)
			(end 0.508 -0.9398)
			(stroke
				(width 0.1524)
				(type default)
			)
			(layer "B.SilkS")
		)
		(fp_rect
			(start 0.508 0.9398)
			(end -0.508 -0.9398)
			(stroke
				(width 0)
				(type default)
			)
			(fill no)
			(layer "B.CrtYd")
		)
		(fp_rect
			(start 0.508 0.9398)
			(end -0.508 -0.9398)
			(stroke
				(width 0)
				(type default)
			)
			(fill no)
			(layer "B.Fab")
		)
		(pad "1" smd custom
			(at 0 -0.4445)
			(size 0.1397 0.1397)
			(layers "B.Cu" "B.Mask" "B.Paste")
			(net "USB_EN_3")
			(options
				(clearance outline)
				(anchor circle)
			)
			(primitives
				(gr_poly
					(pts
						(arc
							(start -0.1778 0.2794)
							(mid -0.249642 0.249642)
							(end -0.2794 0.1778)
						)
						(arc
							(start -0.2794 -0.1778)
							(mid -0.249642 -0.249642)
							(end -0.1778 -0.2794)
						)
						(arc
							(start 0.1778 -0.2794)
							(mid 0.249642 -0.249642)
							(end 0.2794 -0.1778)
						)
						(arc
							(start 0.2794 0.1778)
							(mid 0.249642 0.249642)
							(end 0.1778 0.2794)
						)
					)
					(width 0)
					(fill yes)
				)
			)
		)
		(pad "2" smd custom
			(at 0 0.4445)
			(size 0.1397 0.1397)
			(layers "B.Cu" "B.Mask" "B.Paste")
			(net "GND")
			(options
				(clearance outline)
				(anchor circle)
			)
			(primitives
				(gr_poly
					(pts
						(arc
							(start -0.1778 0.2794)
							(mid -0.249642 0.249642)
							(end -0.2794 0.1778)
						)
						(arc
							(start -0.2794 -0.1778)
							(mid -0.249642 -0.249642)
							(end -0.1778 -0.2794)
						)
						(arc
							(start 0.1778 -0.2794)
							(mid 0.249642 -0.249642)
							(end 0.2794 -0.1778)
						)
						(arc
							(start 0.2794 0.1778)
							(mid 0.249642 0.249642)
							(end 0.1778 0.2794)
						)
					)
					(width 0)
					(fill yes)
				)
			)
		)
	)
	(footprint ""
		(layer "B.Cu")
		(at 56.983884 -158.44393 180)
		(property "Reference" "C96"
			(at 0 0 0)
			(layer "B.SilkS")
			(hide yes)
			(effects
				(font
					(size 1.27 1.27)
				)
				(justify mirror)
			)
		)
		(property "Value" "SC100P50V2JN-3GP"
			(at -1.1811 -2.7051 180)
			(unlocked yes)
			(layer "B.Fab")
			(hide yes)
			(effects
				(font
					(size 1.016 1.016)
					(thickness 0.1524)
				)
				(justify mirror)
			)
		)
		(property "Device Type" "C402H22"
			(at -1.1811 -4.2291 180)
			(unlocked yes)
			(layer "B.Fab")
			(hide yes)
			(effects
				(font
					(size 1.016 1.016)
					(thickness 0.1524)
				)
				(justify mirror)
			)
		)
		(duplicate_pad_numbers_are_jumpers no)
		(fp_rect
			(start 0.4318 0.9525)
			(end -0.4318 -0.9525)
			(stroke
				(width 0)
				(type default)
			)
			(fill no)
			(layer "B.CrtYd")
		)
		(fp_rect
			(start 0.4318 0.9525)
			(end -0.4318 -0.9525)
			(stroke
				(width 0)
				(type default)
			)
			(fill no)
			(layer "B.Fab")
		)
		(pad "1" smd custom
			(at 0 -0.4445)
			(size 0.1524 0.1524)
			(layers "B.Cu" "B.Mask" "B.Paste")
			(net "VPLLAV33")
			(options
				(clearance outline)
				(anchor circle)
			)
			(primitives
				(gr_poly
					(pts
						(arc
							(start 0.3048 0.2032)
							(mid 0.275042 0.275042)
							(end 0.2032 0.3048)
						)
						(arc
							(start -0.2032 0.3048)
							(mid -0.275042 0.275042)
							(end -0.3048 0.2032)
						)
						(arc
							(start -0.3048 -0.2032)
							(mid -0.275042 -0.275042)
							(end -0.2032 -0.3048)
						)
						(arc
							(start 0.2032 -0.3048)
							(mid 0.275042 -0.275042)
							(end 0.3048 -0.2032)
						)
					)
					(width 0)
					(fill yes)
				)
			)
		)
		(pad "2" smd custom
			(at 0 0.4445)
			(size 0.1524 0.1524)
			(layers "B.Cu" "B.Mask" "B.Paste")
			(net "GND")
			(options
				(clearance outline)
				(anchor circle)
			)
			(primitives
				(gr_poly
					(pts
						(arc
							(start 0.3048 0.2032)
							(mid 0.275042 0.275042)
							(end 0.2032 0.3048)
						)
						(arc
							(start -0.2032 0.3048)
							(mid -0.275042 0.275042)
							(end -0.3048 0.2032)
						)
						(arc
							(start -0.3048 -0.2032)
							(mid -0.275042 -0.275042)
							(end -0.2032 -0.3048)
						)
						(arc
							(start 0.2032 -0.3048)
							(mid 0.275042 -0.275042)
							(end 0.3048 -0.2032)
						)
					)
					(width 0)
					(fill yes)
				)
			)
		)
	)
	(footprint ""
		(layer "B.Cu")
		(at 164.465 -51.2064)
		(property "Reference" "C329"
			(at 0 0 0)
			(layer "B.SilkS")
			(hide yes)
			(effects
				(font
					(size 1.27 1.27)
				)
				(justify mirror)
			)
		)
		(property "Value" "SCD1U16V2KX-3GP"
			(at -1.1811 -2.7051 0)
			(unlocked yes)
			(layer "B.Fab")
			(hide yes)
			(effects
				(font
					(size 1.016 1.016)
					(thickness 0.1524)
				)
				(justify mirror)
			)
		)
		(property "Device Type" "C402H22"
			(at -1.1811 -4.2291 0)
			(unlocked yes)
			(layer "B.Fab")
			(hide yes)
			(effects
				(font
					(size 1.016 1.016)
					(thickness 0.1524)
				)
				(justify mirror)
			)
		)
		(duplicate_pad_numbers_are_jumpers no)
		(fp_rect
			(start 0.4318 0.9525)
			(end -0.4318 -0.9525)
			(stroke
				(width 0)
				(type default)
			)
			(fill no)
			(layer "B.CrtYd")
		)
		(fp_rect
			(start 0.4318 0.9525)
			(end -0.4318 -0.9525)
			(stroke
				(width 0)
				(type default)
			)
			(fill no)
			(layer "B.Fab")
		)
		(pad "1" smd custom
			(at 0 -0.4445 180)
			(size 0.1524 0.1524)
			(layers "B.Cu" "B.Mask" "B.Paste")
			(net "P3V3_STBY")
			(options
				(clearance outline)
				(anchor circle)
			)
			(primitives
				(gr_poly
					(pts
						(arc
							(start 0.3048 0.2032)
							(mid 0.275042 0.275042)
							(end 0.2032 0.3048)
						)
						(arc
							(start -0.2032 0.3048)
							(mid -0.275042 0.275042)
							(end -0.3048 0.2032)
						)
						(arc
							(start -0.3048 -0.2032)
							(mid -0.275042 -0.275042)
							(end -0.2032 -0.3048)
						)
						(arc
							(start 0.2032 -0.3048)
							(mid 0.275042 -0.275042)
							(end 0.3048 -0.2032)
						)
					)
					(width 0)
					(fill yes)
				)
			)
		)
		(pad "2" smd custom
			(at 0 0.4445 180)
			(size 0.1524 0.1524)
			(layers "B.Cu" "B.Mask" "B.Paste")
			(net "GND")
			(options
				(clearance outline)
				(anchor circle)
			)
			(primitives
				(gr_poly
					(pts
						(arc
							(start 0.3048 0.2032)
							(mid 0.275042 0.275042)
							(end 0.2032 0.3048)
						)
						(arc
							(start -0.2032 0.3048)
							(mid -0.275042 0.275042)
							(end -0.3048 0.2032)
						)
						(arc
							(start -0.3048 -0.2032)
							(mid -0.275042 -0.275042)
							(end -0.2032 -0.3048)
						)
						(arc
							(start 0.2032 -0.3048)
							(mid 0.275042 -0.275042)
							(end 0.3048 -0.2032)
						)
					)
					(width 0)
					(fill yes)
				)
			)
		)
	)
	(footprint ""
		(layer "B.Cu")
		(at 57.1246 -150.6728 -90)
		(property "Reference" "R388"
			(at 0 0 90)
			(layer "B.SilkS")
			(hide yes)
			(effects
				(font
					(size 1.27 1.27)
				)
				(justify mirror)
			)
		)
		(property "Value" "4K7R2F-GP"
			(at -0.064008 -3.993896 270)
			(unlocked yes)
			(layer "B.Fab")
			(hide yes)
			(effects
				(font
					(size 1.016 1.016)
					(thickness 0.1524)
				)
				(justify mirror)
			)
		)
		(property "Device Type" "R402H16"
			(at -0.064008 -5.517896 270)
			(unlocked yes)
			(layer "B.Fab")
			(hide yes)
			(effects
				(font
					(size 1.016 1.016)
					(thickness 0.1524)
				)
				(justify mirror)
			)
		)
		(duplicate_pad_numbers_are_jumpers no)
		(fp_line
			(start -0.508 -0.9398)
			(end 0.508 -0.9398)
			(stroke
				(width 0.1524)
				(type default)
			)
			(layer "B.SilkS")
		)
		(fp_line
			(start 0.508 -0.9398)
			(end 0.508 0.9398)
			(stroke
				(width 0.1524)
				(type default)
			)
			(layer "B.SilkS")
		)
		(fp_rect
			(start 0.508 0.9398)
			(end -0.508 -0.9398)
			(stroke
				(width 0)
				(type default)
			)
			(fill no)
			(layer "B.CrtYd")
		)
		(fp_rect
			(start 0.508 0.9398)
			(end -0.508 -0.9398)
			(stroke
				(width 0)
				(type default)
			)
			(fill no)
			(layer "B.Fab")
		)
		(pad "1" smd custom
			(at 0 -0.4445 90)
			(size 0.1397 0.1397)
			(layers "B.Cu" "B.Mask" "B.Paste")
			(net "GND")
			(options
				(clearance outline)
				(anchor circle)
			)
			(primitives
				(gr_poly
					(pts
						(arc
							(start -0.1778 0.2794)
							(mid -0.249642 0.249642)
							(end -0.2794 0.1778)
						)
						(arc
							(start -0.2794 -0.1778)
							(mid -0.249642 -0.249642)
							(end -0.1778 -0.2794)
						)
						(arc
							(start 0.1778 -0.2794)
							(mid 0.249642 -0.249642)
							(end 0.2794 -0.1778)
						)
						(arc
							(start 0.2794 0.1778)
							(mid 0.249642 0.249642)
							(end 0.1778 0.2794)
						)
					)
					(width 0)
					(fill yes)
				)
			)
		)
		(pad "2" smd custom
			(at 0 0.4445 90)
			(size 0.1397 0.1397)
			(layers "B.Cu" "B.Mask" "B.Paste")
			(net "MAC1_TXD2")
			(options
				(clearance outline)
				(anchor circle)
			)
			(primitives
				(gr_poly
					(pts
						(arc
							(start -0.1778 0.2794)
							(mid -0.249642 0.249642)
							(end -0.2794 0.1778)
						)
						(arc
							(start -0.2794 -0.1778)
							(mid -0.249642 -0.249642)
							(end -0.1778 -0.2794)
						)
						(arc
							(start 0.1778 -0.2794)
							(mid 0.249642 -0.249642)
							(end 0.2794 -0.1778)
						)
						(arc
							(start 0.2794 0.1778)
							(mid 0.249642 0.249642)
							(end 0.1778 0.2794)
						)
					)
					(width 0)
					(fill yes)
				)
			)
		)
	)
	(footprint ""
		(layer "B.Cu")
		(at 24.8666 -129.1082 180)
		(property "Reference" "R244"
			(at 0 0 0)
			(layer "B.SilkS")
			(hide yes)
			(effects
				(font
					(size 1.27 1.27)
				)
				(justify mirror)
			)
		)
		(property "Value" "120R2F-GP"
			(at -0.064008 -3.993896 180)
			(unlocked yes)
			(layer "B.Fab")
			(hide yes)
			(effects
				(font
					(size 1.016 1.016)
					(thickness 0.1524)
				)
				(justify mirror)
			)
		)
		(property "Device Type" "R402H16"
			(at -0.064008 -5.517896 180)
			(unlocked yes)
			(layer "B.Fab")
			(hide yes)
			(effects
				(font
					(size 1.016 1.016)
					(thickness 0.1524)
				)
				(justify mirror)
			)
		)
		(duplicate_pad_numbers_are_jumpers no)
		(fp_line
			(start 0.508 -0.9398)
			(end 0.508 0.9398)
			(stroke
				(width 0.1524)
				(type default)
			)
			(layer "B.SilkS")
		)
		(fp_line
			(start -0.508 -0.9398)
			(end 0.508 -0.9398)
			(stroke
				(width 0.1524)
				(type default)
			)
			(layer "B.SilkS")
		)
		(fp_rect
			(start 0.508 0.9398)
			(end -0.508 -0.9398)
			(stroke
				(width 0)
				(type default)
			)
			(fill no)
			(layer "B.CrtYd")
		)
		(fp_rect
			(start 0.508 0.9398)
			(end -0.508 -0.9398)
			(stroke
				(width 0)
				(type default)
			)
			(fill no)
			(layer "B.Fab")
		)
		(pad "1" smd custom
			(at 0 -0.4445)
			(size 0.1397 0.1397)
			(layers "B.Cu" "B.Mask" "B.Paste")
			(net "GND")
			(options
				(clearance outline)
				(anchor circle)
			)
			(primitives
				(gr_poly
					(pts
						(arc
							(start -0.1778 0.2794)
							(mid -0.249642 0.249642)
							(end -0.2794 0.1778)
						)
						(arc
							(start -0.2794 -0.1778)
							(mid -0.249642 -0.249642)
							(end -0.1778 -0.2794)
						)
						(arc
							(start 0.1778 -0.2794)
							(mid 0.249642 -0.249642)
							(end 0.2794 -0.1778)
						)
						(arc
							(start 0.2794 0.1778)
							(mid 0.249642 0.249642)
							(end 0.1778 0.2794)
						)
					)
					(width 0)
					(fill yes)
				)
			)
		)
		(pad "2" smd custom
			(at 0 0.4445)
			(size 0.1397 0.1397)
			(layers "B.Cu" "B.Mask" "B.Paste")
			(net "MEMA_5")
			(options
				(clearance outline)
				(anchor circle)
			)
			(primitives
				(gr_poly
					(pts
						(arc
							(start -0.1778 0.2794)
							(mid -0.249642 0.249642)
							(end -0.2794 0.1778)
						)
						(arc
							(start -0.2794 -0.1778)
							(mid -0.249642 -0.249642)
							(end -0.1778 -0.2794)
						)
						(arc
							(start 0.1778 -0.2794)
							(mid 0.249642 -0.249642)
							(end 0.2794 -0.1778)
						)
						(arc
							(start 0.2794 0.1778)
							(mid 0.249642 0.249642)
							(end 0.1778 0.2794)
						)
					)
					(width 0)
					(fill yes)
				)
			)
		)
	)
	(footprint ""
		(layer "B.Cu")
		(at 186.51728 -73.1901 90)
		(property "Reference" "C451"
			(at 0 0 90)
			(layer "B.SilkS")
			(hide yes)
			(effects
				(font
					(size 1.27 1.27)
				)
				(justify mirror)
			)
		)
		(property "Value" "SCD1U16V2KX-3GP"
			(at -1.1811 -2.7051 90)
			(unlocked yes)
			(layer "B.Fab")
			(hide yes)
			(effects
				(font
					(size 1.016 1.016)
					(thickness 0.1524)
				)
				(justify mirror)
			)
		)
		(property "Device Type" "C402H22"
			(at -1.1811 -4.2291 90)
			(unlocked yes)
			(layer "B.Fab")
			(hide yes)
			(effects
				(font
					(size 1.016 1.016)
					(thickness 0.1524)
				)
				(justify mirror)
			)
		)
		(duplicate_pad_numbers_are_jumpers no)
		(fp_rect
			(start 0.4318 0.9525)
			(end -0.4318 -0.9525)
			(stroke
				(width 0)
				(type default)
			)
			(fill no)
			(layer "B.CrtYd")
		)
		(fp_rect
			(start 0.4318 0.9525)
			(end -0.4318 -0.9525)
			(stroke
				(width 0)
				(type default)
			)
			(fill no)
			(layer "B.Fab")
		)
		(pad "1" smd custom
			(at 0 -0.4445 270)
			(size 0.1524 0.1524)
			(layers "B.Cu" "B.Mask" "B.Paste")
			(net "P1V8")
			(options
				(clearance outline)
				(anchor circle)
			)
			(primitives
				(gr_poly
					(pts
						(arc
							(start 0.3048 0.2032)
							(mid 0.275042 0.275042)
							(end 0.2032 0.3048)
						)
						(arc
							(start -0.2032 0.3048)
							(mid -0.275042 0.275042)
							(end -0.3048 0.2032)
						)
						(arc
							(start -0.3048 -0.2032)
							(mid -0.275042 -0.275042)
							(end -0.2032 -0.3048)
						)
						(arc
							(start 0.2032 -0.3048)
							(mid 0.275042 -0.275042)
							(end 0.3048 -0.2032)
						)
					)
					(width 0)
					(fill yes)
				)
			)
		)
		(pad "2" smd custom
			(at 0 0.4445 270)
			(size 0.1524 0.1524)
			(layers "B.Cu" "B.Mask" "B.Paste")
			(net "GND")
			(options
				(clearance outline)
				(anchor circle)
			)
			(primitives
				(gr_poly
					(pts
						(arc
							(start 0.3048 0.2032)
							(mid 0.275042 0.275042)
							(end 0.2032 0.3048)
						)
						(arc
							(start -0.2032 0.3048)
							(mid -0.275042 0.275042)
							(end -0.3048 0.2032)
						)
						(arc
							(start -0.3048 -0.2032)
							(mid -0.275042 -0.275042)
							(end -0.2032 -0.3048)
						)
						(arc
							(start 0.2032 -0.3048)
							(mid 0.275042 -0.275042)
							(end 0.3048 -0.2032)
						)
					)
					(width 0)
					(fill yes)
				)
			)
		)
	)
	(footprint ""
		(layer "B.Cu")
		(at 185.98642 -78.630526)
		(property "Reference" "R620"
			(at 0 0 0)
			(layer "B.SilkS")
			(hide yes)
			(effects
				(font
					(size 1.27 1.27)
				)
				(justify mirror)
			)
		)
		(property "Value" "4K7R2F-GP"
			(at -0.064008 -3.993896 0)
			(unlocked yes)
			(layer "B.Fab")
			(hide yes)
			(effects
				(font
					(size 1.016 1.016)
					(thickness 0.1524)
				)
				(justify mirror)
			)
		)
		(property "Device Type" "R402H16"
			(at -0.064008 -5.517896 0)
			(unlocked yes)
			(layer "B.Fab")
			(hide yes)
			(effects
				(font
					(size 1.016 1.016)
					(thickness 0.1524)
				)
				(justify mirror)
			)
		)
		(duplicate_pad_numbers_are_jumpers no)
		(fp_line
			(start -0.508 -0.9398)
			(end 0.508 -0.9398)
			(stroke
				(width 0.1524)
				(type default)
			)
			(layer "B.SilkS")
		)
		(fp_line
			(start 0.508 -0.9398)
			(end 0.508 0.9398)
			(stroke
				(width 0.1524)
				(type default)
			)
			(layer "B.SilkS")
		)
		(fp_rect
			(start 0.508 0.9398)
			(end -0.508 -0.9398)
			(stroke
				(width 0)
				(type default)
			)
			(fill no)
			(layer "B.CrtYd")
		)
		(fp_rect
			(start 0.508 0.9398)
			(end -0.508 -0.9398)
			(stroke
				(width 0)
				(type default)
			)
			(fill no)
			(layer "B.Fab")
		)
		(pad "1" smd custom
			(at 0 -0.4445 180)
			(size 0.1397 0.1397)
			(layers "B.Cu" "B.Mask" "B.Paste")
			(net "P1V8")
			(options
				(clearance outline)
				(anchor circle)
			)
			(primitives
				(gr_poly
					(pts
						(arc
							(start -0.1778 0.2794)
							(mid -0.249642 0.249642)
							(end -0.2794 0.1778)
						)
						(arc
							(start -0.2794 -0.1778)
							(mid -0.249642 -0.249642)
							(end -0.1778 -0.2794)
						)
						(arc
							(start 0.1778 -0.2794)
							(mid 0.249642 -0.249642)
							(end 0.2794 -0.1778)
						)
						(arc
							(start 0.2794 0.1778)
							(mid 0.249642 0.249642)
							(end 0.1778 0.2794)
						)
					)
					(width 0)
					(fill yes)
				)
			)
		)
		(pad "2" smd custom
			(at 0 0.4445 180)
			(size 0.1397 0.1397)
			(layers "B.Cu" "B.Mask" "B.Paste")
			(net "IOC_UART_1_RX")
			(options
				(clearance outline)
				(anchor circle)
			)
			(primitives
				(gr_poly
					(pts
						(arc
							(start -0.1778 0.2794)
							(mid -0.249642 0.249642)
							(end -0.2794 0.1778)
						)
						(arc
							(start -0.2794 -0.1778)
							(mid -0.249642 -0.249642)
							(end -0.1778 -0.2794)
						)
						(arc
							(start 0.1778 -0.2794)
							(mid 0.249642 -0.249642)
							(end 0.2794 -0.1778)
						)
						(arc
							(start 0.2794 0.1778)
							(mid 0.249642 0.249642)
							(end 0.1778 0.2794)
						)
					)
					(width 0)
					(fill yes)
				)
			)
		)
	)
	(footprint ""
		(layer "B.Cu")
		(at 36.9316 -135.7122 180)
		(property "Reference" "R277"
			(at 0 0 0)
			(layer "B.SilkS")
			(hide yes)
			(effects
				(font
					(size 1.27 1.27)
				)
				(justify mirror)
			)
		)
		(property "Value" "33R2F-3-GP"
			(at -0.064008 -3.993896 180)
			(unlocked yes)
			(layer "B.Fab")
			(hide yes)
			(effects
				(font
					(size 1.016 1.016)
					(thickness 0.1524)
				)
				(justify mirror)
			)
		)
		(property "Device Type" "R402H16"
			(at -0.064008 -5.517896 180)
			(unlocked yes)
			(layer "B.Fab")
			(hide yes)
			(effects
				(font
					(size 1.016 1.016)
					(thickness 0.1524)
				)
				(justify mirror)
			)
		)
		(duplicate_pad_numbers_are_jumpers no)
		(fp_line
			(start 0.508 -0.9398)
			(end 0.508 0.9398)
			(stroke
				(width 0.1524)
				(type default)
			)
			(layer "B.SilkS")
		)
		(fp_line
			(start -0.508 -0.9398)
			(end 0.508 -0.9398)
			(stroke
				(width 0.1524)
				(type default)
			)
			(layer "B.SilkS")
		)
		(fp_rect
			(start 0.508 0.9398)
			(end -0.508 -0.9398)
			(stroke
				(width 0)
				(type default)
			)
			(fill no)
			(layer "B.CrtYd")
		)
		(fp_rect
			(start 0.508 0.9398)
			(end -0.508 -0.9398)
			(stroke
				(width 0)
				(type default)
			)
			(fill no)
			(layer "B.Fab")
		)
		(pad "1" smd custom
			(at 0 -0.4445)
			(size 0.1397 0.1397)
			(layers "B.Cu" "B.Mask" "B.Paste")
			(net "FLA_CS_1_R")
			(options
				(clearance outline)
				(anchor circle)
			)
			(primitives
				(gr_poly
					(pts
						(arc
							(start -0.1778 0.2794)
							(mid -0.249642 0.249642)
							(end -0.2794 0.1778)
						)
						(arc
							(start -0.2794 -0.1778)
							(mid -0.249642 -0.249642)
							(end -0.1778 -0.2794)
						)
						(arc
							(start 0.1778 -0.2794)
							(mid 0.249642 -0.249642)
							(end 0.2794 -0.1778)
						)
						(arc
							(start 0.2794 0.1778)
							(mid 0.249642 0.249642)
							(end 0.1778 0.2794)
						)
					)
					(width 0)
					(fill yes)
				)
			)
		)
		(pad "2" smd custom
			(at 0 0.4445)
			(size 0.1397 0.1397)
			(layers "B.Cu" "B.Mask" "B.Paste")
			(net "FLA_CS_1")
			(options
				(clearance outline)
				(anchor circle)
			)
			(primitives
				(gr_poly
					(pts
						(arc
							(start -0.1778 0.2794)
							(mid -0.249642 0.249642)
							(end -0.2794 0.1778)
						)
						(arc
							(start -0.2794 -0.1778)
							(mid -0.249642 -0.249642)
							(end -0.1778 -0.2794)
						)
						(arc
							(start 0.1778 -0.2794)
							(mid 0.249642 -0.249642)
							(end 0.2794 -0.1778)
						)
						(arc
							(start 0.2794 0.1778)
							(mid 0.249642 0.249642)
							(end 0.1778 0.2794)
						)
					)
					(width 0)
					(fill yes)
				)
			)
		)
	)
	(footprint ""
		(layer "B.Cu")
		(at 203.8604 -62.6872 90)
		(property "Reference" "C456"
			(at 0 0 90)
			(layer "B.SilkS")
			(hide yes)
			(effects
				(font
					(size 1.27 1.27)
				)
				(justify mirror)
			)
		)
		(property "Value" "SCD1U16V2KX-3GP"
			(at -1.1811 -2.7051 90)
			(unlocked yes)
			(layer "B.Fab")
			(hide yes)
			(effects
				(font
					(size 1.016 1.016)
					(thickness 0.1524)
				)
				(justify mirror)
			)
		)
		(property "Device Type" "C402H22"
			(at -1.1811 -4.2291 90)
			(unlocked yes)
			(layer "B.Fab")
			(hide yes)
			(effects
				(font
					(size 1.016 1.016)
					(thickness 0.1524)
				)
				(justify mirror)
			)
		)
		(duplicate_pad_numbers_are_jumpers no)
		(fp_rect
			(start 0.4318 0.9525)
			(end -0.4318 -0.9525)
			(stroke
				(width 0)
				(type default)
			)
			(fill no)
			(layer "B.CrtYd")
		)
		(fp_rect
			(start 0.4318 0.9525)
			(end -0.4318 -0.9525)
			(stroke
				(width 0)
				(type default)
			)
			(fill no)
			(layer "B.Fab")
		)
		(pad "1" smd custom
			(at 0 -0.4445 270)
			(size 0.1524 0.1524)
			(layers "B.Cu" "B.Mask" "B.Paste")
			(net "P1V8")
			(options
				(clearance outline)
				(anchor circle)
			)
			(primitives
				(gr_poly
					(pts
						(arc
							(start 0.3048 0.2032)
							(mid 0.275042 0.275042)
							(end 0.2032 0.3048)
						)
						(arc
							(start -0.2032 0.3048)
							(mid -0.275042 0.275042)
							(end -0.3048 0.2032)
						)
						(arc
							(start -0.3048 -0.2032)
							(mid -0.275042 -0.275042)
							(end -0.2032 -0.3048)
						)
						(arc
							(start 0.2032 -0.3048)
							(mid 0.275042 -0.275042)
							(end 0.3048 -0.2032)
						)
					)
					(width 0)
					(fill yes)
				)
			)
		)
		(pad "2" smd custom
			(at 0 0.4445 270)
			(size 0.1524 0.1524)
			(layers "B.Cu" "B.Mask" "B.Paste")
			(net "GND")
			(options
				(clearance outline)
				(anchor circle)
			)
			(primitives
				(gr_poly
					(pts
						(arc
							(start 0.3048 0.2032)
							(mid 0.275042 0.275042)
							(end 0.2032 0.3048)
						)
						(arc
							(start -0.2032 0.3048)
							(mid -0.275042 0.275042)
							(end -0.3048 0.2032)
						)
						(arc
							(start -0.3048 -0.2032)
							(mid -0.275042 -0.275042)
							(end -0.2032 -0.3048)
						)
						(arc
							(start 0.2032 -0.3048)
							(mid 0.275042 -0.275042)
							(end 0.3048 -0.2032)
						)
					)
					(width 0)
					(fill yes)
				)
			)
		)
	)
	(footprint ""
		(layer "B.Cu")
		(at 184.055766 -60.379356 90)
		(property "Reference" "C478"
			(at 0 0 90)
			(layer "B.SilkS")
			(hide yes)
			(effects
				(font
					(size 1.27 1.27)
				)
				(justify mirror)
			)
		)
		(property "Value" "SC1KP50V2KX-1GP"
			(at -1.1811 -2.7051 90)
			(unlocked yes)
			(layer "B.Fab")
			(hide yes)
			(effects
				(font
					(size 1.016 1.016)
					(thickness 0.1524)
				)
				(justify mirror)
			)
		)
		(property "Device Type" "C402H22"
			(at -1.1811 -4.2291 90)
			(unlocked yes)
			(layer "B.Fab")
			(hide yes)
			(effects
				(font
					(size 1.016 1.016)
					(thickness 0.1524)
				)
				(justify mirror)
			)
		)
		(duplicate_pad_numbers_are_jumpers no)
		(fp_rect
			(start 0.4318 0.9525)
			(end -0.4318 -0.9525)
			(stroke
				(width 0)
				(type default)
			)
			(fill no)
			(layer "B.CrtYd")
		)
		(fp_rect
			(start 0.4318 0.9525)
			(end -0.4318 -0.9525)
			(stroke
				(width 0)
				(type default)
			)
			(fill no)
			(layer "B.Fab")
		)
		(pad "1" smd custom
			(at 0 -0.4445 270)
			(size 0.1524 0.1524)
			(layers "B.Cu" "B.Mask" "B.Paste")
			(net "P1V8")
			(options
				(clearance outline)
				(anchor circle)
			)
			(primitives
				(gr_poly
					(pts
						(arc
							(start 0.3048 0.2032)
							(mid 0.275042 0.275042)
							(end 0.2032 0.3048)
						)
						(arc
							(start -0.2032 0.3048)
							(mid -0.275042 0.275042)
							(end -0.3048 0.2032)
						)
						(arc
							(start -0.3048 -0.2032)
							(mid -0.275042 -0.275042)
							(end -0.2032 -0.3048)
						)
						(arc
							(start 0.2032 -0.3048)
							(mid 0.275042 -0.275042)
							(end 0.3048 -0.2032)
						)
					)
					(width 0)
					(fill yes)
				)
			)
		)
		(pad "2" smd custom
			(at 0 0.4445 270)
			(size 0.1524 0.1524)
			(layers "B.Cu" "B.Mask" "B.Paste")
			(net "GND")
			(options
				(clearance outline)
				(anchor circle)
			)
			(primitives
				(gr_poly
					(pts
						(arc
							(start 0.3048 0.2032)
							(mid 0.275042 0.275042)
							(end 0.2032 0.3048)
						)
						(arc
							(start -0.2032 0.3048)
							(mid -0.275042 0.275042)
							(end -0.3048 0.2032)
						)
						(arc
							(start -0.3048 -0.2032)
							(mid -0.275042 -0.275042)
							(end -0.2032 -0.3048)
						)
						(arc
							(start 0.2032 -0.3048)
							(mid 0.275042 -0.275042)
							(end 0.3048 -0.2032)
						)
					)
					(width 0)
					(fill yes)
				)
			)
		)
	)
	(footprint ""
		(layer "B.Cu")
		(at 204.815948 -49.779682 -90)
		(property "Reference" "C339"
			(at 0 0 90)
			(layer "B.SilkS")
			(hide yes)
			(effects
				(font
					(size 1.27 1.27)
				)
				(justify mirror)
			)
		)
		(property "Value" "SC10U6D3V5KX-4GP"
			(at 0.0762 -6.1214 270)
			(unlocked yes)
			(layer "B.Fab")
			(hide yes)
			(effects
				(font
					(size 1.016 1.016)
					(thickness 0.1524)
				)
				(justify mirror)
			)
		)
		(property "Device Type" "C805H58"
			(at 0.0762 -8.1534 270)
			(unlocked yes)
			(layer "B.Fab")
			(hide yes)
			(effects
				(font
					(size 1.016 1.016)
					(thickness 0.1524)
				)
				(justify mirror)
			)
		)
		(duplicate_pad_numbers_are_jumpers no)
		(fp_line
			(start -0.635 0)
			(end 0.635 0)
			(stroke
				(width 0.508)
				(type default)
			)
			(layer "B.SilkS")
		)
		(fp_rect
			(start 0.9652 1.778)
			(end -0.9652 -1.778)
			(stroke
				(width 0)
				(type default)
			)
			(fill no)
			(layer "B.CrtYd")
		)
		(fp_poly
			(pts
				(xy 0.9652 -1.778) (xy -0.9652 -1.778) (xy -0.9652 1.778) (xy 0.9652 1.778)
			)
			(stroke
				(width 0)
				(type default)
			)
			(fill no)
			(layer "B.Fab")
		)
		(pad "1" smd rect
			(at 0 -0.9652 90)
			(size 1.397 1.143)
			(layers "B.Cu" "B.Mask" "B.Paste")
			(net "SHELL_PLL_VDD")
		)
		(pad "2" smd rect
			(at 0 0.9652 90)
			(size 1.397 1.143)
			(layers "B.Cu" "B.Mask" "B.Paste")
			(net "GND")
		)
	)
	(footprint ""
		(layer "B.Cu")
		(at 24.869902 -131.007358 180)
		(property "Reference" "R245"
			(at 0 0 0)
			(layer "B.SilkS")
			(hide yes)
			(effects
				(font
					(size 1.27 1.27)
				)
				(justify mirror)
			)
		)
		(property "Value" "120R2F-GP"
			(at -0.064008 -3.993896 180)
			(unlocked yes)
			(layer "B.Fab")
			(hide yes)
			(effects
				(font
					(size 1.016 1.016)
					(thickness 0.1524)
				)
				(justify mirror)
			)
		)
		(property "Device Type" "R402H16"
			(at -0.064008 -5.517896 180)
			(unlocked yes)
			(layer "B.Fab")
			(hide yes)
			(effects
				(font
					(size 1.016 1.016)
					(thickness 0.1524)
				)
				(justify mirror)
			)
		)
		(duplicate_pad_numbers_are_jumpers no)
		(fp_line
			(start 0.508 -0.9398)
			(end 0.508 0.9398)
			(stroke
				(width 0.1524)
				(type default)
			)
			(layer "B.SilkS")
		)
		(fp_line
			(start -0.508 -0.9398)
			(end 0.508 -0.9398)
			(stroke
				(width 0.1524)
				(type default)
			)
			(layer "B.SilkS")
		)
		(fp_rect
			(start 0.508 0.9398)
			(end -0.508 -0.9398)
			(stroke
				(width 0)
				(type default)
			)
			(fill no)
			(layer "B.CrtYd")
		)
		(fp_rect
			(start 0.508 0.9398)
			(end -0.508 -0.9398)
			(stroke
				(width 0)
				(type default)
			)
			(fill no)
			(layer "B.Fab")
		)
		(pad "1" smd custom
			(at 0 -0.4445)
			(size 0.1397 0.1397)
			(layers "B.Cu" "B.Mask" "B.Paste")
			(net "MEMA_5")
			(options
				(clearance outline)
				(anchor circle)
			)
			(primitives
				(gr_poly
					(pts
						(arc
							(start -0.1778 0.2794)
							(mid -0.249642 0.249642)
							(end -0.2794 0.1778)
						)
						(arc
							(start -0.2794 -0.1778)
							(mid -0.249642 -0.249642)
							(end -0.1778 -0.2794)
						)
						(arc
							(start 0.1778 -0.2794)
							(mid 0.249642 -0.249642)
							(end 0.2794 -0.1778)
						)
						(arc
							(start 0.2794 0.1778)
							(mid 0.249642 0.249642)
							(end 0.1778 0.2794)
						)
					)
					(width 0)
					(fill yes)
				)
			)
		)
		(pad "2" smd custom
			(at 0 0.4445)
			(size 0.1397 0.1397)
			(layers "B.Cu" "B.Mask" "B.Paste")
			(net "P1V2_STBY")
			(options
				(clearance outline)
				(anchor circle)
			)
			(primitives
				(gr_poly
					(pts
						(arc
							(start -0.1778 0.2794)
							(mid -0.249642 0.249642)
							(end -0.2794 0.1778)
						)
						(arc
							(start -0.2794 -0.1778)
							(mid -0.249642 -0.249642)
							(end -0.1778 -0.2794)
						)
						(arc
							(start 0.1778 -0.2794)
							(mid 0.249642 -0.249642)
							(end 0.2794 -0.1778)
						)
						(arc
							(start 0.2794 0.1778)
							(mid 0.249642 0.249642)
							(end 0.1778 0.2794)
						)
					)
					(width 0)
					(fill yes)
				)
			)
		)
	)
	(footprint ""
		(layer "B.Cu")
		(at 184.03824 -57.16524 90)
		(property "Reference" "C480"
			(at 0 0 90)
			(layer "B.SilkS")
			(hide yes)
			(effects
				(font
					(size 1.27 1.27)
				)
				(justify mirror)
			)
		)
		(property "Value" "SC1KP50V2KX-1GP"
			(at -1.1811 -2.7051 90)
			(unlocked yes)
			(layer "B.Fab")
			(hide yes)
			(effects
				(font
					(size 1.016 1.016)
					(thickness 0.1524)
				)
				(justify mirror)
			)
		)
		(property "Device Type" "C402H22"
			(at -1.1811 -4.2291 90)
			(unlocked yes)
			(layer "B.Fab")
			(hide yes)
			(effects
				(font
					(size 1.016 1.016)
					(thickness 0.1524)
				)
				(justify mirror)
			)
		)
		(duplicate_pad_numbers_are_jumpers no)
		(fp_rect
			(start 0.4318 0.9525)
			(end -0.4318 -0.9525)
			(stroke
				(width 0)
				(type default)
			)
			(fill no)
			(layer "B.CrtYd")
		)
		(fp_rect
			(start 0.4318 0.9525)
			(end -0.4318 -0.9525)
			(stroke
				(width 0)
				(type default)
			)
			(fill no)
			(layer "B.Fab")
		)
		(pad "1" smd custom
			(at 0 -0.4445 270)
			(size 0.1524 0.1524)
			(layers "B.Cu" "B.Mask" "B.Paste")
			(net "P1V8")
			(options
				(clearance outline)
				(anchor circle)
			)
			(primitives
				(gr_poly
					(pts
						(arc
							(start 0.3048 0.2032)
							(mid 0.275042 0.275042)
							(end 0.2032 0.3048)
						)
						(arc
							(start -0.2032 0.3048)
							(mid -0.275042 0.275042)
							(end -0.3048 0.2032)
						)
						(arc
							(start -0.3048 -0.2032)
							(mid -0.275042 -0.275042)
							(end -0.2032 -0.3048)
						)
						(arc
							(start 0.2032 -0.3048)
							(mid 0.275042 -0.275042)
							(end 0.3048 -0.2032)
						)
					)
					(width 0)
					(fill yes)
				)
			)
		)
		(pad "2" smd custom
			(at 0 0.4445 270)
			(size 0.1524 0.1524)
			(layers "B.Cu" "B.Mask" "B.Paste")
			(net "GND")
			(options
				(clearance outline)
				(anchor circle)
			)
			(primitives
				(gr_poly
					(pts
						(arc
							(start 0.3048 0.2032)
							(mid 0.275042 0.275042)
							(end 0.2032 0.3048)
						)
						(arc
							(start -0.2032 0.3048)
							(mid -0.275042 0.275042)
							(end -0.3048 0.2032)
						)
						(arc
							(start -0.3048 -0.2032)
							(mid -0.275042 -0.275042)
							(end -0.2032 -0.3048)
						)
						(arc
							(start 0.2032 -0.3048)
							(mid 0.275042 -0.275042)
							(end 0.3048 -0.2032)
						)
					)
					(width 0)
					(fill yes)
				)
			)
		)
	)
	(footprint ""
		(layer "B.Cu")
		(at 20.37715 -140.808202 -90)
		(property "Reference" "R206"
			(at 0 0 90)
			(layer "B.SilkS")
			(hide yes)
			(effects
				(font
					(size 1.27 1.27)
				)
				(justify mirror)
			)
		)
		(property "Value" "60D4R2F-GP"
			(at -0.064008 -3.993896 270)
			(unlocked yes)
			(layer "B.Fab")
			(hide yes)
			(effects
				(font
					(size 1.016 1.016)
					(thickness 0.1524)
				)
				(justify mirror)
			)
		)
		(property "Device Type" "R402H16"
			(at -0.064008 -5.517896 270)
			(unlocked yes)
			(layer "B.Fab")
			(hide yes)
			(effects
				(font
					(size 1.016 1.016)
					(thickness 0.1524)
				)
				(justify mirror)
			)
		)
		(duplicate_pad_numbers_are_jumpers no)
		(fp_line
			(start -0.508 -0.9398)
			(end 0.508 -0.9398)
			(stroke
				(width 0.1524)
				(type default)
			)
			(layer "B.SilkS")
		)
		(fp_line
			(start 0.508 -0.9398)
			(end 0.508 0.9398)
			(stroke
				(width 0.1524)
				(type default)
			)
			(layer "B.SilkS")
		)
		(fp_rect
			(start 0.508 0.9398)
			(end -0.508 -0.9398)
			(stroke
				(width 0)
				(type default)
			)
			(fill no)
			(layer "B.CrtYd")
		)
		(fp_rect
			(start 0.508 0.9398)
			(end -0.508 -0.9398)
			(stroke
				(width 0)
				(type default)
			)
			(fill no)
			(layer "B.Fab")
		)
		(pad "1" smd custom
			(at 0 -0.4445 90)
			(size 0.1397 0.1397)
			(layers "B.Cu" "B.Mask" "B.Paste")
			(net "MEMCK_N")
			(options
				(clearance outline)
				(anchor circle)
			)
			(primitives
				(gr_poly
					(pts
						(arc
							(start -0.1778 0.2794)
							(mid -0.249642 0.249642)
							(end -0.2794 0.1778)
						)
						(arc
							(start -0.2794 -0.1778)
							(mid -0.249642 -0.249642)
							(end -0.1778 -0.2794)
						)
						(arc
							(start 0.1778 -0.2794)
							(mid 0.249642 -0.249642)
							(end 0.2794 -0.1778)
						)
						(arc
							(start 0.2794 0.1778)
							(mid 0.249642 0.249642)
							(end 0.1778 0.2794)
						)
					)
					(width 0)
					(fill yes)
				)
			)
		)
		(pad "2" smd custom
			(at 0 0.4445 90)
			(size 0.1397 0.1397)
			(layers "B.Cu" "B.Mask" "B.Paste")
			(net "MEMCK_TER")
			(options
				(clearance outline)
				(anchor circle)
			)
			(primitives
				(gr_poly
					(pts
						(arc
							(start -0.1778 0.2794)
							(mid -0.249642 0.249642)
							(end -0.2794 0.1778)
						)
						(arc
							(start -0.2794 -0.1778)
							(mid -0.249642 -0.249642)
							(end -0.1778 -0.2794)
						)
						(arc
							(start 0.1778 -0.2794)
							(mid 0.249642 -0.249642)
							(end 0.2794 -0.1778)
						)
						(arc
							(start 0.2794 0.1778)
							(mid 0.249642 0.249642)
							(end 0.1778 0.2794)
						)
					)
					(width 0)
					(fill yes)
				)
			)
		)
	)
	(footprint ""
		(layer "B.Cu")
		(at 185.6486 -49.022 180)
		(property "Reference" "R767"
			(at 0 0 0)
			(layer "B.SilkS")
			(hide yes)
			(effects
				(font
					(size 1.27 1.27)
				)
				(justify mirror)
			)
		)
		(property "Value" "10KR2F-2-GP"
			(at -0.064008 -3.993896 180)
			(unlocked yes)
			(layer "B.Fab")
			(hide yes)
			(effects
				(font
					(size 1.016 1.016)
					(thickness 0.1524)
				)
				(justify mirror)
			)
		)
		(property "Device Type" "R402H16"
			(at -0.064008 -5.517896 180)
			(unlocked yes)
			(layer "B.Fab")
			(hide yes)
			(effects
				(font
					(size 1.016 1.016)
					(thickness 0.1524)
				)
				(justify mirror)
			)
		)
		(duplicate_pad_numbers_are_jumpers no)
		(fp_line
			(start 0.508 -0.9398)
			(end 0.508 0.9398)
			(stroke
				(width 0.1524)
				(type default)
			)
			(layer "B.SilkS")
		)
		(fp_line
			(start -0.508 -0.9398)
			(end 0.508 -0.9398)
			(stroke
				(width 0.1524)
				(type default)
			)
			(layer "B.SilkS")
		)
		(fp_rect
			(start 0.508 0.9398)
			(end -0.508 -0.9398)
			(stroke
				(width 0)
				(type default)
			)
			(fill no)
			(layer "B.CrtYd")
		)
		(fp_rect
			(start 0.508 0.9398)
			(end -0.508 -0.9398)
			(stroke
				(width 0)
				(type default)
			)
			(fill no)
			(layer "B.Fab")
		)
		(pad "1" smd custom
			(at 0 -0.4445)
			(size 0.1397 0.1397)
			(layers "B.Cu" "B.Mask" "B.Paste")
			(net "P1V8")
			(options
				(clearance outline)
				(anchor circle)
			)
			(primitives
				(gr_poly
					(pts
						(arc
							(start -0.1778 0.2794)
							(mid -0.249642 0.249642)
							(end -0.2794 0.1778)
						)
						(arc
							(start -0.2794 -0.1778)
							(mid -0.249642 -0.249642)
							(end -0.1778 -0.2794)
						)
						(arc
							(start 0.1778 -0.2794)
							(mid 0.249642 -0.249642)
							(end 0.2794 -0.1778)
						)
						(arc
							(start 0.2794 0.1778)
							(mid 0.249642 0.249642)
							(end 0.1778 0.2794)
						)
					)
					(width 0)
					(fill yes)
				)
			)
		)
		(pad "2" smd custom
			(at 0 0.4445)
			(size 0.1397 0.1397)
			(layers "B.Cu" "B.Mask" "B.Paste")
			(net "XM_ADDR_1")
			(options
				(clearance outline)
				(anchor circle)
			)
			(primitives
				(gr_poly
					(pts
						(arc
							(start -0.1778 0.2794)
							(mid -0.249642 0.249642)
							(end -0.2794 0.1778)
						)
						(arc
							(start -0.2794 -0.1778)
							(mid -0.249642 -0.249642)
							(end -0.1778 -0.2794)
						)
						(arc
							(start 0.1778 -0.2794)
							(mid 0.249642 -0.249642)
							(end 0.2794 -0.1778)
						)
						(arc
							(start 0.2794 0.1778)
							(mid 0.249642 0.249642)
							(end 0.1778 0.2794)
						)
					)
					(width 0)
					(fill yes)
				)
			)
		)
	)
	(footprint ""
		(layer "B.Cu")
		(at 201.110342 -46.308772 90)
		(property "Reference" "R680"
			(at 0 0 90)
			(layer "B.SilkS")
			(hide yes)
			(effects
				(font
					(size 1.27 1.27)
				)
				(justify mirror)
			)
		)
		(property "Value" "10R2F-L-GP"
			(at -0.064008 -3.993896 90)
			(unlocked yes)
			(layer "B.Fab")
			(hide yes)
			(effects
				(font
					(size 1.016 1.016)
					(thickness 0.1524)
				)
				(justify mirror)
			)
		)
		(property "Device Type" "R402H14"
			(at -0.064008 -5.517896 90)
			(unlocked yes)
			(layer "B.Fab")
			(hide yes)
			(effects
				(font
					(size 1.016 1.016)
					(thickness 0.1524)
				)
				(justify mirror)
			)
		)
		(duplicate_pad_numbers_are_jumpers no)
		(fp_line
			(start 0.508 -0.9398)
			(end 0.508 0.9398)
			(stroke
				(width 0.1524)
				(type default)
			)
			(layer "B.SilkS")
		)
		(fp_line
			(start -0.508 -0.9398)
			(end 0.508 -0.9398)
			(stroke
				(width 0.1524)
				(type default)
			)
			(layer "B.SilkS")
		)
		(fp_rect
			(start 0.508 0.9398)
			(end -0.508 -0.9398)
			(stroke
				(width 0)
				(type default)
			)
			(fill no)
			(layer "B.CrtYd")
		)
		(fp_rect
			(start 0.508 0.9398)
			(end -0.508 -0.9398)
			(stroke
				(width 0)
				(type default)
			)
			(fill no)
			(layer "B.Fab")
		)
		(pad "1" smd custom
			(at 0 -0.4445 270)
			(size 0.1397 0.1397)
			(layers "B.Cu" "B.Mask" "B.Paste")
			(net "P1V8")
			(options
				(clearance outline)
				(anchor circle)
			)
			(primitives
				(gr_poly
					(pts
						(arc
							(start -0.1778 0.2794)
							(mid -0.249642 0.249642)
							(end -0.2794 0.1778)
						)
						(arc
							(start -0.2794 -0.1778)
							(mid -0.249642 -0.249642)
							(end -0.1778 -0.2794)
						)
						(arc
							(start 0.1778 -0.2794)
							(mid 0.249642 -0.249642)
							(end 0.2794 -0.1778)
						)
						(arc
							(start 0.2794 0.1778)
							(mid 0.249642 0.249642)
							(end 0.1778 0.2794)
						)
					)
					(width 0)
					(fill yes)
				)
			)
		)
		(pad "2" smd custom
			(at 0 0.4445 270)
			(size 0.1397 0.1397)
			(layers "B.Cu" "B.Mask" "B.Paste")
			(net "SYS_PLL_VDD")
			(options
				(clearance outline)
				(anchor circle)
			)
			(primitives
				(gr_poly
					(pts
						(arc
							(start -0.1778 0.2794)
							(mid -0.249642 0.249642)
							(end -0.2794 0.1778)
						)
						(arc
							(start -0.2794 -0.1778)
							(mid -0.249642 -0.249642)
							(end -0.1778 -0.2794)
						)
						(arc
							(start 0.1778 -0.2794)
							(mid 0.249642 -0.249642)
							(end 0.2794 -0.1778)
						)
						(arc
							(start 0.2794 0.1778)
							(mid 0.249642 0.249642)
							(end 0.1778 0.2794)
						)
					)
					(width 0)
					(fill yes)
				)
			)
		)
	)
	(footprint ""
		(layer "B.Cu")
		(at 47.2313 -154.26944 -90)
		(property "Reference" "R368"
			(at 0 0 90)
			(layer "B.SilkS")
			(hide yes)
			(effects
				(font
					(size 1.27 1.27)
				)
				(justify mirror)
			)
		)
		(property "Value" "0R2J-2-GP"
			(at -0.064008 -3.993896 270)
			(unlocked yes)
			(layer "B.Fab")
			(hide yes)
			(effects
				(font
					(size 1.016 1.016)
					(thickness 0.1524)
				)
				(justify mirror)
			)
		)
		(property "Device Type" "R402H16"
			(at -0.064008 -5.517896 270)
			(unlocked yes)
			(layer "B.Fab")
			(hide yes)
			(effects
				(font
					(size 1.016 1.016)
					(thickness 0.1524)
				)
				(justify mirror)
			)
		)
		(duplicate_pad_numbers_are_jumpers no)
		(fp_line
			(start -0.508 -0.9398)
			(end 0.508 -0.9398)
			(stroke
				(width 0.1524)
				(type default)
			)
			(layer "B.SilkS")
		)
		(fp_line
			(start 0.508 -0.9398)
			(end 0.508 0.9398)
			(stroke
				(width 0.1524)
				(type default)
			)
			(layer "B.SilkS")
		)
		(fp_rect
			(start 0.508 0.9398)
			(end -0.508 -0.9398)
			(stroke
				(width 0)
				(type default)
			)
			(fill no)
			(layer "B.CrtYd")
		)
		(fp_rect
			(start 0.508 0.9398)
			(end -0.508 -0.9398)
			(stroke
				(width 0)
				(type default)
			)
			(fill no)
			(layer "B.Fab")
		)
		(pad "1" smd custom
			(at 0 -0.4445 90)
			(size 0.1397 0.1397)
			(layers "B.Cu" "B.Mask" "B.Paste")
			(net "P3V3_STBY")
			(options
				(clearance outline)
				(anchor circle)
			)
			(primitives
				(gr_poly
					(pts
						(arc
							(start -0.1778 0.2794)
							(mid -0.249642 0.249642)
							(end -0.2794 0.1778)
						)
						(arc
							(start -0.2794 -0.1778)
							(mid -0.249642 -0.249642)
							(end -0.1778 -0.2794)
						)
						(arc
							(start 0.1778 -0.2794)
							(mid 0.249642 -0.249642)
							(end 0.2794 -0.1778)
						)
						(arc
							(start 0.2794 0.1778)
							(mid 0.249642 0.249642)
							(end 0.1778 0.2794)
						)
					)
					(width 0)
					(fill yes)
				)
			)
		)
		(pad "2" smd custom
			(at 0 0.4445 90)
			(size 0.1397 0.1397)
			(layers "B.Cu" "B.Mask" "B.Paste")
			(net "DACAV33")
			(options
				(clearance outline)
				(anchor circle)
			)
			(primitives
				(gr_poly
					(pts
						(arc
							(start -0.1778 0.2794)
							(mid -0.249642 0.249642)
							(end -0.2794 0.1778)
						)
						(arc
							(start -0.2794 -0.1778)
							(mid -0.249642 -0.249642)
							(end -0.1778 -0.2794)
						)
						(arc
							(start 0.1778 -0.2794)
							(mid 0.249642 -0.249642)
							(end 0.2794 -0.1778)
						)
						(arc
							(start 0.2794 0.1778)
							(mid 0.249642 0.249642)
							(end 0.1778 0.2794)
						)
					)
					(width 0)
					(fill yes)
				)
			)
		)
	)
	(footprint ""
		(layer "B.Cu")
		(at 184.19318 -61.8998 90)
		(property "Reference" "C477"
			(at 0 0 90)
			(layer "B.SilkS")
			(hide yes)
			(effects
				(font
					(size 1.27 1.27)
				)
				(justify mirror)
			)
		)
		(property "Value" "SC1KP50V2KX-1GP"
			(at -1.1811 -2.7051 90)
			(unlocked yes)
			(layer "B.Fab")
			(hide yes)
			(effects
				(font
					(size 1.016 1.016)
					(thickness 0.1524)
				)
				(justify mirror)
			)
		)
		(property "Device Type" "C402H22"
			(at -1.1811 -4.2291 90)
			(unlocked yes)
			(layer "B.Fab")
			(hide yes)
			(effects
				(font
					(size 1.016 1.016)
					(thickness 0.1524)
				)
				(justify mirror)
			)
		)
		(duplicate_pad_numbers_are_jumpers no)
		(fp_rect
			(start 0.4318 0.9525)
			(end -0.4318 -0.9525)
			(stroke
				(width 0)
				(type default)
			)
			(fill no)
			(layer "B.CrtYd")
		)
		(fp_rect
			(start 0.4318 0.9525)
			(end -0.4318 -0.9525)
			(stroke
				(width 0)
				(type default)
			)
			(fill no)
			(layer "B.Fab")
		)
		(pad "1" smd custom
			(at 0 -0.4445 270)
			(size 0.1524 0.1524)
			(layers "B.Cu" "B.Mask" "B.Paste")
			(net "P1V8")
			(options
				(clearance outline)
				(anchor circle)
			)
			(primitives
				(gr_poly
					(pts
						(arc
							(start 0.3048 0.2032)
							(mid 0.275042 0.275042)
							(end 0.2032 0.3048)
						)
						(arc
							(start -0.2032 0.3048)
							(mid -0.275042 0.275042)
							(end -0.3048 0.2032)
						)
						(arc
							(start -0.3048 -0.2032)
							(mid -0.275042 -0.275042)
							(end -0.2032 -0.3048)
						)
						(arc
							(start 0.2032 -0.3048)
							(mid 0.275042 -0.275042)
							(end 0.3048 -0.2032)
						)
					)
					(width 0)
					(fill yes)
				)
			)
		)
		(pad "2" smd custom
			(at 0 0.4445 270)
			(size 0.1524 0.1524)
			(layers "B.Cu" "B.Mask" "B.Paste")
			(net "GND")
			(options
				(clearance outline)
				(anchor circle)
			)
			(primitives
				(gr_poly
					(pts
						(arc
							(start 0.3048 0.2032)
							(mid 0.275042 0.275042)
							(end 0.2032 0.3048)
						)
						(arc
							(start -0.2032 0.3048)
							(mid -0.275042 0.275042)
							(end -0.3048 0.2032)
						)
						(arc
							(start -0.3048 -0.2032)
							(mid -0.275042 -0.275042)
							(end -0.2032 -0.3048)
						)
						(arc
							(start 0.2032 -0.3048)
							(mid 0.275042 -0.275042)
							(end 0.3048 -0.2032)
						)
					)
					(width 0)
					(fill yes)
				)
			)
		)
	)
	(footprint ""
		(layer "B.Cu")
		(at 193.7004 -44.4246 -90)
		(property "Reference" "L13"
			(at 0 0 90)
			(layer "B.SilkS")
			(hide yes)
			(effects
				(font
					(size 1.27 1.27)
				)
				(justify mirror)
			)
		)
		(property "Value" "MPZ2012S601AT-GP"
			(at 0 -4.2418 270)
			(unlocked yes)
			(layer "B.Fab")
			(hide yes)
			(effects
				(font
					(size 1.016 1.016)
					(thickness 0.1524)
				)
				(justify mirror)
			)
		)
		(property "Device Type" "L805H42"
			(at 0 -5.7912 270)
			(unlocked yes)
			(layer "B.Fab")
			(hide yes)
			(effects
				(font
					(size 1.016 1.016)
					(thickness 0.1524)
				)
				(justify mirror)
			)
		)
		(duplicate_pad_numbers_are_jumpers no)
		(fp_line
			(start -0.889 1.7018)
			(end 0.889 1.7018)
			(stroke
				(width 0.1524)
				(type default)
			)
			(layer "B.SilkS")
		)
		(fp_line
			(start 0.889 1.7018)
			(end 0.889 -1.7018)
			(stroke
				(width 0.1524)
				(type default)
			)
			(layer "B.SilkS")
		)
		(fp_line
			(start -0.889 -1.7018)
			(end -0.889 1.7018)
			(stroke
				(width 0.1524)
				(type default)
			)
			(layer "B.SilkS")
		)
		(fp_line
			(start 0.889 -1.7018)
			(end -0.889 -1.7018)
			(stroke
				(width 0.1524)
				(type default)
			)
			(layer "B.SilkS")
		)
		(fp_rect
			(start 0.9652 1.778)
			(end -0.9652 -1.778)
			(stroke
				(width 0)
				(type default)
			)
			(fill no)
			(layer "B.CrtYd")
		)
		(fp_rect
			(start 0.9652 1.778)
			(end -0.9652 -1.778)
			(stroke
				(width 0)
				(type default)
			)
			(fill no)
			(layer "B.Fab")
		)
		(pad "1" smd rect
			(at 0 -0.9652 90)
			(size 1.397 1.143)
			(layers "B.Cu" "B.Mask" "B.Paste")
			(net "HM40ADC_VDDA")
		)
		(pad "2" smd rect
			(at 0 0.9652 90)
			(size 1.397 1.143)
			(layers "B.Cu" "B.Mask" "B.Paste")
			(net "P1V8")
		)
	)
	(footprint ""
		(layer "B.Cu")
		(at 200.3933 -57.8866 -90)
		(property "Reference" "C445"
			(at 0 0 90)
			(layer "B.SilkS")
			(hide yes)
			(effects
				(font
					(size 1.27 1.27)
				)
				(justify mirror)
			)
		)
		(property "Value" "SCD1U16V2KX-3GP"
			(at -1.1811 -2.7051 270)
			(unlocked yes)
			(layer "B.Fab")
			(hide yes)
			(effects
				(font
					(size 1.016 1.016)
					(thickness 0.1524)
				)
				(justify mirror)
			)
		)
		(property "Device Type" "C402H22"
			(at -1.1811 -4.2291 270)
			(unlocked yes)
			(layer "B.Fab")
			(hide yes)
			(effects
				(font
					(size 1.016 1.016)
					(thickness 0.1524)
				)
				(justify mirror)
			)
		)
		(duplicate_pad_numbers_are_jumpers no)
		(fp_rect
			(start 0.4318 0.9525)
			(end -0.4318 -0.9525)
			(stroke
				(width 0)
				(type default)
			)
			(fill no)
			(layer "B.CrtYd")
		)
		(fp_rect
			(start 0.4318 0.9525)
			(end -0.4318 -0.9525)
			(stroke
				(width 0)
				(type default)
			)
			(fill no)
			(layer "B.Fab")
		)
		(pad "1" smd custom
			(at 0 -0.4445 90)
			(size 0.1524 0.1524)
			(layers "B.Cu" "B.Mask" "B.Paste")
			(net "P1V8")
			(options
				(clearance outline)
				(anchor circle)
			)
			(primitives
				(gr_poly
					(pts
						(arc
							(start 0.3048 0.2032)
							(mid 0.275042 0.275042)
							(end 0.2032 0.3048)
						)
						(arc
							(start -0.2032 0.3048)
							(mid -0.275042 0.275042)
							(end -0.3048 0.2032)
						)
						(arc
							(start -0.3048 -0.2032)
							(mid -0.275042 -0.275042)
							(end -0.2032 -0.3048)
						)
						(arc
							(start 0.2032 -0.3048)
							(mid 0.275042 -0.275042)
							(end 0.3048 -0.2032)
						)
					)
					(width 0)
					(fill yes)
				)
			)
		)
		(pad "2" smd custom
			(at 0 0.4445 90)
			(size 0.1524 0.1524)
			(layers "B.Cu" "B.Mask" "B.Paste")
			(net "GND")
			(options
				(clearance outline)
				(anchor circle)
			)
			(primitives
				(gr_poly
					(pts
						(arc
							(start 0.3048 0.2032)
							(mid 0.275042 0.275042)
							(end 0.2032 0.3048)
						)
						(arc
							(start -0.2032 0.3048)
							(mid -0.275042 0.275042)
							(end -0.3048 0.2032)
						)
						(arc
							(start -0.3048 -0.2032)
							(mid -0.275042 -0.275042)
							(end -0.2032 -0.3048)
						)
						(arc
							(start 0.2032 -0.3048)
							(mid 0.275042 -0.275042)
							(end 0.3048 -0.2032)
						)
					)
					(width 0)
					(fill yes)
				)
			)
		)
	)
	(footprint ""
		(layer "B.Cu")
		(at 37.80536 -140.29309 180)
		(property "Reference" "C99"
			(at 0 0 0)
			(layer "B.SilkS")
			(hide yes)
			(effects
				(font
					(size 1.27 1.27)
				)
				(justify mirror)
			)
		)
		(property "Value" "SC1U16V3KX-5GP"
			(at 0 -2.8194 180)
			(unlocked yes)
			(layer "B.Fab")
			(hide yes)
			(effects
				(font
					(size 1.016 1.016)
					(thickness 0.1524)
				)
				(justify mirror)
			)
		)
		(property "Device Type" "C603H36"
			(at 0 -4.3434 180)
			(unlocked yes)
			(layer "B.Fab")
			(hide yes)
			(effects
				(font
					(size 1.016 1.016)
					(thickness 0.1524)
				)
				(justify mirror)
			)
		)
		(duplicate_pad_numbers_are_jumpers no)
		(fp_line
			(start -0.508 0)
			(end 0.508 0)
			(stroke
				(width 0.2032)
				(type default)
			)
			(layer "B.SilkS")
		)
		(fp_rect
			(start 0.5842 1.3335)
			(end -0.5842 -1.3335)
			(stroke
				(width 0)
				(type default)
			)
			(fill no)
			(layer "B.CrtYd")
		)
		(fp_rect
			(start 0.5842 1.3335)
			(end -0.5842 -1.3335)
			(stroke
				(width 0)
				(type default)
			)
			(fill no)
			(layer "B.Fab")
		)
		(pad "1" smd custom
			(at 0 -0.762)
			(size 0.2159 0.2159)
			(layers "B.Cu" "B.Mask" "B.Paste")
			(net "P3V3_STBY")
			(options
				(clearance outline)
				(anchor circle)
			)
			(primitives
				(gr_poly
					(pts
						(arc
							(start -0.3302 0.4318)
							(mid -0.402042 0.402042)
							(end -0.4318 0.3302)
						)
						(arc
							(start -0.4318 -0.3302)
							(mid -0.402042 -0.402042)
							(end -0.3302 -0.4318)
						)
						(arc
							(start 0.3302 -0.4318)
							(mid 0.402042 -0.402042)
							(end 0.4318 -0.3302)
						)
						(arc
							(start 0.4318 0.3302)
							(mid 0.402042 0.402042)
							(end 0.3302 0.4318)
						)
					)
					(width 0)
					(fill yes)
				)
			)
		)
		(pad "2" smd custom
			(at 0 0.762)
			(size 0.2159 0.2159)
			(layers "B.Cu" "B.Mask" "B.Paste")
			(net "GND")
			(options
				(clearance outline)
				(anchor circle)
			)
			(primitives
				(gr_poly
					(pts
						(arc
							(start -0.3302 0.4318)
							(mid -0.402042 0.402042)
							(end -0.4318 0.3302)
						)
						(arc
							(start -0.4318 -0.3302)
							(mid -0.402042 -0.402042)
							(end -0.3302 -0.4318)
						)
						(arc
							(start 0.3302 -0.4318)
							(mid 0.402042 -0.402042)
							(end 0.4318 -0.3302)
						)
						(arc
							(start 0.4318 0.3302)
							(mid 0.402042 0.402042)
							(end 0.3302 0.4318)
						)
					)
					(width 0)
					(fill yes)
				)
			)
		)
	)
	(footprint ""
		(layer "B.Cu")
		(at 195.7832 -76.454)
		(property "Reference" "C370"
			(at 0 0 0)
			(layer "B.SilkS")
			(hide yes)
			(effects
				(font
					(size 1.27 1.27)
				)
				(justify mirror)
			)
		)
		(property "Value" "SCD1U6D3V1KX-GP"
			(at 2.8321 -1.7399 0)
			(unlocked yes)
			(layer "B.Fab")
			(hide yes)
			(effects
				(font
					(size 1.016 1.016)
					(thickness 0.1524)
				)
				(justify mirror)
			)
		)
		(property "Device Type" "C0201H13"
			(at 2.8321 -3.2639 0)
			(unlocked yes)
			(layer "B.Fab")
			(hide yes)
			(effects
				(font
					(size 1.016 1.016)
					(thickness 0.1524)
				)
				(justify mirror)
			)
		)
		(duplicate_pad_numbers_are_jumpers no)
		(fp_rect
			(start 0.2794 0.6477)
			(end -0.2794 -0.6477)
			(stroke
				(width 0)
				(type default)
			)
			(fill no)
			(layer "B.CrtYd")
		)
		(fp_rect
			(start 0.2794 0.6477)
			(end -0.2794 -0.6477)
			(stroke
				(width 0)
				(type default)
			)
			(fill no)
			(layer "B.Fab")
		)
		(pad "1" smd custom
			(at 0 -0.2794 180)
			(size 0.0762 0.0762)
			(layers "B.Cu" "B.Mask" "B.Paste")
			(net "PCE_AVDD")
			(options
				(clearance outline)
				(anchor circle)
			)
			(primitives
				(gr_poly
					(pts
						(arc
							(start 0.1524 0.127)
							(mid 0.137521 0.162921)
							(end 0.1016 0.1778)
						)
						(arc
							(start -0.1016 0.1778)
							(mid -0.137521 0.162921)
							(end -0.1524 0.127)
						)
						(arc
							(start -0.1524 -0.127)
							(mid -0.137521 -0.162921)
							(end -0.1016 -0.1778)
						)
						(arc
							(start 0.1016 -0.1778)
							(mid 0.137521 -0.162921)
							(end 0.1524 -0.127)
						)
					)
					(width 0)
					(fill yes)
				)
			)
		)
		(pad "2" smd custom
			(at 0 0.2794 180)
			(size 0.0762 0.0762)
			(layers "B.Cu" "B.Mask" "B.Paste")
			(net "GND")
			(options
				(clearance outline)
				(anchor circle)
			)
			(primitives
				(gr_poly
					(pts
						(arc
							(start 0.1524 0.127)
							(mid 0.137521 0.162921)
							(end 0.1016 0.1778)
						)
						(arc
							(start -0.1016 0.1778)
							(mid -0.137521 0.162921)
							(end -0.1524 0.127)
						)
						(arc
							(start -0.1524 -0.127)
							(mid -0.137521 -0.162921)
							(end -0.1016 -0.1778)
						)
						(arc
							(start 0.1016 -0.1778)
							(mid 0.137521 -0.162921)
							(end 0.1524 -0.127)
						)
					)
					(width 0)
					(fill yes)
				)
			)
		)
	)
	(footprint ""
		(layer "B.Cu")
		(at 120.142 -6.477 90)
		(property "Reference" "C132"
			(at 0 0 90)
			(layer "B.SilkS")
			(hide yes)
			(effects
				(font
					(size 1.27 1.27)
				)
				(justify mirror)
			)
		)
		(property "Value" "SC22UF16V6KX-GP"
			(at 0 -6.8072 90)
			(unlocked yes)
			(layer "B.Fab")
			(hide yes)
			(effects
				(font
					(size 1.016 1.016)
					(thickness 0.1524)
				)
				(justify mirror)
			)
		)
		(property "Device Type" "C1206H75"
			(at 0 -8.7122 90)
			(unlocked yes)
			(layer "B.Fab")
			(hide yes)
			(effects
				(font
					(size 1.016 1.016)
					(thickness 0.1524)
				)
				(justify mirror)
			)
		)
		(duplicate_pad_numbers_are_jumpers no)
		(fp_line
			(start 1.016 -2.2352)
			(end 1.016 -0.8382)
			(stroke
				(width 0.1524)
				(type default)
			)
			(layer "B.SilkS")
		)
		(fp_line
			(start -1.016 -2.2352)
			(end 1.016 -2.2352)
			(stroke
				(width 0.1524)
				(type default)
			)
			(layer "B.SilkS")
		)
		(fp_line
			(start -1.016 -2.2352)
			(end -1.016 -0.8382)
			(stroke
				(width 0.1524)
				(type default)
			)
			(layer "B.SilkS")
		)
		(fp_line
			(start -1.016 0.8382)
			(end -1.016 2.2352)
			(stroke
				(width 0.1524)
				(type default)
			)
			(layer "B.SilkS")
		)
		(fp_line
			(start 1.016 2.2352)
			(end 1.016 0.8128)
			(stroke
				(width 0.1524)
				(type default)
			)
			(layer "B.SilkS")
		)
		(fp_line
			(start -1.016 2.2352)
			(end 1.016 2.2352)
			(stroke
				(width 0.1524)
				(type default)
			)
			(layer "B.SilkS")
		)
		(fp_rect
			(start 1.0922 2.3114)
			(end -1.0922 -2.3114)
			(stroke
				(width 0)
				(type default)
			)
			(fill no)
			(layer "B.CrtYd")
		)
		(fp_poly
			(pts
				(xy 1.0922 -2.3114) (xy -1.0922 -2.3114) (xy -1.0922 2.3114) (xy 1.0922 2.3114)
			)
			(stroke
				(width 0)
				(type default)
			)
			(fill no)
			(layer "B.Fab")
		)
		(pad "1" smd rect
			(at 0 -1.397 270)
			(size 1.651 1.27)
			(layers "B.Cu" "B.Mask" "B.Paste")
			(net "MB0_HS_ENABLE")
		)
		(pad "2" smd rect
			(at 0 1.397 270)
			(size 1.651 1.27)
			(layers "B.Cu" "B.Mask" "B.Paste")
			(net "GND")
		)
	)
	(footprint ""
		(layer "B.Cu")
		(at 122.3264 -15.9766 -90)
		(property "Reference" "R742"
			(at 0 0 90)
			(layer "B.SilkS")
			(hide yes)
			(effects
				(font
					(size 1.27 1.27)
				)
				(justify mirror)
			)
		)
		(property "Value" "10KR2F-2-GP"
			(at -0.064008 -3.993896 270)
			(unlocked yes)
			(layer "B.Fab")
			(hide yes)
			(effects
				(font
					(size 1.016 1.016)
					(thickness 0.1524)
				)
				(justify mirror)
			)
		)
		(property "Device Type" "R402H16"
			(at -0.064008 -5.517896 270)
			(unlocked yes)
			(layer "B.Fab")
			(hide yes)
			(effects
				(font
					(size 1.016 1.016)
					(thickness 0.1524)
				)
				(justify mirror)
			)
		)
		(duplicate_pad_numbers_are_jumpers no)
		(fp_line
			(start -0.508 -0.9398)
			(end 0.508 -0.9398)
			(stroke
				(width 0.1524)
				(type default)
			)
			(layer "B.SilkS")
		)
		(fp_line
			(start 0.508 -0.9398)
			(end 0.508 0.9398)
			(stroke
				(width 0.1524)
				(type default)
			)
			(layer "B.SilkS")
		)
		(fp_rect
			(start 0.508 0.9398)
			(end -0.508 -0.9398)
			(stroke
				(width 0)
				(type default)
			)
			(fill no)
			(layer "B.CrtYd")
		)
		(fp_rect
			(start 0.508 0.9398)
			(end -0.508 -0.9398)
			(stroke
				(width 0)
				(type default)
			)
			(fill no)
			(layer "B.Fab")
		)
		(pad "1" smd custom
			(at 0 -0.4445 90)
			(size 0.1397 0.1397)
			(layers "B.Cu" "B.Mask" "B.Paste")
			(net "P12V_IOM")
			(options
				(clearance outline)
				(anchor circle)
			)
			(primitives
				(gr_poly
					(pts
						(arc
							(start -0.1778 0.2794)
							(mid -0.249642 0.249642)
							(end -0.2794 0.1778)
						)
						(arc
							(start -0.2794 -0.1778)
							(mid -0.249642 -0.249642)
							(end -0.1778 -0.2794)
						)
						(arc
							(start 0.1778 -0.2794)
							(mid 0.249642 -0.249642)
							(end 0.2794 -0.1778)
						)
						(arc
							(start 0.2794 0.1778)
							(mid 0.249642 0.249642)
							(end 0.1778 0.2794)
						)
					)
					(width 0)
					(fill yes)
				)
			)
		)
		(pad "2" smd custom
			(at 0 0.4445 90)
			(size 0.1397 0.1397)
			(layers "B.Cu" "B.Mask" "B.Paste")
			(net "IOM_MATED_N")
			(options
				(clearance outline)
				(anchor circle)
			)
			(primitives
				(gr_poly
					(pts
						(arc
							(start -0.1778 0.2794)
							(mid -0.249642 0.249642)
							(end -0.2794 0.1778)
						)
						(arc
							(start -0.2794 -0.1778)
							(mid -0.249642 -0.249642)
							(end -0.1778 -0.2794)
						)
						(arc
							(start 0.1778 -0.2794)
							(mid 0.249642 -0.249642)
							(end 0.2794 -0.1778)
						)
						(arc
							(start 0.2794 0.1778)
							(mid 0.249642 0.249642)
							(end 0.1778 0.2794)
						)
					)
					(width 0)
					(fill yes)
				)
			)
		)
	)
	(footprint ""
		(layer "B.Cu")
		(at 181.6608 -76.2 -90)
		(property "Reference" "TP95"
			(at 0 0 90)
			(layer "B.SilkS")
			(hide yes)
			(effects
				(font
					(size 1.27 1.27)
				)
				(justify mirror)
			)
		)
		(property "Value" "TPAD28-2-GP"
			(at 0.0127 -1.6637 270)
			(unlocked yes)
			(layer "B.Fab")
			(hide yes)
			(effects
				(font
					(size 1.016 1.016)
					(thickness 0.1524)
				)
				(justify mirror)
			)
		)
		(property "Device Type" "TPAD28"
			(at 0.0127 -3.1877 270)
			(unlocked yes)
			(layer "B.Fab")
			(hide yes)
			(effects
				(font
					(size 1.016 1.016)
					(thickness 0.1524)
				)
				(justify mirror)
			)
		)
		(duplicate_pad_numbers_are_jumpers no)
		(fp_poly
			(pts
				(arc
					(start 0 -0.3556)
					(mid 0 0.3556)
					(end 0 -0.3556)
				)
			)
			(stroke
				(width 0)
				(type default)
			)
			(fill no)
			(layer "B.CrtYd")
		)
		(fp_poly
			(pts
				(arc
					(start 0 -0.6096)
					(mid 0 0.6096)
					(end 0 -0.6096)
				)
			)
			(stroke
				(width 0)
				(type default)
			)
			(fill no)
			(layer "B.Fab")
		)
		(pad "1" smd circle
			(at 0 0 90)
			(size 0.7112 0.7112)
			(layers "B.Cu" "B.Mask" "B.Paste")
			(net "IOC_GPIO_10")
		)
	)
	(footprint ""
		(layer "B.Cu")
		(at 19.144742 -129.077466 180)
		(property "Reference" "R235"
			(at 0 0 0)
			(layer "B.SilkS")
			(hide yes)
			(effects
				(font
					(size 1.27 1.27)
				)
				(justify mirror)
			)
		)
		(property "Value" "120R2F-GP"
			(at -0.064008 -3.993896 180)
			(unlocked yes)
			(layer "B.Fab")
			(hide yes)
			(effects
				(font
					(size 1.016 1.016)
					(thickness 0.1524)
				)
				(justify mirror)
			)
		)
		(property "Device Type" "R402H16"
			(at -0.064008 -5.517896 180)
			(unlocked yes)
			(layer "B.Fab")
			(hide yes)
			(effects
				(font
					(size 1.016 1.016)
					(thickness 0.1524)
				)
				(justify mirror)
			)
		)
		(duplicate_pad_numbers_are_jumpers no)
		(fp_line
			(start 0.508 -0.9398)
			(end 0.508 0.9398)
			(stroke
				(width 0.1524)
				(type default)
			)
			(layer "B.SilkS")
		)
		(fp_line
			(start -0.508 -0.9398)
			(end 0.508 -0.9398)
			(stroke
				(width 0.1524)
				(type default)
			)
			(layer "B.SilkS")
		)
		(fp_rect
			(start 0.508 0.9398)
			(end -0.508 -0.9398)
			(stroke
				(width 0)
				(type default)
			)
			(fill no)
			(layer "B.CrtYd")
		)
		(fp_rect
			(start 0.508 0.9398)
			(end -0.508 -0.9398)
			(stroke
				(width 0)
				(type default)
			)
			(fill no)
			(layer "B.Fab")
		)
		(pad "1" smd custom
			(at 0 -0.4445)
			(size 0.1397 0.1397)
			(layers "B.Cu" "B.Mask" "B.Paste")
			(net "GND")
			(options
				(clearance outline)
				(anchor circle)
			)
			(primitives
				(gr_poly
					(pts
						(arc
							(start -0.1778 0.2794)
							(mid -0.249642 0.249642)
							(end -0.2794 0.1778)
						)
						(arc
							(start -0.2794 -0.1778)
							(mid -0.249642 -0.249642)
							(end -0.1778 -0.2794)
						)
						(arc
							(start 0.1778 -0.2794)
							(mid 0.249642 -0.249642)
							(end 0.2794 -0.1778)
						)
						(arc
							(start 0.2794 0.1778)
							(mid 0.249642 0.249642)
							(end 0.1778 0.2794)
						)
					)
					(width 0)
					(fill yes)
				)
			)
		)
		(pad "2" smd custom
			(at 0 0.4445)
			(size 0.1397 0.1397)
			(layers "B.Cu" "B.Mask" "B.Paste")
			(net "MEMA_1")
			(options
				(clearance outline)
				(anchor circle)
			)
			(primitives
				(gr_poly
					(pts
						(arc
							(start -0.1778 0.2794)
							(mid -0.249642 0.249642)
							(end -0.2794 0.1778)
						)
						(arc
							(start -0.2794 -0.1778)
							(mid -0.249642 -0.249642)
							(end -0.1778 -0.2794)
						)
						(arc
							(start 0.1778 -0.2794)
							(mid 0.249642 -0.249642)
							(end 0.2794 -0.1778)
						)
						(arc
							(start 0.2794 0.1778)
							(mid 0.249642 0.249642)
							(end 0.1778 0.2794)
						)
					)
					(width 0)
					(fill yes)
				)
			)
		)
	)
	(footprint ""
		(layer "B.Cu")
		(at 39.537132 -131.489958 -90)
		(property "Reference" "R611"
			(at 0 0 90)
			(layer "B.SilkS")
			(hide yes)
			(effects
				(font
					(size 1.27 1.27)
				)
				(justify mirror)
			)
		)
		(property "Value" "4K7R2F-GP"
			(at -0.064008 -3.993896 270)
			(unlocked yes)
			(layer "B.Fab")
			(hide yes)
			(effects
				(font
					(size 1.016 1.016)
					(thickness 0.1524)
				)
				(justify mirror)
			)
		)
		(property "Device Type" "R402H16"
			(at -0.064008 -5.517896 270)
			(unlocked yes)
			(layer "B.Fab")
			(hide yes)
			(effects
				(font
					(size 1.016 1.016)
					(thickness 0.1524)
				)
				(justify mirror)
			)
		)
		(duplicate_pad_numbers_are_jumpers no)
		(fp_line
			(start -0.508 -0.9398)
			(end 0.508 -0.9398)
			(stroke
				(width 0.1524)
				(type default)
			)
			(layer "B.SilkS")
		)
		(fp_line
			(start 0.508 -0.9398)
			(end 0.508 0.9398)
			(stroke
				(width 0.1524)
				(type default)
			)
			(layer "B.SilkS")
		)
		(fp_rect
			(start 0.508 0.9398)
			(end -0.508 -0.9398)
			(stroke
				(width 0)
				(type default)
			)
			(fill no)
			(layer "B.CrtYd")
		)
		(fp_rect
			(start 0.508 0.9398)
			(end -0.508 -0.9398)
			(stroke
				(width 0)
				(type default)
			)
			(fill no)
			(layer "B.Fab")
		)
		(pad "1" smd custom
			(at 0 -0.4445 90)
			(size 0.1397 0.1397)
			(layers "B.Cu" "B.Mask" "B.Paste")
			(net "P3V3_STBY")
			(options
				(clearance outline)
				(anchor circle)
			)
			(primitives
				(gr_poly
					(pts
						(arc
							(start -0.1778 0.2794)
							(mid -0.249642 0.249642)
							(end -0.2794 0.1778)
						)
						(arc
							(start -0.2794 -0.1778)
							(mid -0.249642 -0.249642)
							(end -0.1778 -0.2794)
						)
						(arc
							(start 0.1778 -0.2794)
							(mid 0.249642 -0.249642)
							(end 0.2794 -0.1778)
						)
						(arc
							(start 0.2794 0.1778)
							(mid 0.249642 0.249642)
							(end 0.1778 0.2794)
						)
					)
					(width 0)
					(fill yes)
				)
			)
		)
		(pad "2" smd custom
			(at 0 0.4445 90)
			(size 0.1397 0.1397)
			(layers "B.Cu" "B.Mask" "B.Paste")
			(net "BMC_ML_PWR_YELLOW_LED")
			(options
				(clearance outline)
				(anchor circle)
			)
			(primitives
				(gr_poly
					(pts
						(arc
							(start -0.1778 0.2794)
							(mid -0.249642 0.249642)
							(end -0.2794 0.1778)
						)
						(arc
							(start -0.2794 -0.1778)
							(mid -0.249642 -0.249642)
							(end -0.1778 -0.2794)
						)
						(arc
							(start 0.1778 -0.2794)
							(mid 0.249642 -0.249642)
							(end 0.2794 -0.1778)
						)
						(arc
							(start 0.2794 0.1778)
							(mid 0.249642 0.249642)
							(end 0.1778 0.2794)
						)
					)
					(width 0)
					(fill yes)
				)
			)
		)
	)
	(footprint ""
		(layer "B.Cu")
		(at 157.099 -120.142 -90)
		(property "Reference" "C218"
			(at 0 0 90)
			(layer "B.SilkS")
			(hide yes)
			(effects
				(font
					(size 1.27 1.27)
				)
				(justify mirror)
			)
		)
		(property "Value" "SC10U6D3V5KX-4GP"
			(at 0.0762 -6.1214 270)
			(unlocked yes)
			(layer "B.Fab")
			(hide yes)
			(effects
				(font
					(size 1.016 1.016)
					(thickness 0.1524)
				)
				(justify mirror)
			)
		)
		(property "Device Type" "C805H58"
			(at 0.0762 -8.1534 270)
			(unlocked yes)
			(layer "B.Fab")
			(hide yes)
			(effects
				(font
					(size 1.016 1.016)
					(thickness 0.1524)
				)
				(justify mirror)
			)
		)
		(duplicate_pad_numbers_are_jumpers no)
		(fp_line
			(start -0.635 0)
			(end 0.635 0)
			(stroke
				(width 0.508)
				(type default)
			)
			(layer "B.SilkS")
		)
		(fp_rect
			(start 0.9652 1.778)
			(end -0.9652 -1.778)
			(stroke
				(width 0)
				(type default)
			)
			(fill no)
			(layer "B.CrtYd")
		)
		(fp_poly
			(pts
				(xy 0.9652 -1.778) (xy -0.9652 -1.778) (xy -0.9652 1.778) (xy 0.9652 1.778)
			)
			(stroke
				(width 0)
				(type default)
			)
			(fill no)
			(layer "B.Fab")
		)
		(pad "1" smd rect
			(at 0 -0.9652 90)
			(size 1.397 1.143)
			(layers "B.Cu" "B.Mask" "B.Paste")
			(net "P1V8_STBY")
		)
		(pad "2" smd rect
			(at 0 0.9652 90)
			(size 1.397 1.143)
			(layers "B.Cu" "B.Mask" "B.Paste")
			(net "GND")
		)
	)
	(footprint ""
		(layer "B.Cu")
		(at 51.4858 -135.7376)
		(property "Reference" "R167"
			(at 0 0 0)
			(layer "B.SilkS")
			(hide yes)
			(effects
				(font
					(size 1.27 1.27)
				)
				(justify mirror)
			)
		)
		(property "Value" "0R2J-2-GP"
			(at -0.064008 -3.993896 0)
			(unlocked yes)
			(layer "B.Fab")
			(hide yes)
			(effects
				(font
					(size 1.016 1.016)
					(thickness 0.1524)
				)
				(justify mirror)
			)
		)
		(property "Device Type" "R402H16"
			(at -0.064008 -5.517896 0)
			(unlocked yes)
			(layer "B.Fab")
			(hide yes)
			(effects
				(font
					(size 1.016 1.016)
					(thickness 0.1524)
				)
				(justify mirror)
			)
		)
		(duplicate_pad_numbers_are_jumpers no)
		(fp_line
			(start -0.508 -0.9398)
			(end 0.508 -0.9398)
			(stroke
				(width 0.1524)
				(type default)
			)
			(layer "B.SilkS")
		)
		(fp_line
			(start 0.508 -0.9398)
			(end 0.508 0.9398)
			(stroke
				(width 0.1524)
				(type default)
			)
			(layer "B.SilkS")
		)
		(fp_rect
			(start 0.508 0.9398)
			(end -0.508 -0.9398)
			(stroke
				(width 0)
				(type default)
			)
			(fill no)
			(layer "B.CrtYd")
		)
		(fp_rect
			(start 0.508 0.9398)
			(end -0.508 -0.9398)
			(stroke
				(width 0)
				(type default)
			)
			(fill no)
			(layer "B.Fab")
		)
		(pad "1" smd custom
			(at 0 -0.4445 180)
			(size 0.1397 0.1397)
			(layers "B.Cu" "B.Mask" "B.Paste")
			(net "PWRBTN_OUT_N_R")
			(options
				(clearance outline)
				(anchor circle)
			)
			(primitives
				(gr_poly
					(pts
						(arc
							(start -0.1778 0.2794)
							(mid -0.249642 0.249642)
							(end -0.2794 0.1778)
						)
						(arc
							(start -0.2794 -0.1778)
							(mid -0.249642 -0.249642)
							(end -0.1778 -0.2794)
						)
						(arc
							(start 0.1778 -0.2794)
							(mid 0.249642 -0.249642)
							(end 0.2794 -0.1778)
						)
						(arc
							(start 0.2794 0.1778)
							(mid 0.249642 0.249642)
							(end 0.1778 0.2794)
						)
					)
					(width 0)
					(fill yes)
				)
			)
		)
		(pad "2" smd custom
			(at 0 0.4445 180)
			(size 0.1397 0.1397)
			(layers "B.Cu" "B.Mask" "B.Paste")
			(net "PWRBTN_OUT_N")
			(options
				(clearance outline)
				(anchor circle)
			)
			(primitives
				(gr_poly
					(pts
						(arc
							(start -0.1778 0.2794)
							(mid -0.249642 0.249642)
							(end -0.2794 0.1778)
						)
						(arc
							(start -0.2794 -0.1778)
							(mid -0.249642 -0.249642)
							(end -0.1778 -0.2794)
						)
						(arc
							(start 0.1778 -0.2794)
							(mid 0.249642 -0.249642)
							(end 0.2794 -0.1778)
						)
						(arc
							(start 0.2794 0.1778)
							(mid 0.249642 0.249642)
							(end 0.1778 0.2794)
						)
					)
					(width 0)
					(fill yes)
				)
			)
		)
	)
	(footprint ""
		(layer "B.Cu")
		(at 56.847232 -162.025076 90)
		(property "Reference" "R415"
			(at 0 0 90)
			(layer "B.SilkS")
			(hide yes)
			(effects
				(font
					(size 1.27 1.27)
				)
				(justify mirror)
			)
		)
		(property "Value" "1KR2F-3-GP"
			(at -0.064008 -3.993896 90)
			(unlocked yes)
			(layer "B.Fab")
			(hide yes)
			(effects
				(font
					(size 1.016 1.016)
					(thickness 0.1524)
				)
				(justify mirror)
			)
		)
		(property "Device Type" "R402H16"
			(at -0.064008 -5.517896 90)
			(unlocked yes)
			(layer "B.Fab")
			(hide yes)
			(effects
				(font
					(size 1.016 1.016)
					(thickness 0.1524)
				)
				(justify mirror)
			)
		)
		(duplicate_pad_numbers_are_jumpers no)
		(fp_line
			(start 0.508 -0.9398)
			(end 0.508 0.9398)
			(stroke
				(width 0.1524)
				(type default)
			)
			(layer "B.SilkS")
		)
		(fp_line
			(start -0.508 -0.9398)
			(end 0.508 -0.9398)
			(stroke
				(width 0.1524)
				(type default)
			)
			(layer "B.SilkS")
		)
		(fp_rect
			(start 0.508 0.9398)
			(end -0.508 -0.9398)
			(stroke
				(width 0)
				(type default)
			)
			(fill no)
			(layer "B.CrtYd")
		)
		(fp_rect
			(start 0.508 0.9398)
			(end -0.508 -0.9398)
			(stroke
				(width 0)
				(type default)
			)
			(fill no)
			(layer "B.Fab")
		)
		(pad "1" smd custom
			(at 0 -0.4445 270)
			(size 0.1397 0.1397)
			(layers "B.Cu" "B.Mask" "B.Paste")
			(net "ADC_P5V_STBY")
			(options
				(clearance outline)
				(anchor circle)
			)
			(primitives
				(gr_poly
					(pts
						(arc
							(start -0.1778 0.2794)
							(mid -0.249642 0.249642)
							(end -0.2794 0.1778)
						)
						(arc
							(start -0.2794 -0.1778)
							(mid -0.249642 -0.249642)
							(end -0.1778 -0.2794)
						)
						(arc
							(start 0.1778 -0.2794)
							(mid 0.249642 -0.249642)
							(end 0.2794 -0.1778)
						)
						(arc
							(start 0.2794 0.1778)
							(mid 0.249642 0.249642)
							(end 0.1778 0.2794)
						)
					)
					(width 0)
					(fill yes)
				)
			)
		)
		(pad "2" smd custom
			(at 0 0.4445 270)
			(size 0.1397 0.1397)
			(layers "B.Cu" "B.Mask" "B.Paste")
			(net "GND")
			(options
				(clearance outline)
				(anchor circle)
			)
			(primitives
				(gr_poly
					(pts
						(arc
							(start -0.1778 0.2794)
							(mid -0.249642 0.249642)
							(end -0.2794 0.1778)
						)
						(arc
							(start -0.2794 -0.1778)
							(mid -0.249642 -0.249642)
							(end -0.1778 -0.2794)
						)
						(arc
							(start 0.1778 -0.2794)
							(mid 0.249642 -0.249642)
							(end 0.2794 -0.1778)
						)
						(arc
							(start 0.2794 0.1778)
							(mid 0.249642 0.249642)
							(end 0.1778 0.2794)
						)
					)
					(width 0)
					(fill yes)
				)
			)
		)
	)
	(footprint ""
		(layer "B.Cu")
		(at 113.2586 -8.8138)
		(property "Reference" "C150"
			(at 0 0 0)
			(layer "B.SilkS")
			(hide yes)
			(effects
				(font
					(size 1.27 1.27)
				)
				(justify mirror)
			)
		)
		(property "Value" "SCD1U50V3KX-GP"
			(at 0 -2.8194 0)
			(unlocked yes)
			(layer "B.Fab")
			(hide yes)
			(effects
				(font
					(size 1.016 1.016)
					(thickness 0.1524)
				)
				(justify mirror)
			)
		)
		(property "Device Type" "C603H36"
			(at 0 -4.3434 0)
			(unlocked yes)
			(layer "B.Fab")
			(hide yes)
			(effects
				(font
					(size 1.016 1.016)
					(thickness 0.1524)
				)
				(justify mirror)
			)
		)
		(duplicate_pad_numbers_are_jumpers no)
		(fp_line
			(start -0.508 0)
			(end 0.508 0)
			(stroke
				(width 0.2032)
				(type default)
			)
			(layer "B.SilkS")
		)
		(fp_rect
			(start 0.5842 1.3335)
			(end -0.5842 -1.3335)
			(stroke
				(width 0)
				(type default)
			)
			(fill no)
			(layer "B.CrtYd")
		)
		(fp_rect
			(start 0.5842 1.3335)
			(end -0.5842 -1.3335)
			(stroke
				(width 0)
				(type default)
			)
			(fill no)
			(layer "B.Fab")
		)
		(pad "1" smd custom
			(at 0 -0.762 180)
			(size 0.2159 0.2159)
			(layers "B.Cu" "B.Mask" "B.Paste")
			(net "MB0_ISTART_R")
			(options
				(clearance outline)
				(anchor circle)
			)
			(primitives
				(gr_poly
					(pts
						(arc
							(start -0.3302 0.4318)
							(mid -0.402042 0.402042)
							(end -0.4318 0.3302)
						)
						(arc
							(start -0.4318 -0.3302)
							(mid -0.402042 -0.402042)
							(end -0.3302 -0.4318)
						)
						(arc
							(start 0.3302 -0.4318)
							(mid 0.402042 -0.402042)
							(end 0.4318 -0.3302)
						)
						(arc
							(start 0.4318 0.3302)
							(mid 0.402042 0.402042)
							(end 0.3302 0.4318)
						)
					)
					(width 0)
					(fill yes)
				)
			)
		)
		(pad "2" smd custom
			(at 0 0.762 180)
			(size 0.2159 0.2159)
			(layers "B.Cu" "B.Mask" "B.Paste")
			(net "AGND_CURRENT_MON")
			(options
				(clearance outline)
				(anchor circle)
			)
			(primitives
				(gr_poly
					(pts
						(arc
							(start -0.3302 0.4318)
							(mid -0.402042 0.402042)
							(end -0.4318 0.3302)
						)
						(arc
							(start -0.4318 -0.3302)
							(mid -0.402042 -0.402042)
							(end -0.3302 -0.4318)
						)
						(arc
							(start 0.3302 -0.4318)
							(mid 0.402042 -0.402042)
							(end 0.4318 -0.3302)
						)
						(arc
							(start 0.4318 0.3302)
							(mid 0.402042 0.402042)
							(end 0.3302 0.4318)
						)
					)
					(width 0)
					(fill yes)
				)
			)
		)
	)
	(footprint ""
		(layer "B.Cu")
		(at 57.404 -148.8186 -90)
		(property "Reference" "R359"
			(at 0 0 90)
			(layer "B.SilkS")
			(hide yes)
			(effects
				(font
					(size 1.27 1.27)
				)
				(justify mirror)
			)
		)
		(property "Value" "10KR2F-2-GP"
			(at -0.064008 -3.993896 270)
			(unlocked yes)
			(layer "B.Fab")
			(hide yes)
			(effects
				(font
					(size 1.016 1.016)
					(thickness 0.1524)
				)
				(justify mirror)
			)
		)
		(property "Device Type" "R402H16"
			(at -0.064008 -5.517896 270)
			(unlocked yes)
			(layer "B.Fab")
			(hide yes)
			(effects
				(font
					(size 1.016 1.016)
					(thickness 0.1524)
				)
				(justify mirror)
			)
		)
		(duplicate_pad_numbers_are_jumpers no)
		(fp_line
			(start -0.508 -0.9398)
			(end 0.508 -0.9398)
			(stroke
				(width 0.1524)
				(type default)
			)
			(layer "B.SilkS")
		)
		(fp_line
			(start 0.508 -0.9398)
			(end 0.508 0.9398)
			(stroke
				(width 0.1524)
				(type default)
			)
			(layer "B.SilkS")
		)
		(fp_rect
			(start 0.508 0.9398)
			(end -0.508 -0.9398)
			(stroke
				(width 0)
				(type default)
			)
			(fill no)
			(layer "B.CrtYd")
		)
		(fp_rect
			(start 0.508 0.9398)
			(end -0.508 -0.9398)
			(stroke
				(width 0)
				(type default)
			)
			(fill no)
			(layer "B.Fab")
		)
		(pad "1" smd custom
			(at 0 -0.4445 90)
			(size 0.1397 0.1397)
			(layers "B.Cu" "B.Mask" "B.Paste")
			(net "P3V3_STBY")
			(options
				(clearance outline)
				(anchor circle)
			)
			(primitives
				(gr_poly
					(pts
						(arc
							(start -0.1778 0.2794)
							(mid -0.249642 0.249642)
							(end -0.2794 0.1778)
						)
						(arc
							(start -0.2794 -0.1778)
							(mid -0.249642 -0.249642)
							(end -0.1778 -0.2794)
						)
						(arc
							(start 0.1778 -0.2794)
							(mid 0.249642 -0.249642)
							(end 0.2794 -0.1778)
						)
						(arc
							(start 0.2794 0.1778)
							(mid 0.249642 0.249642)
							(end 0.1778 0.2794)
						)
					)
					(width 0)
					(fill yes)
				)
			)
		)
		(pad "2" smd custom
			(at 0 0.4445 90)
			(size 0.1397 0.1397)
			(layers "B.Cu" "B.Mask" "B.Paste")
			(net "JTAG_BMC_TMS")
			(options
				(clearance outline)
				(anchor circle)
			)
			(primitives
				(gr_poly
					(pts
						(arc
							(start -0.1778 0.2794)
							(mid -0.249642 0.249642)
							(end -0.2794 0.1778)
						)
						(arc
							(start -0.2794 -0.1778)
							(mid -0.249642 -0.249642)
							(end -0.1778 -0.2794)
						)
						(arc
							(start 0.1778 -0.2794)
							(mid 0.249642 -0.249642)
							(end 0.2794 -0.1778)
						)
						(arc
							(start 0.2794 0.1778)
							(mid 0.249642 0.249642)
							(end 0.1778 0.2794)
						)
					)
					(width 0)
					(fill yes)
				)
			)
		)
	)
	(footprint ""
		(layer "B.Cu")
		(at 197.260718 -81.153 180)
		(property "Reference" "C296"
			(at 0 0 0)
			(layer "B.SilkS")
			(hide yes)
			(effects
				(font
					(size 1.27 1.27)
				)
				(justify mirror)
			)
		)
		(property "Value" "SCD22U10V1KX-GP"
			(at 2.8321 -1.7399 180)
			(unlocked yes)
			(layer "B.Fab")
			(hide yes)
			(effects
				(font
					(size 1.016 1.016)
					(thickness 0.1524)
				)
				(justify mirror)
			)
		)
		(property "Device Type" "C0201H13"
			(at 2.8321 -3.2639 180)
			(unlocked yes)
			(layer "B.Fab")
			(hide yes)
			(effects
				(font
					(size 1.016 1.016)
					(thickness 0.1524)
				)
				(justify mirror)
			)
		)
		(duplicate_pad_numbers_are_jumpers no)
		(fp_rect
			(start 0.2794 0.6477)
			(end -0.2794 -0.6477)
			(stroke
				(width 0)
				(type default)
			)
			(fill no)
			(layer "B.CrtYd")
		)
		(fp_rect
			(start 0.2794 0.6477)
			(end -0.2794 -0.6477)
			(stroke
				(width 0)
				(type default)
			)
			(fill no)
			(layer "B.Fab")
		)
		(pad "1" smd custom
			(at 0 -0.2794)
			(size 0.0762 0.0762)
			(layers "B.Cu" "B.Mask" "B.Paste")
			(net "PCIE_IOM_TO_COMP_11_DN_C")
			(options
				(clearance outline)
				(anchor circle)
			)
			(primitives
				(gr_poly
					(pts
						(arc
							(start 0.1524 0.127)
							(mid 0.137521 0.162921)
							(end 0.1016 0.1778)
						)
						(arc
							(start -0.1016 0.1778)
							(mid -0.137521 0.162921)
							(end -0.1524 0.127)
						)
						(arc
							(start -0.1524 -0.127)
							(mid -0.137521 -0.162921)
							(end -0.1016 -0.1778)
						)
						(arc
							(start 0.1016 -0.1778)
							(mid 0.137521 -0.162921)
							(end 0.1524 -0.127)
						)
					)
					(width 0)
					(fill yes)
				)
			)
		)
		(pad "2" smd custom
			(at 0 0.2794)
			(size 0.0762 0.0762)
			(layers "B.Cu" "B.Mask" "B.Paste")
			(net "PCIE_IOM_TO_COMP_11_DN")
			(options
				(clearance outline)
				(anchor circle)
			)
			(primitives
				(gr_poly
					(pts
						(arc
							(start 0.1524 0.127)
							(mid 0.137521 0.162921)
							(end 0.1016 0.1778)
						)
						(arc
							(start -0.1016 0.1778)
							(mid -0.137521 0.162921)
							(end -0.1524 0.127)
						)
						(arc
							(start -0.1524 -0.127)
							(mid -0.137521 -0.162921)
							(end -0.1016 -0.1778)
						)
						(arc
							(start 0.1016 -0.1778)
							(mid 0.137521 -0.162921)
							(end 0.1524 -0.127)
						)
					)
					(width 0)
					(fill yes)
				)
			)
		)
	)
	(footprint ""
		(layer "B.Cu")
		(at 172.593 -77.851 180)
		(property "Reference" "C343"
			(at 0 0 0)
			(layer "B.SilkS")
			(hide yes)
			(effects
				(font
					(size 1.27 1.27)
				)
				(justify mirror)
			)
		)
		(property "Value" "SC10U6D3V5KX-4GP"
			(at 0.0762 -6.1214 180)
			(unlocked yes)
			(layer "B.Fab")
			(hide yes)
			(effects
				(font
					(size 1.016 1.016)
					(thickness 0.1524)
				)
				(justify mirror)
			)
		)
		(property "Device Type" "C805H58"
			(at 0.0762 -8.1534 180)
			(unlocked yes)
			(layer "B.Fab")
			(hide yes)
			(effects
				(font
					(size 1.016 1.016)
					(thickness 0.1524)
				)
				(justify mirror)
			)
		)
		(duplicate_pad_numbers_are_jumpers no)
		(fp_line
			(start -0.635 0)
			(end 0.635 0)
			(stroke
				(width 0.508)
				(type default)
			)
			(layer "B.SilkS")
		)
		(fp_rect
			(start 0.9652 1.778)
			(end -0.9652 -1.778)
			(stroke
				(width 0)
				(type default)
			)
			(fill no)
			(layer "B.CrtYd")
		)
		(fp_poly
			(pts
				(xy 0.9652 -1.778) (xy -0.9652 -1.778) (xy -0.9652 1.778) (xy 0.9652 1.778)
			)
			(stroke
				(width 0)
				(type default)
			)
			(fill no)
			(layer "B.Fab")
		)
		(pad "1" smd rect
			(at 0 -0.9652)
			(size 1.397 1.143)
			(layers "B.Cu" "B.Mask" "B.Paste")
			(net "PLL_VDD")
		)
		(pad "2" smd rect
			(at 0 0.9652)
			(size 1.397 1.143)
			(layers "B.Cu" "B.Mask" "B.Paste")
			(net "GND")
		)
	)
	(footprint ""
		(layer "B.Cu")
		(at 41.3512 -125.1204 180)
		(property "Reference" "R362"
			(at 0 0 0)
			(layer "B.SilkS")
			(hide yes)
			(effects
				(font
					(size 1.27 1.27)
				)
				(justify mirror)
			)
		)
		(property "Value" "4K7R2F-GP"
			(at -0.064008 -3.993896 180)
			(unlocked yes)
			(layer "B.Fab")
			(hide yes)
			(effects
				(font
					(size 1.016 1.016)
					(thickness 0.1524)
				)
				(justify mirror)
			)
		)
		(property "Device Type" "R402H16"
			(at -0.064008 -5.517896 180)
			(unlocked yes)
			(layer "B.Fab")
			(hide yes)
			(effects
				(font
					(size 1.016 1.016)
					(thickness 0.1524)
				)
				(justify mirror)
			)
		)
		(duplicate_pad_numbers_are_jumpers no)
		(fp_line
			(start 0.508 -0.9398)
			(end 0.508 0.9398)
			(stroke
				(width 0.1524)
				(type default)
			)
			(layer "B.SilkS")
		)
		(fp_line
			(start -0.508 -0.9398)
			(end 0.508 -0.9398)
			(stroke
				(width 0.1524)
				(type default)
			)
			(layer "B.SilkS")
		)
		(fp_rect
			(start 0.508 0.9398)
			(end -0.508 -0.9398)
			(stroke
				(width 0)
				(type default)
			)
			(fill no)
			(layer "B.CrtYd")
		)
		(fp_rect
			(start 0.508 0.9398)
			(end -0.508 -0.9398)
			(stroke
				(width 0)
				(type default)
			)
			(fill no)
			(layer "B.Fab")
		)
		(pad "1" smd custom
			(at 0 -0.4445)
			(size 0.1397 0.1397)
			(layers "B.Cu" "B.Mask" "B.Paste")
			(net "P3V3_STBY")
			(options
				(clearance outline)
				(anchor circle)
			)
			(primitives
				(gr_poly
					(pts
						(arc
							(start -0.1778 0.2794)
							(mid -0.249642 0.249642)
							(end -0.2794 0.1778)
						)
						(arc
							(start -0.2794 -0.1778)
							(mid -0.249642 -0.249642)
							(end -0.1778 -0.2794)
						)
						(arc
							(start 0.1778 -0.2794)
							(mid 0.249642 -0.249642)
							(end 0.2794 -0.1778)
						)
						(arc
							(start 0.2794 0.1778)
							(mid 0.249642 0.249642)
							(end 0.1778 0.2794)
						)
					)
					(width 0)
					(fill yes)
				)
			)
		)
		(pad "2" smd custom
			(at 0 0.4445)
			(size 0.1397 0.1397)
			(layers "B.Cu" "B.Mask" "B.Paste")
			(net "FM_BMC_RESET_N")
			(options
				(clearance outline)
				(anchor circle)
			)
			(primitives
				(gr_poly
					(pts
						(arc
							(start -0.1778 0.2794)
							(mid -0.249642 0.249642)
							(end -0.2794 0.1778)
						)
						(arc
							(start -0.2794 -0.1778)
							(mid -0.249642 -0.249642)
							(end -0.1778 -0.2794)
						)
						(arc
							(start 0.1778 -0.2794)
							(mid 0.249642 -0.249642)
							(end 0.2794 -0.1778)
						)
						(arc
							(start 0.2794 0.1778)
							(mid 0.249642 0.249642)
							(end 0.1778 0.2794)
						)
					)
					(width 0)
					(fill yes)
				)
			)
		)
	)
	(footprint ""
		(layer "B.Cu")
		(at 199.31126 -63.46952 90)
		(property "Reference" "R648"
			(at 0 0 90)
			(layer "B.SilkS")
			(hide yes)
			(effects
				(font
					(size 1.27 1.27)
				)
				(justify mirror)
			)
		)
		(property "Value" "10KR2F-2-GP"
			(at -0.064008 -3.993896 90)
			(unlocked yes)
			(layer "B.Fab")
			(hide yes)
			(effects
				(font
					(size 1.016 1.016)
					(thickness 0.1524)
				)
				(justify mirror)
			)
		)
		(property "Device Type" "R402H16"
			(at -0.064008 -5.517896 90)
			(unlocked yes)
			(layer "B.Fab")
			(hide yes)
			(effects
				(font
					(size 1.016 1.016)
					(thickness 0.1524)
				)
				(justify mirror)
			)
		)
		(duplicate_pad_numbers_are_jumpers no)
		(fp_line
			(start 0.508 -0.9398)
			(end 0.508 0.9398)
			(stroke
				(width 0.1524)
				(type default)
			)
			(layer "B.SilkS")
		)
		(fp_line
			(start -0.508 -0.9398)
			(end 0.508 -0.9398)
			(stroke
				(width 0.1524)
				(type default)
			)
			(layer "B.SilkS")
		)
		(fp_rect
			(start 0.508 0.9398)
			(end -0.508 -0.9398)
			(stroke
				(width 0)
				(type default)
			)
			(fill no)
			(layer "B.CrtYd")
		)
		(fp_rect
			(start 0.508 0.9398)
			(end -0.508 -0.9398)
			(stroke
				(width 0)
				(type default)
			)
			(fill no)
			(layer "B.Fab")
		)
		(pad "1" smd custom
			(at 0 -0.4445 270)
			(size 0.1397 0.1397)
			(layers "B.Cu" "B.Mask" "B.Paste")
			(net "P1V8")
			(options
				(clearance outline)
				(anchor circle)
			)
			(primitives
				(gr_poly
					(pts
						(arc
							(start -0.1778 0.2794)
							(mid -0.249642 0.249642)
							(end -0.2794 0.1778)
						)
						(arc
							(start -0.2794 -0.1778)
							(mid -0.249642 -0.249642)
							(end -0.1778 -0.2794)
						)
						(arc
							(start 0.1778 -0.2794)
							(mid 0.249642 -0.249642)
							(end 0.2794 -0.1778)
						)
						(arc
							(start 0.2794 0.1778)
							(mid 0.249642 0.249642)
							(end 0.1778 0.2794)
						)
					)
					(width 0)
					(fill yes)
				)
			)
		)
		(pad "2" smd custom
			(at 0 0.4445 270)
			(size 0.1397 0.1397)
			(layers "B.Cu" "B.Mask" "B.Paste")
			(net "POWERLOSS#")
			(options
				(clearance outline)
				(anchor circle)
			)
			(primitives
				(gr_poly
					(pts
						(arc
							(start -0.1778 0.2794)
							(mid -0.249642 0.249642)
							(end -0.2794 0.1778)
						)
						(arc
							(start -0.2794 -0.1778)
							(mid -0.249642 -0.249642)
							(end -0.1778 -0.2794)
						)
						(arc
							(start 0.1778 -0.2794)
							(mid 0.249642 -0.249642)
							(end 0.2794 -0.1778)
						)
						(arc
							(start 0.2794 0.1778)
							(mid 0.249642 0.249642)
							(end 0.1778 0.2794)
						)
					)
					(width 0)
					(fill yes)
				)
			)
		)
	)
	(footprint ""
		(layer "B.Cu")
		(at 33.9344 -150.8252 180)
		(property "Reference" "C93"
			(at 0 0 0)
			(layer "B.SilkS")
			(hide yes)
			(effects
				(font
					(size 1.27 1.27)
				)
				(justify mirror)
			)
		)
		(property "Value" "SCD1U16V2KX-3GP"
			(at -1.1811 -2.7051 180)
			(unlocked yes)
			(layer "B.Fab")
			(hide yes)
			(effects
				(font
					(size 1.016 1.016)
					(thickness 0.1524)
				)
				(justify mirror)
			)
		)
		(property "Device Type" "C402H22"
			(at -1.1811 -4.2291 180)
			(unlocked yes)
			(layer "B.Fab")
			(hide yes)
			(effects
				(font
					(size 1.016 1.016)
					(thickness 0.1524)
				)
				(justify mirror)
			)
		)
		(duplicate_pad_numbers_are_jumpers no)
		(fp_rect
			(start 0.4318 0.9525)
			(end -0.4318 -0.9525)
			(stroke
				(width 0)
				(type default)
			)
			(fill no)
			(layer "B.CrtYd")
		)
		(fp_rect
			(start 0.4318 0.9525)
			(end -0.4318 -0.9525)
			(stroke
				(width 0)
				(type default)
			)
			(fill no)
			(layer "B.Fab")
		)
		(pad "1" smd custom
			(at 0 -0.4445)
			(size 0.1524 0.1524)
			(layers "B.Cu" "B.Mask" "B.Paste")
			(net "MPLLAV33")
			(options
				(clearance outline)
				(anchor circle)
			)
			(primitives
				(gr_poly
					(pts
						(arc
							(start 0.3048 0.2032)
							(mid 0.275042 0.275042)
							(end 0.2032 0.3048)
						)
						(arc
							(start -0.2032 0.3048)
							(mid -0.275042 0.275042)
							(end -0.3048 0.2032)
						)
						(arc
							(start -0.3048 -0.2032)
							(mid -0.275042 -0.275042)
							(end -0.2032 -0.3048)
						)
						(arc
							(start 0.2032 -0.3048)
							(mid 0.275042 -0.275042)
							(end 0.3048 -0.2032)
						)
					)
					(width 0)
					(fill yes)
				)
			)
		)
		(pad "2" smd custom
			(at 0 0.4445)
			(size 0.1524 0.1524)
			(layers "B.Cu" "B.Mask" "B.Paste")
			(net "GND")
			(options
				(clearance outline)
				(anchor circle)
			)
			(primitives
				(gr_poly
					(pts
						(arc
							(start 0.3048 0.2032)
							(mid 0.275042 0.275042)
							(end 0.2032 0.3048)
						)
						(arc
							(start -0.2032 0.3048)
							(mid -0.275042 0.275042)
							(end -0.3048 0.2032)
						)
						(arc
							(start -0.3048 -0.2032)
							(mid -0.275042 -0.275042)
							(end -0.2032 -0.3048)
						)
						(arc
							(start 0.2032 -0.3048)
							(mid 0.275042 -0.275042)
							(end 0.3048 -0.2032)
						)
					)
					(width 0)
					(fill yes)
				)
			)
		)
	)
	(footprint ""
		(layer "B.Cu")
		(at 204.7494 -56.9468 180)
		(property "Reference" "R590"
			(at 0 0 0)
			(layer "B.SilkS")
			(hide yes)
			(effects
				(font
					(size 1.27 1.27)
				)
				(justify mirror)
			)
		)
		(property "Value" "2K2R2F-GP"
			(at -0.064008 -3.993896 180)
			(unlocked yes)
			(layer "B.Fab")
			(hide yes)
			(effects
				(font
					(size 1.016 1.016)
					(thickness 0.1524)
				)
				(justify mirror)
			)
		)
		(property "Device Type" "R402H16"
			(at -0.064008 -5.517896 180)
			(unlocked yes)
			(layer "B.Fab")
			(hide yes)
			(effects
				(font
					(size 1.016 1.016)
					(thickness 0.1524)
				)
				(justify mirror)
			)
		)
		(duplicate_pad_numbers_are_jumpers no)
		(fp_line
			(start 0.508 -0.9398)
			(end 0.508 0.9398)
			(stroke
				(width 0.1524)
				(type default)
			)
			(layer "B.SilkS")
		)
		(fp_line
			(start -0.508 -0.9398)
			(end 0.508 -0.9398)
			(stroke
				(width 0.1524)
				(type default)
			)
			(layer "B.SilkS")
		)
		(fp_rect
			(start 0.508 0.9398)
			(end -0.508 -0.9398)
			(stroke
				(width 0)
				(type default)
			)
			(fill no)
			(layer "B.CrtYd")
		)
		(fp_rect
			(start 0.508 0.9398)
			(end -0.508 -0.9398)
			(stroke
				(width 0)
				(type default)
			)
			(fill no)
			(layer "B.Fab")
		)
		(pad "1" smd custom
			(at 0 -0.4445)
			(size 0.1397 0.1397)
			(layers "B.Cu" "B.Mask" "B.Paste")
			(net "P1V8")
			(options
				(clearance outline)
				(anchor circle)
			)
			(primitives
				(gr_poly
					(pts
						(arc
							(start -0.1778 0.2794)
							(mid -0.249642 0.249642)
							(end -0.2794 0.1778)
						)
						(arc
							(start -0.2794 -0.1778)
							(mid -0.249642 -0.249642)
							(end -0.1778 -0.2794)
						)
						(arc
							(start 0.1778 -0.2794)
							(mid 0.249642 -0.249642)
							(end 0.2794 -0.1778)
						)
						(arc
							(start 0.2794 0.1778)
							(mid 0.249642 0.249642)
							(end 0.1778 0.2794)
						)
					)
					(width 0)
					(fill yes)
				)
			)
		)
		(pad "2" smd custom
			(at 0 0.4445)
			(size 0.1397 0.1397)
			(layers "B.Cu" "B.Mask" "B.Paste")
			(net "SIO_DOUT_0")
			(options
				(clearance outline)
				(anchor circle)
			)
			(primitives
				(gr_poly
					(pts
						(arc
							(start -0.1778 0.2794)
							(mid -0.249642 0.249642)
							(end -0.2794 0.1778)
						)
						(arc
							(start -0.2794 -0.1778)
							(mid -0.249642 -0.249642)
							(end -0.1778 -0.2794)
						)
						(arc
							(start 0.1778 -0.2794)
							(mid 0.249642 -0.249642)
							(end 0.2794 -0.1778)
						)
						(arc
							(start 0.2794 0.1778)
							(mid 0.249642 0.249642)
							(end 0.1778 0.2794)
						)
					)
					(width 0)
					(fill yes)
				)
			)
		)
	)
	(footprint ""
		(layer "B.Cu")
		(at 190.8175 -65.3796 90)
		(property "Reference" "C417"
			(at 0 0 90)
			(layer "B.SilkS")
			(hide yes)
			(effects
				(font
					(size 1.27 1.27)
				)
				(justify mirror)
			)
		)
		(property "Value" "SCD1U6D3V1KX-GP"
			(at 2.8321 -1.7399 90)
			(unlocked yes)
			(layer "B.Fab")
			(hide yes)
			(effects
				(font
					(size 1.016 1.016)
					(thickness 0.1524)
				)
				(justify mirror)
			)
		)
		(property "Device Type" "C0201H13"
			(at 2.8321 -3.2639 90)
			(unlocked yes)
			(layer "B.Fab")
			(hide yes)
			(effects
				(font
					(size 1.016 1.016)
					(thickness 0.1524)
				)
				(justify mirror)
			)
		)
		(duplicate_pad_numbers_are_jumpers no)
		(fp_rect
			(start 0.2794 0.6477)
			(end -0.2794 -0.6477)
			(stroke
				(width 0)
				(type default)
			)
			(fill no)
			(layer "B.CrtYd")
		)
		(fp_rect
			(start 0.2794 0.6477)
			(end -0.2794 -0.6477)
			(stroke
				(width 0)
				(type default)
			)
			(fill no)
			(layer "B.Fab")
		)
		(pad "1" smd custom
			(at 0 -0.2794 270)
			(size 0.0762 0.0762)
			(layers "B.Cu" "B.Mask" "B.Paste")
			(net "P0V975")
			(options
				(clearance outline)
				(anchor circle)
			)
			(primitives
				(gr_poly
					(pts
						(arc
							(start 0.1524 0.127)
							(mid 0.137521 0.162921)
							(end 0.1016 0.1778)
						)
						(arc
							(start -0.1016 0.1778)
							(mid -0.137521 0.162921)
							(end -0.1524 0.127)
						)
						(arc
							(start -0.1524 -0.127)
							(mid -0.137521 -0.162921)
							(end -0.1016 -0.1778)
						)
						(arc
							(start 0.1016 -0.1778)
							(mid 0.137521 -0.162921)
							(end 0.1524 -0.127)
						)
					)
					(width 0)
					(fill yes)
				)
			)
		)
		(pad "2" smd custom
			(at 0 0.2794 270)
			(size 0.0762 0.0762)
			(layers "B.Cu" "B.Mask" "B.Paste")
			(net "GND")
			(options
				(clearance outline)
				(anchor circle)
			)
			(primitives
				(gr_poly
					(pts
						(arc
							(start 0.1524 0.127)
							(mid 0.137521 0.162921)
							(end 0.1016 0.1778)
						)
						(arc
							(start -0.1016 0.1778)
							(mid -0.137521 0.162921)
							(end -0.1524 0.127)
						)
						(arc
							(start -0.1524 -0.127)
							(mid -0.137521 -0.162921)
							(end -0.1016 -0.1778)
						)
						(arc
							(start 0.1016 -0.1778)
							(mid 0.137521 -0.162921)
							(end 0.1524 -0.127)
						)
					)
					(width 0)
					(fill yes)
				)
			)
		)
	)
	(footprint ""
		(layer "B.Cu")
		(at 10.174732 -136.716516 90)
		(property "Reference" "R250"
			(at 0 0 90)
			(layer "B.SilkS")
			(hide yes)
			(effects
				(font
					(size 1.27 1.27)
				)
				(justify mirror)
			)
		)
		(property "Value" "120R2F-GP"
			(at -0.064008 -3.993896 90)
			(unlocked yes)
			(layer "B.Fab")
			(hide yes)
			(effects
				(font
					(size 1.016 1.016)
					(thickness 0.1524)
				)
				(justify mirror)
			)
		)
		(property "Device Type" "R402H16"
			(at -0.064008 -5.517896 90)
			(unlocked yes)
			(layer "B.Fab")
			(hide yes)
			(effects
				(font
					(size 1.016 1.016)
					(thickness 0.1524)
				)
				(justify mirror)
			)
		)
		(duplicate_pad_numbers_are_jumpers no)
		(fp_line
			(start 0.508 -0.9398)
			(end 0.508 0.9398)
			(stroke
				(width 0.1524)
				(type default)
			)
			(layer "B.SilkS")
		)
		(fp_line
			(start -0.508 -0.9398)
			(end 0.508 -0.9398)
			(stroke
				(width 0.1524)
				(type default)
			)
			(layer "B.SilkS")
		)
		(fp_rect
			(start 0.508 0.9398)
			(end -0.508 -0.9398)
			(stroke
				(width 0)
				(type default)
			)
			(fill no)
			(layer "B.CrtYd")
		)
		(fp_rect
			(start 0.508 0.9398)
			(end -0.508 -0.9398)
			(stroke
				(width 0)
				(type default)
			)
			(fill no)
			(layer "B.Fab")
		)
		(pad "1" smd custom
			(at 0 -0.4445 270)
			(size 0.1397 0.1397)
			(layers "B.Cu" "B.Mask" "B.Paste")
			(net "GND")
			(options
				(clearance outline)
				(anchor circle)
			)
			(primitives
				(gr_poly
					(pts
						(arc
							(start -0.1778 0.2794)
							(mid -0.249642 0.249642)
							(end -0.2794 0.1778)
						)
						(arc
							(start -0.2794 -0.1778)
							(mid -0.249642 -0.249642)
							(end -0.1778 -0.2794)
						)
						(arc
							(start 0.1778 -0.2794)
							(mid 0.249642 -0.249642)
							(end 0.2794 -0.1778)
						)
						(arc
							(start 0.2794 0.1778)
							(mid 0.249642 0.249642)
							(end 0.1778 0.2794)
						)
					)
					(width 0)
					(fill yes)
				)
			)
		)
		(pad "2" smd custom
			(at 0 0.4445 270)
			(size 0.1397 0.1397)
			(layers "B.Cu" "B.Mask" "B.Paste")
			(net "MEMA_8")
			(options
				(clearance outline)
				(anchor circle)
			)
			(primitives
				(gr_poly
					(pts
						(arc
							(start -0.1778 0.2794)
							(mid -0.249642 0.249642)
							(end -0.2794 0.1778)
						)
						(arc
							(start -0.2794 -0.1778)
							(mid -0.249642 -0.249642)
							(end -0.1778 -0.2794)
						)
						(arc
							(start 0.1778 -0.2794)
							(mid 0.249642 -0.249642)
							(end 0.2794 -0.1778)
						)
						(arc
							(start 0.2794 0.1778)
							(mid 0.249642 0.249642)
							(end 0.1778 0.2794)
						)
					)
					(width 0)
					(fill yes)
				)
			)
		)
	)
	(footprint ""
		(layer "B.Cu")
		(at 200.359518 -81.153 180)
		(property "Reference" "C291"
			(at 0 0 0)
			(layer "B.SilkS")
			(hide yes)
			(effects
				(font
					(size 1.27 1.27)
				)
				(justify mirror)
			)
		)
		(property "Value" "SCD22U10V1KX-GP"
			(at 2.8321 -1.7399 180)
			(unlocked yes)
			(layer "B.Fab")
			(hide yes)
			(effects
				(font
					(size 1.016 1.016)
					(thickness 0.1524)
				)
				(justify mirror)
			)
		)
		(property "Device Type" "C0201H13"
			(at 2.8321 -3.2639 180)
			(unlocked yes)
			(layer "B.Fab")
			(hide yes)
			(effects
				(font
					(size 1.016 1.016)
					(thickness 0.1524)
				)
				(justify mirror)
			)
		)
		(duplicate_pad_numbers_are_jumpers no)
		(fp_rect
			(start 0.2794 0.6477)
			(end -0.2794 -0.6477)
			(stroke
				(width 0)
				(type default)
			)
			(fill no)
			(layer "B.CrtYd")
		)
		(fp_rect
			(start 0.2794 0.6477)
			(end -0.2794 -0.6477)
			(stroke
				(width 0)
				(type default)
			)
			(fill no)
			(layer "B.Fab")
		)
		(pad "1" smd custom
			(at 0 -0.2794)
			(size 0.0762 0.0762)
			(layers "B.Cu" "B.Mask" "B.Paste")
			(net "PCIE_IOM_TO_COMP_9_DP_C")
			(options
				(clearance outline)
				(anchor circle)
			)
			(primitives
				(gr_poly
					(pts
						(arc
							(start 0.1524 0.127)
							(mid 0.137521 0.162921)
							(end 0.1016 0.1778)
						)
						(arc
							(start -0.1016 0.1778)
							(mid -0.137521 0.162921)
							(end -0.1524 0.127)
						)
						(arc
							(start -0.1524 -0.127)
							(mid -0.137521 -0.162921)
							(end -0.1016 -0.1778)
						)
						(arc
							(start 0.1016 -0.1778)
							(mid 0.137521 -0.162921)
							(end 0.1524 -0.127)
						)
					)
					(width 0)
					(fill yes)
				)
			)
		)
		(pad "2" smd custom
			(at 0 0.2794)
			(size 0.0762 0.0762)
			(layers "B.Cu" "B.Mask" "B.Paste")
			(net "PCIE_IOM_TO_COMP_9_DP")
			(options
				(clearance outline)
				(anchor circle)
			)
			(primitives
				(gr_poly
					(pts
						(arc
							(start 0.1524 0.127)
							(mid 0.137521 0.162921)
							(end 0.1016 0.1778)
						)
						(arc
							(start -0.1016 0.1778)
							(mid -0.137521 0.162921)
							(end -0.1524 0.127)
						)
						(arc
							(start -0.1524 -0.127)
							(mid -0.137521 -0.162921)
							(end -0.1016 -0.1778)
						)
						(arc
							(start 0.1016 -0.1778)
							(mid 0.137521 -0.162921)
							(end 0.1524 -0.127)
						)
					)
					(width 0)
					(fill yes)
				)
			)
		)
	)
	(footprint ""
		(layer "B.Cu")
		(at 207.18018 -61.69406)
		(property "Reference" "TP111"
			(at 0 0 0)
			(layer "B.SilkS")
			(hide yes)
			(effects
				(font
					(size 1.27 1.27)
				)
				(justify mirror)
			)
		)
		(property "Value" "TPAD28-2-GP"
			(at 0.0127 -1.6637 0)
			(unlocked yes)
			(layer "B.Fab")
			(hide yes)
			(effects
				(font
					(size 1.016 1.016)
					(thickness 0.1524)
				)
				(justify mirror)
			)
		)
		(property "Device Type" "TPAD28"
			(at 0.0127 -3.1877 0)
			(unlocked yes)
			(layer "B.Fab")
			(hide yes)
			(effects
				(font
					(size 1.016 1.016)
					(thickness 0.1524)
				)
				(justify mirror)
			)
		)
		(duplicate_pad_numbers_are_jumpers no)
		(fp_poly
			(pts
				(arc
					(start 0.3556 0)
					(mid -0.3556 0)
					(end 0.3556 0)
				)
			)
			(stroke
				(width 0)
				(type default)
			)
			(fill no)
			(layer "B.CrtYd")
		)
		(fp_poly
			(pts
				(arc
					(start 0.6096 0)
					(mid -0.6096 0)
					(end 0.6096 0)
				)
			)
			(stroke
				(width 0)
				(type default)
			)
			(fill no)
			(layer "B.Fab")
		)
		(pad "1" smd circle
			(at 0 0 180)
			(size 0.7112 0.7112)
			(layers "B.Cu" "B.Mask" "B.Paste")
			(net "SIO_CLK_0")
		)
	)
	(footprint ""
		(layer "B.Cu")
		(at 199.800718 -81.153 180)
		(property "Reference" "C292"
			(at 0 0 0)
			(layer "B.SilkS")
			(hide yes)
			(effects
				(font
					(size 1.27 1.27)
				)
				(justify mirror)
			)
		)
		(property "Value" "SCD22U10V1KX-GP"
			(at 2.8321 -1.7399 180)
			(unlocked yes)
			(layer "B.Fab")
			(hide yes)
			(effects
				(font
					(size 1.016 1.016)
					(thickness 0.1524)
				)
				(justify mirror)
			)
		)
		(property "Device Type" "C0201H13"
			(at 2.8321 -3.2639 180)
			(unlocked yes)
			(layer "B.Fab")
			(hide yes)
			(effects
				(font
					(size 1.016 1.016)
					(thickness 0.1524)
				)
				(justify mirror)
			)
		)
		(duplicate_pad_numbers_are_jumpers no)
		(fp_rect
			(start 0.2794 0.6477)
			(end -0.2794 -0.6477)
			(stroke
				(width 0)
				(type default)
			)
			(fill no)
			(layer "B.CrtYd")
		)
		(fp_rect
			(start 0.2794 0.6477)
			(end -0.2794 -0.6477)
			(stroke
				(width 0)
				(type default)
			)
			(fill no)
			(layer "B.Fab")
		)
		(pad "1" smd custom
			(at 0 -0.2794)
			(size 0.0762 0.0762)
			(layers "B.Cu" "B.Mask" "B.Paste")
			(net "PCIE_IOM_TO_COMP_9_DN_C")
			(options
				(clearance outline)
				(anchor circle)
			)
			(primitives
				(gr_poly
					(pts
						(arc
							(start 0.1524 0.127)
							(mid 0.137521 0.162921)
							(end 0.1016 0.1778)
						)
						(arc
							(start -0.1016 0.1778)
							(mid -0.137521 0.162921)
							(end -0.1524 0.127)
						)
						(arc
							(start -0.1524 -0.127)
							(mid -0.137521 -0.162921)
							(end -0.1016 -0.1778)
						)
						(arc
							(start 0.1016 -0.1778)
							(mid 0.137521 -0.162921)
							(end 0.1524 -0.127)
						)
					)
					(width 0)
					(fill yes)
				)
			)
		)
		(pad "2" smd custom
			(at 0 0.2794)
			(size 0.0762 0.0762)
			(layers "B.Cu" "B.Mask" "B.Paste")
			(net "PCIE_IOM_TO_COMP_9_DN")
			(options
				(clearance outline)
				(anchor circle)
			)
			(primitives
				(gr_poly
					(pts
						(arc
							(start 0.1524 0.127)
							(mid 0.137521 0.162921)
							(end 0.1016 0.1778)
						)
						(arc
							(start -0.1016 0.1778)
							(mid -0.137521 0.162921)
							(end -0.1524 0.127)
						)
						(arc
							(start -0.1524 -0.127)
							(mid -0.137521 -0.162921)
							(end -0.1016 -0.1778)
						)
						(arc
							(start 0.1016 -0.1778)
							(mid 0.137521 -0.162921)
							(end 0.1524 -0.127)
						)
					)
					(width 0)
					(fill yes)
				)
			)
		)
	)
	(footprint ""
		(layer "B.Cu")
		(at 175.133 -77.978 180)
		(property "Reference" "C345"
			(at 0 0 0)
			(layer "B.SilkS")
			(hide yes)
			(effects
				(font
					(size 1.27 1.27)
				)
				(justify mirror)
			)
		)
		(property "Value" "SCD1U6D3V1KX-GP"
			(at 2.8321 -1.7399 180)
			(unlocked yes)
			(layer "B.Fab")
			(hide yes)
			(effects
				(font
					(size 1.016 1.016)
					(thickness 0.1524)
				)
				(justify mirror)
			)
		)
		(property "Device Type" "C0201H13"
			(at 2.8321 -3.2639 180)
			(unlocked yes)
			(layer "B.Fab")
			(hide yes)
			(effects
				(font
					(size 1.016 1.016)
					(thickness 0.1524)
				)
				(justify mirror)
			)
		)
		(duplicate_pad_numbers_are_jumpers no)
		(fp_rect
			(start 0.2794 0.6477)
			(end -0.2794 -0.6477)
			(stroke
				(width 0)
				(type default)
			)
			(fill no)
			(layer "B.CrtYd")
		)
		(fp_rect
			(start 0.2794 0.6477)
			(end -0.2794 -0.6477)
			(stroke
				(width 0)
				(type default)
			)
			(fill no)
			(layer "B.Fab")
		)
		(pad "1" smd custom
			(at 0 -0.2794)
			(size 0.0762 0.0762)
			(layers "B.Cu" "B.Mask" "B.Paste")
			(net "PLL_VDD")
			(options
				(clearance outline)
				(anchor circle)
			)
			(primitives
				(gr_poly
					(pts
						(arc
							(start 0.1524 0.127)
							(mid 0.137521 0.162921)
							(end 0.1016 0.1778)
						)
						(arc
							(start -0.1016 0.1778)
							(mid -0.137521 0.162921)
							(end -0.1524 0.127)
						)
						(arc
							(start -0.1524 -0.127)
							(mid -0.137521 -0.162921)
							(end -0.1016 -0.1778)
						)
						(arc
							(start 0.1016 -0.1778)
							(mid 0.137521 -0.162921)
							(end 0.1524 -0.127)
						)
					)
					(width 0)
					(fill yes)
				)
			)
		)
		(pad "2" smd custom
			(at 0 0.2794)
			(size 0.0762 0.0762)
			(layers "B.Cu" "B.Mask" "B.Paste")
			(net "GND")
			(options
				(clearance outline)
				(anchor circle)
			)
			(primitives
				(gr_poly
					(pts
						(arc
							(start 0.1524 0.127)
							(mid 0.137521 0.162921)
							(end 0.1016 0.1778)
						)
						(arc
							(start -0.1016 0.1778)
							(mid -0.137521 0.162921)
							(end -0.1524 0.127)
						)
						(arc
							(start -0.1524 -0.127)
							(mid -0.137521 -0.162921)
							(end -0.1016 -0.1778)
						)
						(arc
							(start 0.1016 -0.1778)
							(mid 0.137521 -0.162921)
							(end 0.1524 -0.127)
						)
					)
					(width 0)
					(fill yes)
				)
			)
		)
	)
	(footprint ""
		(layer "B.Cu")
		(at 93.3704 -178.7398 180)
		(property "Reference" "C39"
			(at 0 0 0)
			(layer "B.SilkS")
			(hide yes)
			(effects
				(font
					(size 1.27 1.27)
				)
				(justify mirror)
			)
		)
		(property "Value" "SCD1U16V2KX-3GP"
			(at -1.1811 -2.7051 180)
			(unlocked yes)
			(layer "B.Fab")
			(hide yes)
			(effects
				(font
					(size 1.016 1.016)
					(thickness 0.1524)
				)
				(justify mirror)
			)
		)
		(property "Device Type" "C402H22"
			(at -1.1811 -4.2291 180)
			(unlocked yes)
			(layer "B.Fab")
			(hide yes)
			(effects
				(font
					(size 1.016 1.016)
					(thickness 0.1524)
				)
				(justify mirror)
			)
		)
		(duplicate_pad_numbers_are_jumpers no)
		(fp_rect
			(start 0.4318 0.9525)
			(end -0.4318 -0.9525)
			(stroke
				(width 0)
				(type default)
			)
			(fill no)
			(layer "B.CrtYd")
		)
		(fp_rect
			(start 0.4318 0.9525)
			(end -0.4318 -0.9525)
			(stroke
				(width 0)
				(type default)
			)
			(fill no)
			(layer "B.Fab")
		)
		(pad "1" smd custom
			(at 0 -0.4445)
			(size 0.1524 0.1524)
			(layers "B.Cu" "B.Mask" "B.Paste")
			(net "P3V3_STBY")
			(options
				(clearance outline)
				(anchor circle)
			)
			(primitives
				(gr_poly
					(pts
						(arc
							(start 0.3048 0.2032)
							(mid 0.275042 0.275042)
							(end 0.2032 0.3048)
						)
						(arc
							(start -0.2032 0.3048)
							(mid -0.275042 0.275042)
							(end -0.3048 0.2032)
						)
						(arc
							(start -0.3048 -0.2032)
							(mid -0.275042 -0.275042)
							(end -0.2032 -0.3048)
						)
						(arc
							(start 0.2032 -0.3048)
							(mid 0.275042 -0.275042)
							(end 0.3048 -0.2032)
						)
					)
					(width 0)
					(fill yes)
				)
			)
		)
		(pad "2" smd custom
			(at 0 0.4445)
			(size 0.1524 0.1524)
			(layers "B.Cu" "B.Mask" "B.Paste")
			(net "GND")
			(options
				(clearance outline)
				(anchor circle)
			)
			(primitives
				(gr_poly
					(pts
						(arc
							(start 0.3048 0.2032)
							(mid 0.275042 0.275042)
							(end 0.2032 0.3048)
						)
						(arc
							(start -0.2032 0.3048)
							(mid -0.275042 0.275042)
							(end -0.3048 0.2032)
						)
						(arc
							(start -0.3048 -0.2032)
							(mid -0.275042 -0.275042)
							(end -0.2032 -0.3048)
						)
						(arc
							(start 0.2032 -0.3048)
							(mid 0.275042 -0.275042)
							(end 0.3048 -0.2032)
						)
					)
					(width 0)
					(fill yes)
				)
			)
		)
	)
	(footprint ""
		(layer "B.Cu")
		(at 204.815948 -47.773082 -90)
		(property "Reference" "L15"
			(at 0 0 90)
			(layer "B.SilkS")
			(hide yes)
			(effects
				(font
					(size 1.27 1.27)
				)
				(justify mirror)
			)
		)
		(property "Value" "MPZ2012S601AT-GP"
			(at 0 -4.2418 270)
			(unlocked yes)
			(layer "B.Fab")
			(hide yes)
			(effects
				(font
					(size 1.016 1.016)
					(thickness 0.1524)
				)
				(justify mirror)
			)
		)
		(property "Device Type" "L805H42"
			(at 0 -5.7912 270)
			(unlocked yes)
			(layer "B.Fab")
			(hide yes)
			(effects
				(font
					(size 1.016 1.016)
					(thickness 0.1524)
				)
				(justify mirror)
			)
		)
		(duplicate_pad_numbers_are_jumpers no)
		(fp_line
			(start -0.889 1.7018)
			(end 0.889 1.7018)
			(stroke
				(width 0.1524)
				(type default)
			)
			(layer "B.SilkS")
		)
		(fp_line
			(start 0.889 1.7018)
			(end 0.889 -1.7018)
			(stroke
				(width 0.1524)
				(type default)
			)
			(layer "B.SilkS")
		)
		(fp_line
			(start -0.889 -1.7018)
			(end -0.889 1.7018)
			(stroke
				(width 0.1524)
				(type default)
			)
			(layer "B.SilkS")
		)
		(fp_line
			(start 0.889 -1.7018)
			(end -0.889 -1.7018)
			(stroke
				(width 0.1524)
				(type default)
			)
			(layer "B.SilkS")
		)
		(fp_rect
			(start 0.9652 1.778)
			(end -0.9652 -1.778)
			(stroke
				(width 0)
				(type default)
			)
			(fill no)
			(layer "B.CrtYd")
		)
		(fp_rect
			(start 0.9652 1.778)
			(end -0.9652 -1.778)
			(stroke
				(width 0)
				(type default)
			)
			(fill no)
			(layer "B.Fab")
		)
		(pad "1" smd rect
			(at 0 -0.9652 90)
			(size 1.397 1.143)
			(layers "B.Cu" "B.Mask" "B.Paste")
			(net "SHELL_PLL_VDD")
		)
		(pad "2" smd rect
			(at 0 0.9652 90)
			(size 1.397 1.143)
			(layers "B.Cu" "B.Mask" "B.Paste")
			(net "P1V8")
		)
	)
	(footprint ""
		(layer "B.Cu")
		(at 52.5526 -146.5834 -90)
		(property "Reference" "TP51"
			(at 0 0 90)
			(layer "B.SilkS")
			(hide yes)
			(effects
				(font
					(size 1.27 1.27)
				)
				(justify mirror)
			)
		)
		(property "Value" "TPAD28-2-GP"
			(at 0.0127 -1.6637 270)
			(unlocked yes)
			(layer "B.Fab")
			(hide yes)
			(effects
				(font
					(size 1.016 1.016)
					(thickness 0.1524)
				)
				(justify mirror)
			)
		)
		(property "Device Type" "TPAD28"
			(at 0.0127 -3.1877 270)
			(unlocked yes)
			(layer "B.Fab")
			(hide yes)
			(effects
				(font
					(size 1.016 1.016)
					(thickness 0.1524)
				)
				(justify mirror)
			)
		)
		(duplicate_pad_numbers_are_jumpers no)
		(fp_poly
			(pts
				(arc
					(start 0 -0.3556)
					(mid 0 0.3556)
					(end 0 -0.3556)
				)
			)
			(stroke
				(width 0)
				(type default)
			)
			(fill no)
			(layer "B.CrtYd")
		)
		(fp_poly
			(pts
				(arc
					(start 0 -0.6096)
					(mid 0 0.6096)
					(end 0 -0.6096)
				)
			)
			(stroke
				(width 0)
				(type default)
			)
			(fill no)
			(layer "B.Fab")
		)
		(pad "1" smd circle
			(at 0 0 90)
			(size 0.7112 0.7112)
			(layers "B.Cu" "B.Mask" "B.Paste")
			(net "RMII_BMC_MDC_R")
		)
	)
	(footprint ""
		(layer "B.Cu")
		(at 195.5927 -63.78956 90)
		(property "Reference" "C422"
			(at 0 0 90)
			(layer "B.SilkS")
			(hide yes)
			(effects
				(font
					(size 1.27 1.27)
				)
				(justify mirror)
			)
		)
		(property "Value" "SCD1U6D3V1KX-GP"
			(at 2.8321 -1.7399 90)
			(unlocked yes)
			(layer "B.Fab")
			(hide yes)
			(effects
				(font
					(size 1.016 1.016)
					(thickness 0.1524)
				)
				(justify mirror)
			)
		)
		(property "Device Type" "C0201H13"
			(at 2.8321 -3.2639 90)
			(unlocked yes)
			(layer "B.Fab")
			(hide yes)
			(effects
				(font
					(size 1.016 1.016)
					(thickness 0.1524)
				)
				(justify mirror)
			)
		)
		(duplicate_pad_numbers_are_jumpers no)
		(fp_rect
			(start 0.2794 0.6477)
			(end -0.2794 -0.6477)
			(stroke
				(width 0)
				(type default)
			)
			(fill no)
			(layer "B.CrtYd")
		)
		(fp_rect
			(start 0.2794 0.6477)
			(end -0.2794 -0.6477)
			(stroke
				(width 0)
				(type default)
			)
			(fill no)
			(layer "B.Fab")
		)
		(pad "1" smd custom
			(at 0 -0.2794 270)
			(size 0.0762 0.0762)
			(layers "B.Cu" "B.Mask" "B.Paste")
			(net "P0V975")
			(options
				(clearance outline)
				(anchor circle)
			)
			(primitives
				(gr_poly
					(pts
						(arc
							(start 0.1524 0.127)
							(mid 0.137521 0.162921)
							(end 0.1016 0.1778)
						)
						(arc
							(start -0.1016 0.1778)
							(mid -0.137521 0.162921)
							(end -0.1524 0.127)
						)
						(arc
							(start -0.1524 -0.127)
							(mid -0.137521 -0.162921)
							(end -0.1016 -0.1778)
						)
						(arc
							(start 0.1016 -0.1778)
							(mid 0.137521 -0.162921)
							(end 0.1524 -0.127)
						)
					)
					(width 0)
					(fill yes)
				)
			)
		)
		(pad "2" smd custom
			(at 0 0.2794 270)
			(size 0.0762 0.0762)
			(layers "B.Cu" "B.Mask" "B.Paste")
			(net "GND")
			(options
				(clearance outline)
				(anchor circle)
			)
			(primitives
				(gr_poly
					(pts
						(arc
							(start 0.1524 0.127)
							(mid 0.137521 0.162921)
							(end 0.1016 0.1778)
						)
						(arc
							(start -0.1016 0.1778)
							(mid -0.137521 0.162921)
							(end -0.1524 0.127)
						)
						(arc
							(start -0.1524 -0.127)
							(mid -0.137521 -0.162921)
							(end -0.1016 -0.1778)
						)
						(arc
							(start 0.1016 -0.1778)
							(mid 0.137521 -0.162921)
							(end 0.1524 -0.127)
						)
					)
					(width 0)
					(fill yes)
				)
			)
		)
	)
	(footprint ""
		(layer "B.Cu")
		(at 200.94956 -62.92596)
		(property "Reference" "TP134"
			(at 0 0 0)
			(layer "B.SilkS")
			(hide yes)
			(effects
				(font
					(size 1.27 1.27)
				)
				(justify mirror)
			)
		)
		(property "Value" "TPAD28-2-GP"
			(at 0.0127 -1.6637 0)
			(unlocked yes)
			(layer "B.Fab")
			(hide yes)
			(effects
				(font
					(size 1.016 1.016)
					(thickness 0.1524)
				)
				(justify mirror)
			)
		)
		(property "Device Type" "TPAD28"
			(at 0.0127 -3.1877 0)
			(unlocked yes)
			(layer "B.Fab")
			(hide yes)
			(effects
				(font
					(size 1.016 1.016)
					(thickness 0.1524)
				)
				(justify mirror)
			)
		)
		(duplicate_pad_numbers_are_jumpers no)
		(fp_poly
			(pts
				(arc
					(start 0.3556 0)
					(mid -0.3556 0)
					(end 0.3556 0)
				)
			)
			(stroke
				(width 0)
				(type default)
			)
			(fill no)
			(layer "B.CrtYd")
		)
		(fp_poly
			(pts
				(arc
					(start 0.6096 0)
					(mid -0.6096 0)
					(end 0.6096 0)
				)
			)
			(stroke
				(width 0)
				(type default)
			)
			(fill no)
			(layer "B.Fab")
		)
		(pad "1" smd circle
			(at 0 0 180)
			(size 0.7112 0.7112)
			(layers "B.Cu" "B.Mask" "B.Paste")
			(net "ICE_SEL")
		)
	)
	(footprint ""
		(layer "B.Cu")
		(at 192.405 -48.641 -90)
		(property "Reference" "C332"
			(at 0 0 90)
			(layer "B.SilkS")
			(hide yes)
			(effects
				(font
					(size 1.27 1.27)
				)
				(justify mirror)
			)
		)
		(property "Value" "SC10U6D3V5KX-4GP"
			(at 0.0762 -6.1214 270)
			(unlocked yes)
			(layer "B.Fab")
			(hide yes)
			(effects
				(font
					(size 1.016 1.016)
					(thickness 0.1524)
				)
				(justify mirror)
			)
		)
		(property "Device Type" "C805H58"
			(at 0.0762 -8.1534 270)
			(unlocked yes)
			(layer "B.Fab")
			(hide yes)
			(effects
				(font
					(size 1.016 1.016)
					(thickness 0.1524)
				)
				(justify mirror)
			)
		)
		(duplicate_pad_numbers_are_jumpers no)
		(fp_line
			(start -0.635 0)
			(end 0.635 0)
			(stroke
				(width 0.508)
				(type default)
			)
			(layer "B.SilkS")
		)
		(fp_rect
			(start 0.9652 1.778)
			(end -0.9652 -1.778)
			(stroke
				(width 0)
				(type default)
			)
			(fill no)
			(layer "B.CrtYd")
		)
		(fp_poly
			(pts
				(xy 0.9652 -1.778) (xy -0.9652 -1.778) (xy -0.9652 1.778) (xy 0.9652 1.778)
			)
			(stroke
				(width 0)
				(type default)
			)
			(fill no)
			(layer "B.Fab")
		)
		(pad "1" smd rect
			(at 0 -0.9652 90)
			(size 1.397 1.143)
			(layers "B.Cu" "B.Mask" "B.Paste")
			(net "HM40ADC_VDDA")
		)
		(pad "2" smd rect
			(at 0 0.9652 90)
			(size 1.397 1.143)
			(layers "B.Cu" "B.Mask" "B.Paste")
			(net "GND")
		)
	)
	(footprint ""
		(layer "B.Cu")
		(at 116.3828 -15.7226 90)
		(property "Reference" "R744"
			(at 0 0 90)
			(layer "B.SilkS")
			(hide yes)
			(effects
				(font
					(size 1.27 1.27)
				)
				(justify mirror)
			)
		)
		(property "Value" "11KR2F-L-GP"
			(at -0.064008 -3.993896 90)
			(unlocked yes)
			(layer "B.Fab")
			(hide yes)
			(effects
				(font
					(size 1.016 1.016)
					(thickness 0.1524)
				)
				(justify mirror)
			)
		)
		(property "Device Type" "R402H16"
			(at -0.064008 -5.517896 90)
			(unlocked yes)
			(layer "B.Fab")
			(hide yes)
			(effects
				(font
					(size 1.016 1.016)
					(thickness 0.1524)
				)
				(justify mirror)
			)
		)
		(duplicate_pad_numbers_are_jumpers no)
		(fp_line
			(start 0.508 -0.9398)
			(end 0.508 0.9398)
			(stroke
				(width 0.1524)
				(type default)
			)
			(layer "B.SilkS")
		)
		(fp_line
			(start -0.508 -0.9398)
			(end 0.508 -0.9398)
			(stroke
				(width 0.1524)
				(type default)
			)
			(layer "B.SilkS")
		)
		(fp_rect
			(start 0.508 0.9398)
			(end -0.508 -0.9398)
			(stroke
				(width 0)
				(type default)
			)
			(fill no)
			(layer "B.CrtYd")
		)
		(fp_rect
			(start 0.508 0.9398)
			(end -0.508 -0.9398)
			(stroke
				(width 0)
				(type default)
			)
			(fill no)
			(layer "B.Fab")
		)
		(pad "1" smd custom
			(at 0 -0.4445 270)
			(size 0.1397 0.1397)
			(layers "B.Cu" "B.Mask" "B.Paste")
			(net "IOM_ADM1278_EN")
			(options
				(clearance outline)
				(anchor circle)
			)
			(primitives
				(gr_poly
					(pts
						(arc
							(start -0.1778 0.2794)
							(mid -0.249642 0.249642)
							(end -0.2794 0.1778)
						)
						(arc
							(start -0.2794 -0.1778)
							(mid -0.249642 -0.249642)
							(end -0.1778 -0.2794)
						)
						(arc
							(start 0.1778 -0.2794)
							(mid 0.249642 -0.249642)
							(end 0.2794 -0.1778)
						)
						(arc
							(start 0.2794 0.1778)
							(mid 0.249642 0.249642)
							(end 0.1778 0.2794)
						)
					)
					(width 0)
					(fill yes)
				)
			)
		)
		(pad "2" smd custom
			(at 0 0.4445 270)
			(size 0.1397 0.1397)
			(layers "B.Cu" "B.Mask" "B.Paste")
			(net "GND")
			(options
				(clearance outline)
				(anchor circle)
			)
			(primitives
				(gr_poly
					(pts
						(arc
							(start -0.1778 0.2794)
							(mid -0.249642 0.249642)
							(end -0.2794 0.1778)
						)
						(arc
							(start -0.2794 -0.1778)
							(mid -0.249642 -0.249642)
							(end -0.1778 -0.2794)
						)
						(arc
							(start 0.1778 -0.2794)
							(mid 0.249642 -0.249642)
							(end 0.2794 -0.1778)
						)
						(arc
							(start 0.2794 0.1778)
							(mid 0.249642 0.249642)
							(end 0.1778 0.2794)
						)
					)
					(width 0)
					(fill yes)
				)
			)
		)
	)
	(footprint ""
		(layer "B.Cu")
		(at 189.983872 -74.793856 90)
		(property "Reference" "C450"
			(at 0 0 90)
			(layer "B.SilkS")
			(hide yes)
			(effects
				(font
					(size 1.27 1.27)
				)
				(justify mirror)
			)
		)
		(property "Value" "SCD1U16V2KX-3GP"
			(at -1.1811 -2.7051 90)
			(unlocked yes)
			(layer "B.Fab")
			(hide yes)
			(effects
				(font
					(size 1.016 1.016)
					(thickness 0.1524)
				)
				(justify mirror)
			)
		)
		(property "Device Type" "C402H22"
			(at -1.1811 -4.2291 90)
			(unlocked yes)
			(layer "B.Fab")
			(hide yes)
			(effects
				(font
					(size 1.016 1.016)
					(thickness 0.1524)
				)
				(justify mirror)
			)
		)
		(duplicate_pad_numbers_are_jumpers no)
		(fp_rect
			(start 0.4318 0.9525)
			(end -0.4318 -0.9525)
			(stroke
				(width 0)
				(type default)
			)
			(fill no)
			(layer "B.CrtYd")
		)
		(fp_rect
			(start 0.4318 0.9525)
			(end -0.4318 -0.9525)
			(stroke
				(width 0)
				(type default)
			)
			(fill no)
			(layer "B.Fab")
		)
		(pad "1" smd custom
			(at 0 -0.4445 270)
			(size 0.1524 0.1524)
			(layers "B.Cu" "B.Mask" "B.Paste")
			(net "P1V8")
			(options
				(clearance outline)
				(anchor circle)
			)
			(primitives
				(gr_poly
					(pts
						(arc
							(start 0.3048 0.2032)
							(mid 0.275042 0.275042)
							(end 0.2032 0.3048)
						)
						(arc
							(start -0.2032 0.3048)
							(mid -0.275042 0.275042)
							(end -0.3048 0.2032)
						)
						(arc
							(start -0.3048 -0.2032)
							(mid -0.275042 -0.275042)
							(end -0.2032 -0.3048)
						)
						(arc
							(start 0.2032 -0.3048)
							(mid 0.275042 -0.275042)
							(end 0.3048 -0.2032)
						)
					)
					(width 0)
					(fill yes)
				)
			)
		)
		(pad "2" smd custom
			(at 0 0.4445 270)
			(size 0.1524 0.1524)
			(layers "B.Cu" "B.Mask" "B.Paste")
			(net "GND")
			(options
				(clearance outline)
				(anchor circle)
			)
			(primitives
				(gr_poly
					(pts
						(arc
							(start 0.3048 0.2032)
							(mid 0.275042 0.275042)
							(end 0.2032 0.3048)
						)
						(arc
							(start -0.2032 0.3048)
							(mid -0.275042 0.275042)
							(end -0.3048 0.2032)
						)
						(arc
							(start -0.3048 -0.2032)
							(mid -0.275042 -0.275042)
							(end -0.2032 -0.3048)
						)
						(arc
							(start 0.2032 -0.3048)
							(mid 0.275042 -0.275042)
							(end 0.3048 -0.2032)
						)
					)
					(width 0)
					(fill yes)
				)
			)
		)
	)
	(footprint ""
		(layer "B.Cu")
		(at 59.055 -133.985 180)
		(property "Reference" "R784"
			(at 0 0 0)
			(layer "B.SilkS")
			(hide yes)
			(effects
				(font
					(size 1.27 1.27)
				)
				(justify mirror)
			)
		)
		(property "Value" "10KR2F-2-GP"
			(at -0.064008 -3.993896 180)
			(unlocked yes)
			(layer "B.Fab")
			(hide yes)
			(effects
				(font
					(size 1.016 1.016)
					(thickness 0.1524)
				)
				(justify mirror)
			)
		)
		(property "Device Type" "R402H16"
			(at -0.064008 -5.517896 180)
			(unlocked yes)
			(layer "B.Fab")
			(hide yes)
			(effects
				(font
					(size 1.016 1.016)
					(thickness 0.1524)
				)
				(justify mirror)
			)
		)
		(duplicate_pad_numbers_are_jumpers no)
		(fp_line
			(start 0.508 -0.9398)
			(end 0.508 0.9398)
			(stroke
				(width 0.1524)
				(type default)
			)
			(layer "B.SilkS")
		)
		(fp_line
			(start -0.508 -0.9398)
			(end 0.508 -0.9398)
			(stroke
				(width 0.1524)
				(type default)
			)
			(layer "B.SilkS")
		)
		(fp_rect
			(start 0.508 0.9398)
			(end -0.508 -0.9398)
			(stroke
				(width 0)
				(type default)
			)
			(fill no)
			(layer "B.CrtYd")
		)
		(fp_rect
			(start 0.508 0.9398)
			(end -0.508 -0.9398)
			(stroke
				(width 0)
				(type default)
			)
			(fill no)
			(layer "B.Fab")
		)
		(pad "1" smd custom
			(at 0 -0.4445)
			(size 0.1397 0.1397)
			(layers "B.Cu" "B.Mask" "B.Paste")
			(net "P3V3_STBY")
			(options
				(clearance outline)
				(anchor circle)
			)
			(primitives
				(gr_poly
					(pts
						(arc
							(start -0.1778 0.2794)
							(mid -0.249642 0.249642)
							(end -0.2794 0.1778)
						)
						(arc
							(start -0.2794 -0.1778)
							(mid -0.249642 -0.249642)
							(end -0.1778 -0.2794)
						)
						(arc
							(start 0.1778 -0.2794)
							(mid 0.249642 -0.249642)
							(end 0.2794 -0.1778)
						)
						(arc
							(start 0.2794 0.1778)
							(mid 0.249642 0.249642)
							(end 0.1778 0.2794)
						)
					)
					(width 0)
					(fill yes)
				)
			)
		)
		(pad "2" smd custom
			(at 0 0.4445)
			(size 0.1397 0.1397)
			(layers "B.Cu" "B.Mask" "B.Paste")
			(net "COMP_PWR_BTN_N")
			(options
				(clearance outline)
				(anchor circle)
			)
			(primitives
				(gr_poly
					(pts
						(arc
							(start -0.1778 0.2794)
							(mid -0.249642 0.249642)
							(end -0.2794 0.1778)
						)
						(arc
							(start -0.2794 -0.1778)
							(mid -0.249642 -0.249642)
							(end -0.1778 -0.2794)
						)
						(arc
							(start 0.1778 -0.2794)
							(mid 0.249642 -0.249642)
							(end 0.2794 -0.1778)
						)
						(arc
							(start 0.2794 0.1778)
							(mid 0.249642 0.249642)
							(end 0.1778 0.2794)
						)
					)
					(width 0)
					(fill yes)
				)
			)
		)
	)
	(footprint ""
		(layer "B.Cu")
		(at 58.0136 -143.7767 180)
		(property "Reference" "R358"
			(at 0 0 0)
			(layer "B.SilkS")
			(hide yes)
			(effects
				(font
					(size 1.27 1.27)
				)
				(justify mirror)
			)
		)
		(property "Value" "10KR2F-2-GP"
			(at -0.064008 -3.993896 180)
			(unlocked yes)
			(layer "B.Fab")
			(hide yes)
			(effects
				(font
					(size 1.016 1.016)
					(thickness 0.1524)
				)
				(justify mirror)
			)
		)
		(property "Device Type" "R402H16"
			(at -0.064008 -5.517896 180)
			(unlocked yes)
			(layer "B.Fab")
			(hide yes)
			(effects
				(font
					(size 1.016 1.016)
					(thickness 0.1524)
				)
				(justify mirror)
			)
		)
		(duplicate_pad_numbers_are_jumpers no)
		(fp_line
			(start 0.508 -0.9398)
			(end 0.508 0.9398)
			(stroke
				(width 0.1524)
				(type default)
			)
			(layer "B.SilkS")
		)
		(fp_line
			(start -0.508 -0.9398)
			(end 0.508 -0.9398)
			(stroke
				(width 0.1524)
				(type default)
			)
			(layer "B.SilkS")
		)
		(fp_rect
			(start 0.508 0.9398)
			(end -0.508 -0.9398)
			(stroke
				(width 0)
				(type default)
			)
			(fill no)
			(layer "B.CrtYd")
		)
		(fp_rect
			(start 0.508 0.9398)
			(end -0.508 -0.9398)
			(stroke
				(width 0)
				(type default)
			)
			(fill no)
			(layer "B.Fab")
		)
		(pad "1" smd custom
			(at 0 -0.4445)
			(size 0.1397 0.1397)
			(layers "B.Cu" "B.Mask" "B.Paste")
			(net "P3V3_STBY")
			(options
				(clearance outline)
				(anchor circle)
			)
			(primitives
				(gr_poly
					(pts
						(arc
							(start -0.1778 0.2794)
							(mid -0.249642 0.249642)
							(end -0.2794 0.1778)
						)
						(arc
							(start -0.2794 -0.1778)
							(mid -0.249642 -0.249642)
							(end -0.1778 -0.2794)
						)
						(arc
							(start 0.1778 -0.2794)
							(mid 0.249642 -0.249642)
							(end 0.2794 -0.1778)
						)
						(arc
							(start 0.2794 0.1778)
							(mid 0.249642 0.249642)
							(end 0.1778 0.2794)
						)
					)
					(width 0)
					(fill yes)
				)
			)
		)
		(pad "2" smd custom
			(at 0 0.4445)
			(size 0.1397 0.1397)
			(layers "B.Cu" "B.Mask" "B.Paste")
			(net "JTAG_BMC_TDI")
			(options
				(clearance outline)
				(anchor circle)
			)
			(primitives
				(gr_poly
					(pts
						(arc
							(start -0.1778 0.2794)
							(mid -0.249642 0.249642)
							(end -0.2794 0.1778)
						)
						(arc
							(start -0.2794 -0.1778)
							(mid -0.249642 -0.249642)
							(end -0.1778 -0.2794)
						)
						(arc
							(start 0.1778 -0.2794)
							(mid 0.249642 -0.249642)
							(end 0.2794 -0.1778)
						)
						(arc
							(start 0.2794 0.1778)
							(mid 0.249642 0.249642)
							(end 0.1778 0.2794)
						)
					)
					(width 0)
					(fill yes)
				)
			)
		)
	)
	(footprint ""
		(layer "B.Cu")
		(at 181.04612 -81.44256)
		(property "Reference" "L20"
			(at 0 0 0)
			(layer "B.SilkS")
			(hide yes)
			(effects
				(font
					(size 1.27 1.27)
				)
				(justify mirror)
			)
		)
		(property "Value" "MPZ2012S300AT-GP"
			(at 0 -4.2418 0)
			(unlocked yes)
			(layer "B.Fab")
			(hide yes)
			(effects
				(font
					(size 1.016 1.016)
					(thickness 0.1524)
				)
				(justify mirror)
			)
		)
		(property "Device Type" "L805H42"
			(at 0 -5.7912 0)
			(unlocked yes)
			(layer "B.Fab")
			(hide yes)
			(effects
				(font
					(size 1.016 1.016)
					(thickness 0.1524)
				)
				(justify mirror)
			)
		)
		(duplicate_pad_numbers_are_jumpers no)
		(fp_line
			(start -0.889 -1.7018)
			(end -0.889 1.7018)
			(stroke
				(width 0.1524)
				(type default)
			)
			(layer "B.SilkS")
		)
		(fp_line
			(start -0.889 1.7018)
			(end 0.889 1.7018)
			(stroke
				(width 0.1524)
				(type default)
			)
			(layer "B.SilkS")
		)
		(fp_line
			(start 0.889 -1.7018)
			(end -0.889 -1.7018)
			(stroke
				(width 0.1524)
				(type default)
			)
			(layer "B.SilkS")
		)
		(fp_line
			(start 0.889 1.7018)
			(end 0.889 -1.7018)
			(stroke
				(width 0.1524)
				(type default)
			)
			(layer "B.SilkS")
		)
		(fp_rect
			(start 0.9652 1.778)
			(end -0.9652 -1.778)
			(stroke
				(width 0)
				(type default)
			)
			(fill no)
			(layer "B.CrtYd")
		)
		(fp_rect
			(start 0.9652 1.778)
			(end -0.9652 -1.778)
			(stroke
				(width 0)
				(type default)
			)
			(fill no)
			(layer "B.Fab")
		)
		(pad "1" smd rect
			(at 0 -0.9652 180)
			(size 1.397 1.143)
			(layers "B.Cu" "B.Mask" "B.Paste")
			(net "P0V975")
		)
		(pad "2" smd rect
			(at 0 0.9652 180)
			(size 1.397 1.143)
			(layers "B.Cu" "B.Mask" "B.Paste")
			(net "PCE_AVDD")
		)
	)
	(footprint ""
		(layer "B.Cu")
		(at 43.485308 -159.975804 90)
		(property "Reference" "R697"
			(at 0 0 90)
			(layer "B.SilkS")
			(hide yes)
			(effects
				(font
					(size 1.27 1.27)
				)
				(justify mirror)
			)
		)
		(property "Value" "4K7R2F-GP"
			(at -0.064008 -3.993896 90)
			(unlocked yes)
			(layer "B.Fab")
			(hide yes)
			(effects
				(font
					(size 1.016 1.016)
					(thickness 0.1524)
				)
				(justify mirror)
			)
		)
		(property "Device Type" "R402H16"
			(at -0.064008 -5.517896 90)
			(unlocked yes)
			(layer "B.Fab")
			(hide yes)
			(effects
				(font
					(size 1.016 1.016)
					(thickness 0.1524)
				)
				(justify mirror)
			)
		)
		(duplicate_pad_numbers_are_jumpers no)
		(fp_line
			(start 0.508 -0.9398)
			(end 0.508 0.9398)
			(stroke
				(width 0.1524)
				(type default)
			)
			(layer "B.SilkS")
		)
		(fp_line
			(start -0.508 -0.9398)
			(end 0.508 -0.9398)
			(stroke
				(width 0.1524)
				(type default)
			)
			(layer "B.SilkS")
		)
		(fp_rect
			(start 0.508 0.9398)
			(end -0.508 -0.9398)
			(stroke
				(width 0)
				(type default)
			)
			(fill no)
			(layer "B.CrtYd")
		)
		(fp_rect
			(start 0.508 0.9398)
			(end -0.508 -0.9398)
			(stroke
				(width 0)
				(type default)
			)
			(fill no)
			(layer "B.Fab")
		)
		(pad "1" smd custom
			(at 0 -0.4445 270)
			(size 0.1397 0.1397)
			(layers "B.Cu" "B.Mask" "B.Paste")
			(net "P3V3_STBY")
			(options
				(clearance outline)
				(anchor circle)
			)
			(primitives
				(gr_poly
					(pts
						(arc
							(start -0.1778 0.2794)
							(mid -0.249642 0.249642)
							(end -0.2794 0.1778)
						)
						(arc
							(start -0.2794 -0.1778)
							(mid -0.249642 -0.249642)
							(end -0.1778 -0.2794)
						)
						(arc
							(start 0.1778 -0.2794)
							(mid 0.249642 -0.249642)
							(end 0.2794 -0.1778)
						)
						(arc
							(start 0.2794 0.1778)
							(mid 0.249642 0.249642)
							(end 0.1778 0.2794)
						)
					)
					(width 0)
					(fill yes)
				)
			)
		)
		(pad "2" smd custom
			(at 0 0.4445 270)
			(size 0.1397 0.1397)
			(layers "B.Cu" "B.Mask" "B.Paste")
			(net "PCIE_WAKE_N")
			(options
				(clearance outline)
				(anchor circle)
			)
			(primitives
				(gr_poly
					(pts
						(arc
							(start -0.1778 0.2794)
							(mid -0.249642 0.249642)
							(end -0.2794 0.1778)
						)
						(arc
							(start -0.2794 -0.1778)
							(mid -0.249642 -0.249642)
							(end -0.1778 -0.2794)
						)
						(arc
							(start 0.1778 -0.2794)
							(mid 0.249642 -0.249642)
							(end 0.2794 -0.1778)
						)
						(arc
							(start 0.2794 0.1778)
							(mid 0.249642 0.249642)
							(end 0.1778 0.2794)
						)
					)
					(width 0)
					(fill yes)
				)
			)
		)
	)
	(footprint ""
		(layer "B.Cu")
		(at 38.227 -126.51232)
		(property "Reference" "R348"
			(at 0 0 0)
			(layer "B.SilkS")
			(hide yes)
			(effects
				(font
					(size 1.27 1.27)
				)
				(justify mirror)
			)
		)
		(property "Value" "0R2J-2-GP"
			(at -0.064008 -3.993896 0)
			(unlocked yes)
			(layer "B.Fab")
			(hide yes)
			(effects
				(font
					(size 1.016 1.016)
					(thickness 0.1524)
				)
				(justify mirror)
			)
		)
		(property "Device Type" "R402H16"
			(at -0.064008 -5.517896 0)
			(unlocked yes)
			(layer "B.Fab")
			(hide yes)
			(effects
				(font
					(size 1.016 1.016)
					(thickness 0.1524)
				)
				(justify mirror)
			)
		)
		(duplicate_pad_numbers_are_jumpers no)
		(fp_line
			(start -0.508 -0.9398)
			(end 0.508 -0.9398)
			(stroke
				(width 0.1524)
				(type default)
			)
			(layer "B.SilkS")
		)
		(fp_line
			(start 0.508 -0.9398)
			(end 0.508 0.9398)
			(stroke
				(width 0.1524)
				(type default)
			)
			(layer "B.SilkS")
		)
		(fp_rect
			(start 0.508 0.9398)
			(end -0.508 -0.9398)
			(stroke
				(width 0)
				(type default)
			)
			(fill no)
			(layer "B.CrtYd")
		)
		(fp_rect
			(start 0.508 0.9398)
			(end -0.508 -0.9398)
			(stroke
				(width 0)
				(type default)
			)
			(fill no)
			(layer "B.Fab")
		)
		(pad "1" smd custom
			(at 0 -0.4445 180)
			(size 0.1397 0.1397)
			(layers "B.Cu" "B.Mask" "B.Paste")
			(net "BMC_EXTRST_N")
			(options
				(clearance outline)
				(anchor circle)
			)
			(primitives
				(gr_poly
					(pts
						(arc
							(start -0.1778 0.2794)
							(mid -0.249642 0.249642)
							(end -0.2794 0.1778)
						)
						(arc
							(start -0.2794 -0.1778)
							(mid -0.249642 -0.249642)
							(end -0.1778 -0.2794)
						)
						(arc
							(start 0.1778 -0.2794)
							(mid 0.249642 -0.249642)
							(end 0.2794 -0.1778)
						)
						(arc
							(start 0.2794 0.1778)
							(mid 0.249642 0.249642)
							(end 0.1778 0.2794)
						)
					)
					(width 0)
					(fill yes)
				)
			)
		)
		(pad "2" smd custom
			(at 0 0.4445 180)
			(size 0.1397 0.1397)
			(layers "B.Cu" "B.Mask" "B.Paste")
			(net "RST_BMC_EXTRST_N_1")
			(options
				(clearance outline)
				(anchor circle)
			)
			(primitives
				(gr_poly
					(pts
						(arc
							(start -0.1778 0.2794)
							(mid -0.249642 0.249642)
							(end -0.2794 0.1778)
						)
						(arc
							(start -0.2794 -0.1778)
							(mid -0.249642 -0.249642)
							(end -0.1778 -0.2794)
						)
						(arc
							(start 0.1778 -0.2794)
							(mid 0.249642 -0.249642)
							(end 0.2794 -0.1778)
						)
						(arc
							(start 0.2794 0.1778)
							(mid 0.249642 0.249642)
							(end 0.1778 0.2794)
						)
					)
					(width 0)
					(fill yes)
				)
			)
		)
	)
	(footprint ""
		(layer "B.Cu")
		(at 209.042 -62.0268 -90)
		(property "Reference" "R637"
			(at 0 0 90)
			(layer "B.SilkS")
			(hide yes)
			(effects
				(font
					(size 1.27 1.27)
				)
				(justify mirror)
			)
		)
		(property "Value" "4K7R2F-GP"
			(at -0.064008 -3.993896 270)
			(unlocked yes)
			(layer "B.Fab")
			(hide yes)
			(effects
				(font
					(size 1.016 1.016)
					(thickness 0.1524)
				)
				(justify mirror)
			)
		)
		(property "Device Type" "R402H16"
			(at -0.064008 -5.517896 270)
			(unlocked yes)
			(layer "B.Fab")
			(hide yes)
			(effects
				(font
					(size 1.016 1.016)
					(thickness 0.1524)
				)
				(justify mirror)
			)
		)
		(duplicate_pad_numbers_are_jumpers no)
		(fp_line
			(start -0.508 -0.9398)
			(end 0.508 -0.9398)
			(stroke
				(width 0.1524)
				(type default)
			)
			(layer "B.SilkS")
		)
		(fp_line
			(start 0.508 -0.9398)
			(end 0.508 0.9398)
			(stroke
				(width 0.1524)
				(type default)
			)
			(layer "B.SilkS")
		)
		(fp_rect
			(start 0.508 0.9398)
			(end -0.508 -0.9398)
			(stroke
				(width 0)
				(type default)
			)
			(fill no)
			(layer "B.CrtYd")
		)
		(fp_rect
			(start 0.508 0.9398)
			(end -0.508 -0.9398)
			(stroke
				(width 0)
				(type default)
			)
			(fill no)
			(layer "B.Fab")
		)
		(pad "1" smd custom
			(at 0 -0.4445 90)
			(size 0.1397 0.1397)
			(layers "B.Cu" "B.Mask" "B.Paste")
			(net "P1V8")
			(options
				(clearance outline)
				(anchor circle)
			)
			(primitives
				(gr_poly
					(pts
						(arc
							(start -0.1778 0.2794)
							(mid -0.249642 0.249642)
							(end -0.2794 0.1778)
						)
						(arc
							(start -0.2794 -0.1778)
							(mid -0.249642 -0.249642)
							(end -0.1778 -0.2794)
						)
						(arc
							(start 0.1778 -0.2794)
							(mid 0.249642 -0.249642)
							(end 0.2794 -0.1778)
						)
						(arc
							(start 0.2794 0.1778)
							(mid 0.249642 0.249642)
							(end 0.1778 0.2794)
						)
					)
					(width 0)
					(fill yes)
				)
			)
		)
		(pad "2" smd custom
			(at 0 0.4445 90)
			(size 0.1397 0.1397)
			(layers "B.Cu" "B.Mask" "B.Paste")
			(net "ICE_SEL")
			(options
				(clearance outline)
				(anchor circle)
			)
			(primitives
				(gr_poly
					(pts
						(arc
							(start -0.1778 0.2794)
							(mid -0.249642 0.249642)
							(end -0.2794 0.1778)
						)
						(arc
							(start -0.2794 -0.1778)
							(mid -0.249642 -0.249642)
							(end -0.1778 -0.2794)
						)
						(arc
							(start 0.1778 -0.2794)
							(mid 0.249642 -0.249642)
							(end 0.2794 -0.1778)
						)
						(arc
							(start 0.2794 0.1778)
							(mid 0.249642 0.249642)
							(end 0.1778 0.2794)
						)
					)
					(width 0)
					(fill yes)
				)
			)
		)
	)
	(footprint ""
		(layer "B.Cu")
		(at 198.52132 -66.25336)
		(property "Reference" "C375"
			(at 0 0 0)
			(layer "B.SilkS")
			(hide yes)
			(effects
				(font
					(size 1.27 1.27)
				)
				(justify mirror)
			)
		)
		(property "Value" "SC1U6D3V1MX-GP"
			(at -1.9177 2.0193 0)
			(unlocked yes)
			(layer "B.Fab")
			(hide yes)
			(effects
				(font
					(size 1.016 1.016)
					(thickness 0.1524)
				)
				(justify mirror)
			)
		)
		(property "Device Type" "C0201H14"
			(at -1.9177 0.4953 0)
			(unlocked yes)
			(layer "B.Fab")
			(hide yes)
			(effects
				(font
					(size 1.016 1.016)
					(thickness 0.1524)
				)
				(justify mirror)
			)
		)
		(duplicate_pad_numbers_are_jumpers no)
		(fp_rect
			(start 0.1524 0.3048)
			(end -0.1524 -0.3048)
			(stroke
				(width 0)
				(type default)
			)
			(fill no)
			(layer "B.CrtYd")
		)
		(fp_poly
			(pts
				(xy 0.2794 0.6477) (xy 0.2794 -0.6477) (xy -0.2794 -0.6477) (xy -0.2794 -0.1905) (xy -0.1524 -0.1905)
				(xy -0.1524 -0.3048) (xy 0.1524 -0.3048) (xy 0.1524 0.3048) (xy -0.1524 0.3048) (xy -0.1524 -0.1778)
				(xy -0.2794 -0.1778) (xy -0.2794 0.6477)
			)
			(stroke
				(width 0)
				(type default)
			)
			(fill no)
			(layer "B.CrtYd")
		)
		(fp_rect
			(start 0.2794 0.6477)
			(end -0.2794 -0.6477)
			(stroke
				(width 0)
				(type default)
			)
			(fill no)
			(layer "B.Fab")
		)
		(pad "1" smd custom
			(at 0 -0.2794 180)
			(size 0.0762 0.0762)
			(layers "B.Cu" "B.Mask" "B.Paste")
			(net "SAS0_AVDD")
			(options
				(clearance outline)
				(anchor circle)
			)
			(primitives
				(gr_poly
					(pts
						(arc
							(start 0.1524 0.127)
							(mid 0.137521 0.162921)
							(end 0.1016 0.1778)
						)
						(arc
							(start -0.1016 0.1778)
							(mid -0.137521 0.162921)
							(end -0.1524 0.127)
						)
						(arc
							(start -0.1524 -0.127)
							(mid -0.137521 -0.162921)
							(end -0.1016 -0.1778)
						)
						(arc
							(start 0.1016 -0.1778)
							(mid 0.137521 -0.162921)
							(end 0.1524 -0.127)
						)
					)
					(width 0)
					(fill yes)
				)
			)
		)
		(pad "2" smd custom
			(at 0 0.2794 180)
			(size 0.0762 0.0762)
			(layers "B.Cu" "B.Mask" "B.Paste")
			(net "GND")
			(options
				(clearance outline)
				(anchor circle)
			)
			(primitives
				(gr_poly
					(pts
						(arc
							(start 0.1524 0.127)
							(mid 0.137521 0.162921)
							(end 0.1016 0.1778)
						)
						(arc
							(start -0.1016 0.1778)
							(mid -0.137521 0.162921)
							(end -0.1524 0.127)
						)
						(arc
							(start -0.1524 -0.127)
							(mid -0.137521 -0.162921)
							(end -0.1016 -0.1778)
						)
						(arc
							(start 0.1016 -0.1778)
							(mid 0.137521 -0.162921)
							(end 0.1524 -0.127)
						)
					)
					(width 0)
					(fill yes)
				)
			)
		)
	)
	(footprint ""
		(layer "B.Cu")
		(at 202.112626 -54.946296)
		(property "Reference" "C442"
			(at 0 0 0)
			(layer "B.SilkS")
			(hide yes)
			(effects
				(font
					(size 1.27 1.27)
				)
				(justify mirror)
			)
		)
		(property "Value" "SCD1U16V2KX-3GP"
			(at -1.1811 -2.7051 0)
			(unlocked yes)
			(layer "B.Fab")
			(hide yes)
			(effects
				(font
					(size 1.016 1.016)
					(thickness 0.1524)
				)
				(justify mirror)
			)
		)
		(property "Device Type" "C402H22"
			(at -1.1811 -4.2291 0)
			(unlocked yes)
			(layer "B.Fab")
			(hide yes)
			(effects
				(font
					(size 1.016 1.016)
					(thickness 0.1524)
				)
				(justify mirror)
			)
		)
		(duplicate_pad_numbers_are_jumpers no)
		(fp_rect
			(start 0.4318 0.9525)
			(end -0.4318 -0.9525)
			(stroke
				(width 0)
				(type default)
			)
			(fill no)
			(layer "B.CrtYd")
		)
		(fp_rect
			(start 0.4318 0.9525)
			(end -0.4318 -0.9525)
			(stroke
				(width 0)
				(type default)
			)
			(fill no)
			(layer "B.Fab")
		)
		(pad "1" smd custom
			(at 0 -0.4445 180)
			(size 0.1524 0.1524)
			(layers "B.Cu" "B.Mask" "B.Paste")
			(net "P1V8")
			(options
				(clearance outline)
				(anchor circle)
			)
			(primitives
				(gr_poly
					(pts
						(arc
							(start 0.3048 0.2032)
							(mid 0.275042 0.275042)
							(end 0.2032 0.3048)
						)
						(arc
							(start -0.2032 0.3048)
							(mid -0.275042 0.275042)
							(end -0.3048 0.2032)
						)
						(arc
							(start -0.3048 -0.2032)
							(mid -0.275042 -0.275042)
							(end -0.2032 -0.3048)
						)
						(arc
							(start 0.2032 -0.3048)
							(mid 0.275042 -0.275042)
							(end 0.3048 -0.2032)
						)
					)
					(width 0)
					(fill yes)
				)
			)
		)
		(pad "2" smd custom
			(at 0 0.4445 180)
			(size 0.1524 0.1524)
			(layers "B.Cu" "B.Mask" "B.Paste")
			(net "GND")
			(options
				(clearance outline)
				(anchor circle)
			)
			(primitives
				(gr_poly
					(pts
						(arc
							(start 0.3048 0.2032)
							(mid 0.275042 0.275042)
							(end 0.2032 0.3048)
						)
						(arc
							(start -0.2032 0.3048)
							(mid -0.275042 0.275042)
							(end -0.3048 0.2032)
						)
						(arc
							(start -0.3048 -0.2032)
							(mid -0.275042 -0.275042)
							(end -0.2032 -0.3048)
						)
						(arc
							(start 0.2032 -0.3048)
							(mid 0.275042 -0.275042)
							(end 0.3048 -0.2032)
						)
					)
					(width 0)
					(fill yes)
				)
			)
		)
	)
	(footprint ""
		(layer "B.Cu")
		(at 56.376824 -138.325098 -90)
		(property "Reference" "TP70"
			(at 0 0 90)
			(layer "B.SilkS")
			(hide yes)
			(effects
				(font
					(size 1.27 1.27)
				)
				(justify mirror)
			)
		)
		(property "Value" "TPAD28-2-GP"
			(at 0.0127 -1.6637 270)
			(unlocked yes)
			(layer "B.Fab")
			(hide yes)
			(effects
				(font
					(size 1.016 1.016)
					(thickness 0.1524)
				)
				(justify mirror)
			)
		)
		(property "Device Type" "TPAD28"
			(at 0.0127 -3.1877 270)
			(unlocked yes)
			(layer "B.Fab")
			(hide yes)
			(effects
				(font
					(size 1.016 1.016)
					(thickness 0.1524)
				)
				(justify mirror)
			)
		)
		(duplicate_pad_numbers_are_jumpers no)
		(fp_poly
			(pts
				(arc
					(start 0 -0.3556)
					(mid 0 0.3556)
					(end 0 -0.3556)
				)
			)
			(stroke
				(width 0)
				(type default)
			)
			(fill no)
			(layer "B.CrtYd")
		)
		(fp_poly
			(pts
				(arc
					(start 0 -0.6096)
					(mid 0 0.6096)
					(end 0 -0.6096)
				)
			)
			(stroke
				(width 0)
				(type default)
			)
			(fill no)
			(layer "B.Fab")
		)
		(pad "1" smd circle
			(at 0 0 90)
			(size 0.7112 0.7112)
			(layers "B.Cu" "B.Mask" "B.Paste")
			(net "TP_BMC_GPIOI0")
		)
	)
	(footprint ""
		(layer "B.Cu")
		(at 186.173872 -74.793856 -90)
		(property "Reference" "C471"
			(at 0 0 90)
			(layer "B.SilkS")
			(hide yes)
			(effects
				(font
					(size 1.27 1.27)
				)
				(justify mirror)
			)
		)
		(property "Value" "SCD1U16V2KX-3GP"
			(at -1.1811 -2.7051 270)
			(unlocked yes)
			(layer "B.Fab")
			(hide yes)
			(effects
				(font
					(size 1.016 1.016)
					(thickness 0.1524)
				)
				(justify mirror)
			)
		)
		(property "Device Type" "C402H22"
			(at -1.1811 -4.2291 270)
			(unlocked yes)
			(layer "B.Fab")
			(hide yes)
			(effects
				(font
					(size 1.016 1.016)
					(thickness 0.1524)
				)
				(justify mirror)
			)
		)
		(duplicate_pad_numbers_are_jumpers no)
		(fp_rect
			(start 0.4318 0.9525)
			(end -0.4318 -0.9525)
			(stroke
				(width 0)
				(type default)
			)
			(fill no)
			(layer "B.CrtYd")
		)
		(fp_rect
			(start 0.4318 0.9525)
			(end -0.4318 -0.9525)
			(stroke
				(width 0)
				(type default)
			)
			(fill no)
			(layer "B.Fab")
		)
		(pad "1" smd custom
			(at 0 -0.4445 90)
			(size 0.1524 0.1524)
			(layers "B.Cu" "B.Mask" "B.Paste")
			(net "P1V8")
			(options
				(clearance outline)
				(anchor circle)
			)
			(primitives
				(gr_poly
					(pts
						(arc
							(start 0.3048 0.2032)
							(mid 0.275042 0.275042)
							(end 0.2032 0.3048)
						)
						(arc
							(start -0.2032 0.3048)
							(mid -0.275042 0.275042)
							(end -0.3048 0.2032)
						)
						(arc
							(start -0.3048 -0.2032)
							(mid -0.275042 -0.275042)
							(end -0.2032 -0.3048)
						)
						(arc
							(start 0.2032 -0.3048)
							(mid 0.275042 -0.275042)
							(end 0.3048 -0.2032)
						)
					)
					(width 0)
					(fill yes)
				)
			)
		)
		(pad "2" smd custom
			(at 0 0.4445 90)
			(size 0.1524 0.1524)
			(layers "B.Cu" "B.Mask" "B.Paste")
			(net "GND")
			(options
				(clearance outline)
				(anchor circle)
			)
			(primitives
				(gr_poly
					(pts
						(arc
							(start 0.3048 0.2032)
							(mid 0.275042 0.275042)
							(end 0.2032 0.3048)
						)
						(arc
							(start -0.2032 0.3048)
							(mid -0.275042 0.275042)
							(end -0.3048 0.2032)
						)
						(arc
							(start -0.3048 -0.2032)
							(mid -0.275042 -0.275042)
							(end -0.2032 -0.3048)
						)
						(arc
							(start 0.2032 -0.3048)
							(mid 0.275042 -0.275042)
							(end 0.3048 -0.2032)
						)
					)
					(width 0)
					(fill yes)
				)
			)
		)
	)
	(footprint ""
		(layer "B.Cu")
		(at 189.21984 -50.14722)
		(property "Reference" "TP169"
			(at 0 0 0)
			(layer "B.SilkS")
			(hide yes)
			(effects
				(font
					(size 1.27 1.27)
				)
				(justify mirror)
			)
		)
		(property "Value" "TPAD28-2-GP"
			(at 0.0127 -1.6637 0)
			(unlocked yes)
			(layer "B.Fab")
			(hide yes)
			(effects
				(font
					(size 1.016 1.016)
					(thickness 0.1524)
				)
				(justify mirror)
			)
		)
		(property "Device Type" "TPAD28"
			(at 0.0127 -3.1877 0)
			(unlocked yes)
			(layer "B.Fab")
			(hide yes)
			(effects
				(font
					(size 1.016 1.016)
					(thickness 0.1524)
				)
				(justify mirror)
			)
		)
		(duplicate_pad_numbers_are_jumpers no)
		(fp_poly
			(pts
				(arc
					(start 0.3556 0)
					(mid -0.3556 0)
					(end 0.3556 0)
				)
			)
			(stroke
				(width 0)
				(type default)
			)
			(fill no)
			(layer "B.CrtYd")
		)
		(fp_poly
			(pts
				(arc
					(start 0.6096 0)
					(mid -0.6096 0)
					(end 0.6096 0)
				)
			)
			(stroke
				(width 0)
				(type default)
			)
			(fill no)
			(layer "B.Fab")
		)
		(pad "1" smd circle
			(at 0 0 180)
			(size 0.7112 0.7112)
			(layers "B.Cu" "B.Mask" "B.Paste")
			(net "VDDIO_15")
		)
	)
	(footprint ""
		(layer "B.Cu")
		(at 47.22368 -155.25496 90)
		(property "Reference" "C91"
			(at 0 0 90)
			(layer "B.SilkS")
			(hide yes)
			(effects
				(font
					(size 1.27 1.27)
				)
				(justify mirror)
			)
		)
		(property "Value" "SC100P50V2JN-3GP"
			(at -1.1811 -2.7051 90)
			(unlocked yes)
			(layer "B.Fab")
			(hide yes)
			(effects
				(font
					(size 1.016 1.016)
					(thickness 0.1524)
				)
				(justify mirror)
			)
		)
		(property "Device Type" "C402H22"
			(at -1.1811 -4.2291 90)
			(unlocked yes)
			(layer "B.Fab")
			(hide yes)
			(effects
				(font
					(size 1.016 1.016)
					(thickness 0.1524)
				)
				(justify mirror)
			)
		)
		(duplicate_pad_numbers_are_jumpers no)
		(fp_rect
			(start 0.4318 0.9525)
			(end -0.4318 -0.9525)
			(stroke
				(width 0)
				(type default)
			)
			(fill no)
			(layer "B.CrtYd")
		)
		(fp_rect
			(start 0.4318 0.9525)
			(end -0.4318 -0.9525)
			(stroke
				(width 0)
				(type default)
			)
			(fill no)
			(layer "B.Fab")
		)
		(pad "1" smd custom
			(at 0 -0.4445 270)
			(size 0.1524 0.1524)
			(layers "B.Cu" "B.Mask" "B.Paste")
			(net "DACAV33")
			(options
				(clearance outline)
				(anchor circle)
			)
			(primitives
				(gr_poly
					(pts
						(arc
							(start 0.3048 0.2032)
							(mid 0.275042 0.275042)
							(end 0.2032 0.3048)
						)
						(arc
							(start -0.2032 0.3048)
							(mid -0.275042 0.275042)
							(end -0.3048 0.2032)
						)
						(arc
							(start -0.3048 -0.2032)
							(mid -0.275042 -0.275042)
							(end -0.2032 -0.3048)
						)
						(arc
							(start 0.2032 -0.3048)
							(mid 0.275042 -0.275042)
							(end 0.3048 -0.2032)
						)
					)
					(width 0)
					(fill yes)
				)
			)
		)
		(pad "2" smd custom
			(at 0 0.4445 270)
			(size 0.1524 0.1524)
			(layers "B.Cu" "B.Mask" "B.Paste")
			(net "GND")
			(options
				(clearance outline)
				(anchor circle)
			)
			(primitives
				(gr_poly
					(pts
						(arc
							(start 0.3048 0.2032)
							(mid 0.275042 0.275042)
							(end 0.2032 0.3048)
						)
						(arc
							(start -0.2032 0.3048)
							(mid -0.275042 0.275042)
							(end -0.3048 0.2032)
						)
						(arc
							(start -0.3048 -0.2032)
							(mid -0.275042 -0.275042)
							(end -0.2032 -0.3048)
						)
						(arc
							(start 0.2032 -0.3048)
							(mid 0.275042 -0.275042)
							(end 0.3048 -0.2032)
						)
					)
					(width 0)
					(fill yes)
				)
			)
		)
	)
	(footprint ""
		(layer "B.Cu")
		(at 186.618626 -122.236738 -90)
		(property "Reference" "PSP1"
			(at 0 0 90)
			(layer "B.SilkS")
			(hide yes)
			(effects
				(font
					(size 1.27 1.27)
				)
				(justify mirror)
			)
		)
		(property "Value" "COPPER-CLOSE-GP-U"
			(at -0.0762 -2.8702 270)
			(unlocked yes)
			(layer "B.Fab")
			(hide yes)
			(effects
				(font
					(size 1.016 1.016)
					(thickness 0.1524)
				)
				(justify mirror)
			)
		)
		(property "Device Type" "CON2C-U"
			(at -0.0762 -4.3942 270)
			(unlocked yes)
			(layer "B.Fab")
			(hide yes)
			(effects
				(font
					(size 1.016 1.016)
					(thickness 0.1524)
				)
				(justify mirror)
			)
		)
		(duplicate_pad_numbers_are_jumpers no)
		(fp_rect
			(start 0.9398 0.9652)
			(end -0.9398 -0.9652)
			(stroke
				(width 0)
				(type default)
			)
			(fill no)
			(layer "B.CrtYd")
		)
		(fp_rect
			(start 0.9398 0.9652)
			(end -0.9398 -0.9652)
			(stroke
				(width 0)
				(type default)
			)
			(fill no)
			(layer "B.Fab")
		)
		(pad "1" smd custom
			(at 0 -0.5334 90)
			(size 0.17145 0.17145)
			(layers "B.Cu" "B.Mask" "B.Paste")
			(net "GND")
			(options
				(clearance outline)
				(anchor circle)
			)
			(primitives
				(gr_poly
					(pts
						(xy -0.127 -0.3429) (xy -0.127 -0.1651) (xy -0.635 0.3429) (xy 0.635 0.3429) (xy 0.127 -0.1651)
						(xy 0.127 -0.3429)
					)
					(width 0)
					(fill yes)
				)
			)
		)
		(pad "2" smd custom
			(at 0 0.5334 90)
			(size 0.17145 0.17145)
			(layers "B.Cu" "B.Mask" "B.Paste")
			(net "AGND_P0V975")
			(options
				(clearance outline)
				(anchor circle)
			)
			(primitives
				(gr_poly
					(pts
						(xy -0.635 -0.3429) (xy -0.127 0.1651) (xy -0.127 0.3429) (xy 0.127 0.3429) (xy 0.127 0.1651)
						(xy 0.635 -0.3429)
					)
					(width 0)
					(fill yes)
				)
			)
		)
	)
	(footprint ""
		(layer "B.Cu")
		(at 48.079406 -147.98675 90)
		(property "Reference" "C107"
			(at 0 0 90)
			(layer "B.SilkS")
			(hide yes)
			(effects
				(font
					(size 1.27 1.27)
				)
				(justify mirror)
			)
		)
		(property "Value" "SC1U16V3KX-5GP"
			(at 0 -2.8194 90)
			(unlocked yes)
			(layer "B.Fab")
			(hide yes)
			(effects
				(font
					(size 1.016 1.016)
					(thickness 0.1524)
				)
				(justify mirror)
			)
		)
		(property "Device Type" "C603H36"
			(at 0 -4.3434 90)
			(unlocked yes)
			(layer "B.Fab")
			(hide yes)
			(effects
				(font
					(size 1.016 1.016)
					(thickness 0.1524)
				)
				(justify mirror)
			)
		)
		(duplicate_pad_numbers_are_jumpers no)
		(fp_line
			(start -0.508 0)
			(end 0.508 0)
			(stroke
				(width 0.2032)
				(type default)
			)
			(layer "B.SilkS")
		)
		(fp_rect
			(start 0.5842 1.3335)
			(end -0.5842 -1.3335)
			(stroke
				(width 0)
				(type default)
			)
			(fill no)
			(layer "B.CrtYd")
		)
		(fp_rect
			(start 0.5842 1.3335)
			(end -0.5842 -1.3335)
			(stroke
				(width 0)
				(type default)
			)
			(fill no)
			(layer "B.Fab")
		)
		(pad "1" smd custom
			(at 0 -0.762 270)
			(size 0.2159 0.2159)
			(layers "B.Cu" "B.Mask" "B.Paste")
			(net "P1V15_STBY")
			(options
				(clearance outline)
				(anchor circle)
			)
			(primitives
				(gr_poly
					(pts
						(arc
							(start -0.3302 0.4318)
							(mid -0.402042 0.402042)
							(end -0.4318 0.3302)
						)
						(arc
							(start -0.4318 -0.3302)
							(mid -0.402042 -0.402042)
							(end -0.3302 -0.4318)
						)
						(arc
							(start 0.3302 -0.4318)
							(mid 0.402042 -0.402042)
							(end 0.4318 -0.3302)
						)
						(arc
							(start 0.4318 0.3302)
							(mid 0.402042 0.402042)
							(end 0.3302 0.4318)
						)
					)
					(width 0)
					(fill yes)
				)
			)
		)
		(pad "2" smd custom
			(at 0 0.762 270)
			(size 0.2159 0.2159)
			(layers "B.Cu" "B.Mask" "B.Paste")
			(net "GND")
			(options
				(clearance outline)
				(anchor circle)
			)
			(primitives
				(gr_poly
					(pts
						(arc
							(start -0.3302 0.4318)
							(mid -0.402042 0.402042)
							(end -0.4318 0.3302)
						)
						(arc
							(start -0.4318 -0.3302)
							(mid -0.402042 -0.402042)
							(end -0.3302 -0.4318)
						)
						(arc
							(start 0.3302 -0.4318)
							(mid 0.402042 -0.402042)
							(end 0.4318 -0.3302)
						)
						(arc
							(start 0.4318 0.3302)
							(mid 0.402042 0.402042)
							(end 0.3302 0.4318)
						)
					)
					(width 0)
					(fill yes)
				)
			)
		)
	)
	(footprint ""
		(layer "B.Cu")
		(at 188.43244 -73.10374 90)
		(property "Reference" "C452"
			(at 0 0 90)
			(layer "B.SilkS")
			(hide yes)
			(effects
				(font
					(size 1.27 1.27)
				)
				(justify mirror)
			)
		)
		(property "Value" "SCD1U16V2KX-3GP"
			(at -1.1811 -2.7051 90)
			(unlocked yes)
			(layer "B.Fab")
			(hide yes)
			(effects
				(font
					(size 1.016 1.016)
					(thickness 0.1524)
				)
				(justify mirror)
			)
		)
		(property "Device Type" "C402H22"
			(at -1.1811 -4.2291 90)
			(unlocked yes)
			(layer "B.Fab")
			(hide yes)
			(effects
				(font
					(size 1.016 1.016)
					(thickness 0.1524)
				)
				(justify mirror)
			)
		)
		(duplicate_pad_numbers_are_jumpers no)
		(fp_rect
			(start 0.4318 0.9525)
			(end -0.4318 -0.9525)
			(stroke
				(width 0)
				(type default)
			)
			(fill no)
			(layer "B.CrtYd")
		)
		(fp_rect
			(start 0.4318 0.9525)
			(end -0.4318 -0.9525)
			(stroke
				(width 0)
				(type default)
			)
			(fill no)
			(layer "B.Fab")
		)
		(pad "1" smd custom
			(at 0 -0.4445 270)
			(size 0.1524 0.1524)
			(layers "B.Cu" "B.Mask" "B.Paste")
			(net "P1V8")
			(options
				(clearance outline)
				(anchor circle)
			)
			(primitives
				(gr_poly
					(pts
						(arc
							(start 0.3048 0.2032)
							(mid 0.275042 0.275042)
							(end 0.2032 0.3048)
						)
						(arc
							(start -0.2032 0.3048)
							(mid -0.275042 0.275042)
							(end -0.3048 0.2032)
						)
						(arc
							(start -0.3048 -0.2032)
							(mid -0.275042 -0.275042)
							(end -0.2032 -0.3048)
						)
						(arc
							(start 0.2032 -0.3048)
							(mid 0.275042 -0.275042)
							(end 0.3048 -0.2032)
						)
					)
					(width 0)
					(fill yes)
				)
			)
		)
		(pad "2" smd custom
			(at 0 0.4445 270)
			(size 0.1524 0.1524)
			(layers "B.Cu" "B.Mask" "B.Paste")
			(net "GND")
			(options
				(clearance outline)
				(anchor circle)
			)
			(primitives
				(gr_poly
					(pts
						(arc
							(start 0.3048 0.2032)
							(mid 0.275042 0.275042)
							(end 0.2032 0.3048)
						)
						(arc
							(start -0.2032 0.3048)
							(mid -0.275042 0.275042)
							(end -0.3048 0.2032)
						)
						(arc
							(start -0.3048 -0.2032)
							(mid -0.275042 -0.275042)
							(end -0.2032 -0.3048)
						)
						(arc
							(start 0.2032 -0.3048)
							(mid 0.275042 -0.275042)
							(end 0.3048 -0.2032)
						)
					)
					(width 0)
					(fill yes)
				)
			)
		)
	)
	(footprint ""
		(layer "B.Cu")
		(at 184.61482 -73.13422 90)
		(property "Reference" "R650"
			(at 0 0 90)
			(layer "B.SilkS")
			(hide yes)
			(effects
				(font
					(size 1.27 1.27)
				)
				(justify mirror)
			)
		)
		(property "Value" "10KR2F-2-GP"
			(at -0.064008 -3.993896 90)
			(unlocked yes)
			(layer "B.Fab")
			(hide yes)
			(effects
				(font
					(size 1.016 1.016)
					(thickness 0.1524)
				)
				(justify mirror)
			)
		)
		(property "Device Type" "R402H16"
			(at -0.064008 -5.517896 90)
			(unlocked yes)
			(layer "B.Fab")
			(hide yes)
			(effects
				(font
					(size 1.016 1.016)
					(thickness 0.1524)
				)
				(justify mirror)
			)
		)
		(duplicate_pad_numbers_are_jumpers no)
		(fp_line
			(start 0.508 -0.9398)
			(end 0.508 0.9398)
			(stroke
				(width 0.1524)
				(type default)
			)
			(layer "B.SilkS")
		)
		(fp_line
			(start -0.508 -0.9398)
			(end 0.508 -0.9398)
			(stroke
				(width 0.1524)
				(type default)
			)
			(layer "B.SilkS")
		)
		(fp_rect
			(start 0.508 0.9398)
			(end -0.508 -0.9398)
			(stroke
				(width 0)
				(type default)
			)
			(fill no)
			(layer "B.CrtYd")
		)
		(fp_rect
			(start 0.508 0.9398)
			(end -0.508 -0.9398)
			(stroke
				(width 0)
				(type default)
			)
			(fill no)
			(layer "B.Fab")
		)
		(pad "1" smd custom
			(at 0 -0.4445 270)
			(size 0.1397 0.1397)
			(layers "B.Cu" "B.Mask" "B.Paste")
			(net "P1V8")
			(options
				(clearance outline)
				(anchor circle)
			)
			(primitives
				(gr_poly
					(pts
						(arc
							(start -0.1778 0.2794)
							(mid -0.249642 0.249642)
							(end -0.2794 0.1778)
						)
						(arc
							(start -0.2794 -0.1778)
							(mid -0.249642 -0.249642)
							(end -0.1778 -0.2794)
						)
						(arc
							(start 0.1778 -0.2794)
							(mid 0.249642 -0.249642)
							(end 0.2794 -0.1778)
						)
						(arc
							(start 0.2794 0.1778)
							(mid 0.249642 0.249642)
							(end 0.1778 0.2794)
						)
					)
					(width 0)
					(fill yes)
				)
			)
		)
		(pad "2" smd custom
			(at 0 0.4445 270)
			(size 0.1397 0.1397)
			(layers "B.Cu" "B.Mask" "B.Paste")
			(net "SYS_RST_N_1")
			(options
				(clearance outline)
				(anchor circle)
			)
			(primitives
				(gr_poly
					(pts
						(arc
							(start -0.1778 0.2794)
							(mid -0.249642 0.249642)
							(end -0.2794 0.1778)
						)
						(arc
							(start -0.2794 -0.1778)
							(mid -0.249642 -0.249642)
							(end -0.1778 -0.2794)
						)
						(arc
							(start 0.1778 -0.2794)
							(mid 0.249642 -0.249642)
							(end 0.2794 -0.1778)
						)
						(arc
							(start 0.2794 0.1778)
							(mid 0.249642 0.249642)
							(end 0.1778 0.2794)
						)
					)
					(width 0)
					(fill yes)
				)
			)
		)
	)
	(footprint ""
		(layer "B.Cu")
		(at 12.091924 -135.285988 90)
		(property "Reference" "R257"
			(at 0 0 90)
			(layer "B.SilkS")
			(hide yes)
			(effects
				(font
					(size 1.27 1.27)
				)
				(justify mirror)
			)
		)
		(property "Value" "120R2F-GP"
			(at -0.064008 -3.993896 90)
			(unlocked yes)
			(layer "B.Fab")
			(hide yes)
			(effects
				(font
					(size 1.016 1.016)
					(thickness 0.1524)
				)
				(justify mirror)
			)
		)
		(property "Device Type" "R402H16"
			(at -0.064008 -5.517896 90)
			(unlocked yes)
			(layer "B.Fab")
			(hide yes)
			(effects
				(font
					(size 1.016 1.016)
					(thickness 0.1524)
				)
				(justify mirror)
			)
		)
		(duplicate_pad_numbers_are_jumpers no)
		(fp_line
			(start 0.508 -0.9398)
			(end 0.508 0.9398)
			(stroke
				(width 0.1524)
				(type default)
			)
			(layer "B.SilkS")
		)
		(fp_line
			(start -0.508 -0.9398)
			(end 0.508 -0.9398)
			(stroke
				(width 0.1524)
				(type default)
			)
			(layer "B.SilkS")
		)
		(fp_rect
			(start 0.508 0.9398)
			(end -0.508 -0.9398)
			(stroke
				(width 0)
				(type default)
			)
			(fill no)
			(layer "B.CrtYd")
		)
		(fp_rect
			(start 0.508 0.9398)
			(end -0.508 -0.9398)
			(stroke
				(width 0)
				(type default)
			)
			(fill no)
			(layer "B.Fab")
		)
		(pad "1" smd custom
			(at 0 -0.4445 270)
			(size 0.1397 0.1397)
			(layers "B.Cu" "B.Mask" "B.Paste")
			(net "MEMA_11")
			(options
				(clearance outline)
				(anchor circle)
			)
			(primitives
				(gr_poly
					(pts
						(arc
							(start -0.1778 0.2794)
							(mid -0.249642 0.249642)
							(end -0.2794 0.1778)
						)
						(arc
							(start -0.2794 -0.1778)
							(mid -0.249642 -0.249642)
							(end -0.1778 -0.2794)
						)
						(arc
							(start 0.1778 -0.2794)
							(mid 0.249642 -0.249642)
							(end 0.2794 -0.1778)
						)
						(arc
							(start 0.2794 0.1778)
							(mid 0.249642 0.249642)
							(end 0.1778 0.2794)
						)
					)
					(width 0)
					(fill yes)
				)
			)
		)
		(pad "2" smd custom
			(at 0 0.4445 270)
			(size 0.1397 0.1397)
			(layers "B.Cu" "B.Mask" "B.Paste")
			(net "P1V2_STBY")
			(options
				(clearance outline)
				(anchor circle)
			)
			(primitives
				(gr_poly
					(pts
						(arc
							(start -0.1778 0.2794)
							(mid -0.249642 0.249642)
							(end -0.2794 0.1778)
						)
						(arc
							(start -0.2794 -0.1778)
							(mid -0.249642 -0.249642)
							(end -0.1778 -0.2794)
						)
						(arc
							(start 0.1778 -0.2794)
							(mid 0.249642 -0.249642)
							(end 0.2794 -0.1778)
						)
						(arc
							(start 0.2794 0.1778)
							(mid 0.249642 0.249642)
							(end 0.1778 0.2794)
						)
					)
					(width 0)
					(fill yes)
				)
			)
		)
	)
	(footprint ""
		(layer "B.Cu")
		(at 80.8228 -167.1574 -90)
		(property "Reference" "R452"
			(at 0 0 90)
			(layer "B.SilkS")
			(hide yes)
			(effects
				(font
					(size 1.27 1.27)
				)
				(justify mirror)
			)
		)
		(property "Value" "0R2J-2-GP"
			(at -0.064008 -3.993896 270)
			(unlocked yes)
			(layer "B.Fab")
			(hide yes)
			(effects
				(font
					(size 1.016 1.016)
					(thickness 0.1524)
				)
				(justify mirror)
			)
		)
		(property "Device Type" "R402H16"
			(at -0.064008 -5.517896 270)
			(unlocked yes)
			(layer "B.Fab")
			(hide yes)
			(effects
				(font
					(size 1.016 1.016)
					(thickness 0.1524)
				)
				(justify mirror)
			)
		)
		(duplicate_pad_numbers_are_jumpers no)
		(fp_line
			(start -0.508 -0.9398)
			(end 0.508 -0.9398)
			(stroke
				(width 0.1524)
				(type default)
			)
			(layer "B.SilkS")
		)
		(fp_line
			(start 0.508 -0.9398)
			(end 0.508 0.9398)
			(stroke
				(width 0.1524)
				(type default)
			)
			(layer "B.SilkS")
		)
		(fp_rect
			(start 0.508 0.9398)
			(end -0.508 -0.9398)
			(stroke
				(width 0)
				(type default)
			)
			(fill no)
			(layer "B.CrtYd")
		)
		(fp_rect
			(start 0.508 0.9398)
			(end -0.508 -0.9398)
			(stroke
				(width 0)
				(type default)
			)
			(fill no)
			(layer "B.Fab")
		)
		(pad "1" smd custom
			(at 0 -0.4445 90)
			(size 0.1397 0.1397)
			(layers "B.Cu" "B.Mask" "B.Paste")
			(net "UART_SDB_TX_R")
			(options
				(clearance outline)
				(anchor circle)
			)
			(primitives
				(gr_poly
					(pts
						(arc
							(start -0.1778 0.2794)
							(mid -0.249642 0.249642)
							(end -0.2794 0.1778)
						)
						(arc
							(start -0.2794 -0.1778)
							(mid -0.249642 -0.249642)
							(end -0.1778 -0.2794)
						)
						(arc
							(start 0.1778 -0.2794)
							(mid 0.249642 -0.249642)
							(end 0.2794 -0.1778)
						)
						(arc
							(start 0.2794 0.1778)
							(mid 0.249642 0.249642)
							(end 0.1778 0.2794)
						)
					)
					(width 0)
					(fill yes)
				)
			)
		)
		(pad "2" smd custom
			(at 0 0.4445 90)
			(size 0.1397 0.1397)
			(layers "B.Cu" "B.Mask" "B.Paste")
			(net "UART_SDB_TX")
			(options
				(clearance outline)
				(anchor circle)
			)
			(primitives
				(gr_poly
					(pts
						(arc
							(start -0.1778 0.2794)
							(mid -0.249642 0.249642)
							(end -0.2794 0.1778)
						)
						(arc
							(start -0.2794 -0.1778)
							(mid -0.249642 -0.249642)
							(end -0.1778 -0.2794)
						)
						(arc
							(start 0.1778 -0.2794)
							(mid 0.249642 -0.249642)
							(end 0.2794 -0.1778)
						)
						(arc
							(start 0.2794 0.1778)
							(mid 0.249642 0.249642)
							(end 0.1778 0.2794)
						)
					)
					(width 0)
					(fill yes)
				)
			)
		)
	)
	(footprint ""
		(layer "B.Cu")
		(at 197.485 -47.8028 -90)
		(property "Reference" "L17"
			(at 0 0 90)
			(layer "B.SilkS")
			(hide yes)
			(effects
				(font
					(size 1.27 1.27)
				)
				(justify mirror)
			)
		)
		(property "Value" "MPZ2012S601AT-GP"
			(at 0 -4.2418 270)
			(unlocked yes)
			(layer "B.Fab")
			(hide yes)
			(effects
				(font
					(size 1.016 1.016)
					(thickness 0.1524)
				)
				(justify mirror)
			)
		)
		(property "Device Type" "L805H42"
			(at 0 -5.7912 270)
			(unlocked yes)
			(layer "B.Fab")
			(hide yes)
			(effects
				(font
					(size 1.016 1.016)
					(thickness 0.1524)
				)
				(justify mirror)
			)
		)
		(duplicate_pad_numbers_are_jumpers no)
		(fp_line
			(start -0.889 1.7018)
			(end 0.889 1.7018)
			(stroke
				(width 0.1524)
				(type default)
			)
			(layer "B.SilkS")
		)
		(fp_line
			(start 0.889 1.7018)
			(end 0.889 -1.7018)
			(stroke
				(width 0.1524)
				(type default)
			)
			(layer "B.SilkS")
		)
		(fp_line
			(start -0.889 -1.7018)
			(end -0.889 1.7018)
			(stroke
				(width 0.1524)
				(type default)
			)
			(layer "B.SilkS")
		)
		(fp_line
			(start 0.889 -1.7018)
			(end -0.889 -1.7018)
			(stroke
				(width 0.1524)
				(type default)
			)
			(layer "B.SilkS")
		)
		(fp_rect
			(start 0.9652 1.778)
			(end -0.9652 -1.778)
			(stroke
				(width 0)
				(type default)
			)
			(fill no)
			(layer "B.CrtYd")
		)
		(fp_rect
			(start 0.9652 1.778)
			(end -0.9652 -1.778)
			(stroke
				(width 0)
				(type default)
			)
			(fill no)
			(layer "B.Fab")
		)
		(pad "1" smd rect
			(at 0 -0.9652 90)
			(size 1.397 1.143)
			(layers "B.Cu" "B.Mask" "B.Paste")
			(net "VDDA_SAS_REF_CLK")
		)
		(pad "2" smd rect
			(at 0 0.9652 90)
			(size 1.397 1.143)
			(layers "B.Cu" "B.Mask" "B.Paste")
			(net "P1V8")
		)
	)
	(footprint ""
		(layer "B.Cu")
		(at 92.5068 -168.7068 -90)
		(property "Reference" "R419"
			(at 0 0 90)
			(layer "B.SilkS")
			(hide yes)
			(effects
				(font
					(size 1.27 1.27)
				)
				(justify mirror)
			)
		)
		(property "Value" "0R2J-2-GP"
			(at -0.064008 -3.993896 270)
			(unlocked yes)
			(layer "B.Fab")
			(hide yes)
			(effects
				(font
					(size 1.016 1.016)
					(thickness 0.1524)
				)
				(justify mirror)
			)
		)
		(property "Device Type" "R402H16"
			(at -0.064008 -5.517896 270)
			(unlocked yes)
			(layer "B.Fab")
			(hide yes)
			(effects
				(font
					(size 1.016 1.016)
					(thickness 0.1524)
				)
				(justify mirror)
			)
		)
		(duplicate_pad_numbers_are_jumpers no)
		(fp_line
			(start -0.508 -0.9398)
			(end 0.508 -0.9398)
			(stroke
				(width 0.1524)
				(type default)
			)
			(layer "B.SilkS")
		)
		(fp_line
			(start 0.508 -0.9398)
			(end 0.508 0.9398)
			(stroke
				(width 0.1524)
				(type default)
			)
			(layer "B.SilkS")
		)
		(fp_rect
			(start 0.508 0.9398)
			(end -0.508 -0.9398)
			(stroke
				(width 0)
				(type default)
			)
			(fill no)
			(layer "B.CrtYd")
		)
		(fp_rect
			(start 0.508 0.9398)
			(end -0.508 -0.9398)
			(stroke
				(width 0)
				(type default)
			)
			(fill no)
			(layer "B.Fab")
		)
		(pad "1" smd custom
			(at 0 -0.4445 90)
			(size 0.1397 0.1397)
			(layers "B.Cu" "B.Mask" "B.Paste")
			(net "UART_COMP_RX")
			(options
				(clearance outline)
				(anchor circle)
			)
			(primitives
				(gr_poly
					(pts
						(arc
							(start -0.1778 0.2794)
							(mid -0.249642 0.249642)
							(end -0.2794 0.1778)
						)
						(arc
							(start -0.2794 -0.1778)
							(mid -0.249642 -0.249642)
							(end -0.1778 -0.2794)
						)
						(arc
							(start 0.1778 -0.2794)
							(mid 0.249642 -0.249642)
							(end 0.2794 -0.1778)
						)
						(arc
							(start 0.2794 0.1778)
							(mid 0.249642 0.249642)
							(end 0.1778 0.2794)
						)
					)
					(width 0)
					(fill yes)
				)
			)
		)
		(pad "2" smd custom
			(at 0 0.4445 90)
			(size 0.1397 0.1397)
			(layers "B.Cu" "B.Mask" "B.Paste")
			(net "UART_COMP_R_RX")
			(options
				(clearance outline)
				(anchor circle)
			)
			(primitives
				(gr_poly
					(pts
						(arc
							(start -0.1778 0.2794)
							(mid -0.249642 0.249642)
							(end -0.2794 0.1778)
						)
						(arc
							(start -0.2794 -0.1778)
							(mid -0.249642 -0.249642)
							(end -0.1778 -0.2794)
						)
						(arc
							(start 0.1778 -0.2794)
							(mid 0.249642 -0.249642)
							(end 0.2794 -0.1778)
						)
						(arc
							(start 0.2794 0.1778)
							(mid 0.249642 0.249642)
							(end 0.1778 0.2794)
						)
					)
					(width 0)
					(fill yes)
				)
			)
		)
	)
	(footprint ""
		(layer "B.Cu")
		(at 88.265 -179.832)
		(property "Reference" "R97"
			(at 0 0 0)
			(layer "B.SilkS")
			(hide yes)
			(effects
				(font
					(size 1.27 1.27)
				)
				(justify mirror)
			)
		)
		(property "Value" "0R2J-2-GP"
			(at -0.064008 -3.993896 0)
			(unlocked yes)
			(layer "B.Fab")
			(hide yes)
			(effects
				(font
					(size 1.016 1.016)
					(thickness 0.1524)
				)
				(justify mirror)
			)
		)
		(property "Device Type" "R402H16"
			(at -0.064008 -5.517896 0)
			(unlocked yes)
			(layer "B.Fab")
			(hide yes)
			(effects
				(font
					(size 1.016 1.016)
					(thickness 0.1524)
				)
				(justify mirror)
			)
		)
		(duplicate_pad_numbers_are_jumpers no)
		(fp_line
			(start -0.508 -0.9398)
			(end 0.508 -0.9398)
			(stroke
				(width 0.1524)
				(type default)
			)
			(layer "B.SilkS")
		)
		(fp_line
			(start 0.508 -0.9398)
			(end 0.508 0.9398)
			(stroke
				(width 0.1524)
				(type default)
			)
			(layer "B.SilkS")
		)
		(fp_rect
			(start 0.508 0.9398)
			(end -0.508 -0.9398)
			(stroke
				(width 0)
				(type default)
			)
			(fill no)
			(layer "B.CrtYd")
		)
		(fp_rect
			(start 0.508 0.9398)
			(end -0.508 -0.9398)
			(stroke
				(width 0)
				(type default)
			)
			(fill no)
			(layer "B.Fab")
		)
		(pad "1" smd custom
			(at 0 -0.4445 180)
			(size 0.1397 0.1397)
			(layers "B.Cu" "B.Mask" "B.Paste")
			(net "I2C_BMC_COMP_SDA_OUT")
			(options
				(clearance outline)
				(anchor circle)
			)
			(primitives
				(gr_poly
					(pts
						(arc
							(start -0.1778 0.2794)
							(mid -0.249642 0.249642)
							(end -0.2794 0.1778)
						)
						(arc
							(start -0.2794 -0.1778)
							(mid -0.249642 -0.249642)
							(end -0.1778 -0.2794)
						)
						(arc
							(start 0.1778 -0.2794)
							(mid 0.249642 -0.249642)
							(end 0.2794 -0.1778)
						)
						(arc
							(start 0.2794 0.1778)
							(mid 0.249642 0.249642)
							(end 0.1778 0.2794)
						)
					)
					(width 0)
					(fill yes)
				)
			)
		)
		(pad "2" smd custom
			(at 0 0.4445 180)
			(size 0.1397 0.1397)
			(layers "B.Cu" "B.Mask" "B.Paste")
			(net "I2C_BMC_COMP_SDA_R")
			(options
				(clearance outline)
				(anchor circle)
			)
			(primitives
				(gr_poly
					(pts
						(arc
							(start -0.1778 0.2794)
							(mid -0.249642 0.249642)
							(end -0.2794 0.1778)
						)
						(arc
							(start -0.2794 -0.1778)
							(mid -0.249642 -0.249642)
							(end -0.1778 -0.2794)
						)
						(arc
							(start 0.1778 -0.2794)
							(mid 0.249642 -0.249642)
							(end 0.2794 -0.1778)
						)
						(arc
							(start 0.2794 0.1778)
							(mid 0.249642 0.249642)
							(end 0.1778 0.2794)
						)
					)
					(width 0)
					(fill yes)
				)
			)
		)
	)
	(footprint ""
		(layer "B.Cu")
		(at 193.9798 -65.3796 90)
		(property "Reference" "C401"
			(at 0 0 90)
			(layer "B.SilkS")
			(hide yes)
			(effects
				(font
					(size 1.27 1.27)
				)
				(justify mirror)
			)
		)
		(property "Value" "SCD1U6D3V1KX-GP"
			(at 2.8321 -1.7399 90)
			(unlocked yes)
			(layer "B.Fab")
			(hide yes)
			(effects
				(font
					(size 1.016 1.016)
					(thickness 0.1524)
				)
				(justify mirror)
			)
		)
		(property "Device Type" "C0201H13"
			(at 2.8321 -3.2639 90)
			(unlocked yes)
			(layer "B.Fab")
			(hide yes)
			(effects
				(font
					(size 1.016 1.016)
					(thickness 0.1524)
				)
				(justify mirror)
			)
		)
		(duplicate_pad_numbers_are_jumpers no)
		(fp_rect
			(start 0.2794 0.6477)
			(end -0.2794 -0.6477)
			(stroke
				(width 0)
				(type default)
			)
			(fill no)
			(layer "B.CrtYd")
		)
		(fp_rect
			(start 0.2794 0.6477)
			(end -0.2794 -0.6477)
			(stroke
				(width 0)
				(type default)
			)
			(fill no)
			(layer "B.Fab")
		)
		(pad "1" smd custom
			(at 0 -0.2794 270)
			(size 0.0762 0.0762)
			(layers "B.Cu" "B.Mask" "B.Paste")
			(net "P0V975")
			(options
				(clearance outline)
				(anchor circle)
			)
			(primitives
				(gr_poly
					(pts
						(arc
							(start 0.1524 0.127)
							(mid 0.137521 0.162921)
							(end 0.1016 0.1778)
						)
						(arc
							(start -0.1016 0.1778)
							(mid -0.137521 0.162921)
							(end -0.1524 0.127)
						)
						(arc
							(start -0.1524 -0.127)
							(mid -0.137521 -0.162921)
							(end -0.1016 -0.1778)
						)
						(arc
							(start 0.1016 -0.1778)
							(mid 0.137521 -0.162921)
							(end 0.1524 -0.127)
						)
					)
					(width 0)
					(fill yes)
				)
			)
		)
		(pad "2" smd custom
			(at 0 0.2794 270)
			(size 0.0762 0.0762)
			(layers "B.Cu" "B.Mask" "B.Paste")
			(net "GND")
			(options
				(clearance outline)
				(anchor circle)
			)
			(primitives
				(gr_poly
					(pts
						(arc
							(start 0.1524 0.127)
							(mid 0.137521 0.162921)
							(end 0.1016 0.1778)
						)
						(arc
							(start -0.1016 0.1778)
							(mid -0.137521 0.162921)
							(end -0.1524 0.127)
						)
						(arc
							(start -0.1524 -0.127)
							(mid -0.137521 -0.162921)
							(end -0.1016 -0.1778)
						)
						(arc
							(start 0.1016 -0.1778)
							(mid 0.137521 -0.162921)
							(end 0.1524 -0.127)
						)
					)
					(width 0)
					(fill yes)
				)
			)
		)
	)
	(footprint ""
		(layer "B.Cu")
		(at 54.777132 -123.249182)
		(property "Reference" "R345"
			(at 0 0 0)
			(layer "B.SilkS")
			(hide yes)
			(effects
				(font
					(size 1.27 1.27)
				)
				(justify mirror)
			)
		)
		(property "Value" "0R2J-2-GP"
			(at -0.064008 -3.993896 0)
			(unlocked yes)
			(layer "B.Fab")
			(hide yes)
			(effects
				(font
					(size 1.016 1.016)
					(thickness 0.1524)
				)
				(justify mirror)
			)
		)
		(property "Device Type" "R402H16"
			(at -0.064008 -5.517896 0)
			(unlocked yes)
			(layer "B.Fab")
			(hide yes)
			(effects
				(font
					(size 1.016 1.016)
					(thickness 0.1524)
				)
				(justify mirror)
			)
		)
		(duplicate_pad_numbers_are_jumpers no)
		(fp_line
			(start -0.508 -0.9398)
			(end 0.508 -0.9398)
			(stroke
				(width 0.1524)
				(type default)
			)
			(layer "B.SilkS")
		)
		(fp_line
			(start 0.508 -0.9398)
			(end 0.508 0.9398)
			(stroke
				(width 0.1524)
				(type default)
			)
			(layer "B.SilkS")
		)
		(fp_rect
			(start 0.508 0.9398)
			(end -0.508 -0.9398)
			(stroke
				(width 0)
				(type default)
			)
			(fill no)
			(layer "B.CrtYd")
		)
		(fp_rect
			(start 0.508 0.9398)
			(end -0.508 -0.9398)
			(stroke
				(width 0)
				(type default)
			)
			(fill no)
			(layer "B.Fab")
		)
		(pad "1" smd custom
			(at 0 -0.4445 180)
			(size 0.1397 0.1397)
			(layers "B.Cu" "B.Mask" "B.Paste")
			(net "DEBUG_RST_BTN_N_R")
			(options
				(clearance outline)
				(anchor circle)
			)
			(primitives
				(gr_poly
					(pts
						(arc
							(start -0.1778 0.2794)
							(mid -0.249642 0.249642)
							(end -0.2794 0.1778)
						)
						(arc
							(start -0.2794 -0.1778)
							(mid -0.249642 -0.249642)
							(end -0.1778 -0.2794)
						)
						(arc
							(start 0.1778 -0.2794)
							(mid 0.249642 -0.249642)
							(end 0.2794 -0.1778)
						)
						(arc
							(start 0.2794 0.1778)
							(mid 0.249642 0.249642)
							(end 0.1778 0.2794)
						)
					)
					(width 0)
					(fill yes)
				)
			)
		)
		(pad "2" smd custom
			(at 0 0.4445 180)
			(size 0.1397 0.1397)
			(layers "B.Cu" "B.Mask" "B.Paste")
			(net "DEBUG_RST_BTN_N")
			(options
				(clearance outline)
				(anchor circle)
			)
			(primitives
				(gr_poly
					(pts
						(arc
							(start -0.1778 0.2794)
							(mid -0.249642 0.249642)
							(end -0.2794 0.1778)
						)
						(arc
							(start -0.2794 -0.1778)
							(mid -0.249642 -0.249642)
							(end -0.1778 -0.2794)
						)
						(arc
							(start 0.1778 -0.2794)
							(mid 0.249642 -0.249642)
							(end 0.2794 -0.1778)
						)
						(arc
							(start 0.2794 0.1778)
							(mid 0.249642 0.249642)
							(end 0.1778 0.2794)
						)
					)
					(width 0)
					(fill yes)
				)
			)
		)
	)
	(footprint ""
		(layer "B.Cu")
		(at 204.815948 -51.430682 -90)
		(property "Reference" "C338"
			(at 0 0 90)
			(layer "B.SilkS")
			(hide yes)
			(effects
				(font
					(size 1.27 1.27)
				)
				(justify mirror)
			)
		)
		(property "Value" "SC22U6D3V3MX-9-GP-U"
			(at 0 -2.8194 270)
			(unlocked yes)
			(layer "B.Fab")
			(hide yes)
			(effects
				(font
					(size 1.016 1.016)
					(thickness 0.1524)
				)
				(justify mirror)
			)
		)
		(property "Device Type" "C603H40"
			(at 0 -4.3434 270)
			(unlocked yes)
			(layer "B.Fab")
			(hide yes)
			(effects
				(font
					(size 1.016 1.016)
					(thickness 0.1524)
				)
				(justify mirror)
			)
		)
		(duplicate_pad_numbers_are_jumpers no)
		(fp_line
			(start -0.508 0)
			(end 0.508 0)
			(stroke
				(width 0.2032)
				(type default)
			)
			(layer "B.SilkS")
		)
		(fp_rect
			(start 0.5842 1.3335)
			(end -0.5842 -1.3335)
			(stroke
				(width 0)
				(type default)
			)
			(fill no)
			(layer "B.CrtYd")
		)
		(fp_rect
			(start 0.5842 1.3335)
			(end -0.5842 -1.3335)
			(stroke
				(width 0)
				(type default)
			)
			(fill no)
			(layer "B.Fab")
		)
		(pad "1" smd custom
			(at 0 -0.762 90)
			(size 0.2159 0.2159)
			(layers "B.Cu" "B.Mask" "B.Paste")
			(net "SHELL_PLL_VDD")
			(options
				(clearance outline)
				(anchor circle)
			)
			(primitives
				(gr_poly
					(pts
						(arc
							(start -0.3302 0.4318)
							(mid -0.402042 0.402042)
							(end -0.4318 0.3302)
						)
						(arc
							(start -0.4318 -0.3302)
							(mid -0.402042 -0.402042)
							(end -0.3302 -0.4318)
						)
						(arc
							(start 0.3302 -0.4318)
							(mid 0.402042 -0.402042)
							(end 0.4318 -0.3302)
						)
						(arc
							(start 0.4318 0.3302)
							(mid 0.402042 0.402042)
							(end 0.3302 0.4318)
						)
					)
					(width 0)
					(fill yes)
				)
			)
		)
		(pad "2" smd custom
			(at 0 0.762 90)
			(size 0.2159 0.2159)
			(layers "B.Cu" "B.Mask" "B.Paste")
			(net "GND")
			(options
				(clearance outline)
				(anchor circle)
			)
			(primitives
				(gr_poly
					(pts
						(arc
							(start -0.3302 0.4318)
							(mid -0.402042 0.402042)
							(end -0.4318 0.3302)
						)
						(arc
							(start -0.4318 -0.3302)
							(mid -0.402042 -0.402042)
							(end -0.3302 -0.4318)
						)
						(arc
							(start 0.3302 -0.4318)
							(mid 0.402042 -0.402042)
							(end 0.4318 -0.3302)
						)
						(arc
							(start 0.4318 0.3302)
							(mid 0.402042 0.402042)
							(end 0.3302 0.4318)
						)
					)
					(width 0)
					(fill yes)
				)
			)
		)
	)
	(footprint ""
		(layer "B.Cu")
		(at 93.853 -145.8976 180)
		(property "Reference" "R430"
			(at 0 0 0)
			(layer "B.SilkS")
			(hide yes)
			(effects
				(font
					(size 1.27 1.27)
				)
				(justify mirror)
			)
		)
		(property "Value" "4K7R2F-GP"
			(at -0.064008 -3.993896 180)
			(unlocked yes)
			(layer "B.Fab")
			(hide yes)
			(effects
				(font
					(size 1.016 1.016)
					(thickness 0.1524)
				)
				(justify mirror)
			)
		)
		(property "Device Type" "R402H16"
			(at -0.064008 -5.517896 180)
			(unlocked yes)
			(layer "B.Fab")
			(hide yes)
			(effects
				(font
					(size 1.016 1.016)
					(thickness 0.1524)
				)
				(justify mirror)
			)
		)
		(duplicate_pad_numbers_are_jumpers no)
		(fp_line
			(start 0.508 -0.9398)
			(end 0.508 0.9398)
			(stroke
				(width 0.1524)
				(type default)
			)
			(layer "B.SilkS")
		)
		(fp_line
			(start -0.508 -0.9398)
			(end 0.508 -0.9398)
			(stroke
				(width 0.1524)
				(type default)
			)
			(layer "B.SilkS")
		)
		(fp_rect
			(start 0.508 0.9398)
			(end -0.508 -0.9398)
			(stroke
				(width 0)
				(type default)
			)
			(fill no)
			(layer "B.CrtYd")
		)
		(fp_rect
			(start 0.508 0.9398)
			(end -0.508 -0.9398)
			(stroke
				(width 0)
				(type default)
			)
			(fill no)
			(layer "B.Fab")
		)
		(pad "1" smd custom
			(at 0 -0.4445)
			(size 0.1397 0.1397)
			(layers "B.Cu" "B.Mask" "B.Paste")
			(net "TCA9555_A2")
			(options
				(clearance outline)
				(anchor circle)
			)
			(primitives
				(gr_poly
					(pts
						(arc
							(start -0.1778 0.2794)
							(mid -0.249642 0.249642)
							(end -0.2794 0.1778)
						)
						(arc
							(start -0.2794 -0.1778)
							(mid -0.249642 -0.249642)
							(end -0.1778 -0.2794)
						)
						(arc
							(start 0.1778 -0.2794)
							(mid 0.249642 -0.249642)
							(end 0.2794 -0.1778)
						)
						(arc
							(start 0.2794 0.1778)
							(mid 0.249642 0.249642)
							(end 0.1778 0.2794)
						)
					)
					(width 0)
					(fill yes)
				)
			)
		)
		(pad "2" smd custom
			(at 0 0.4445)
			(size 0.1397 0.1397)
			(layers "B.Cu" "B.Mask" "B.Paste")
			(net "GND")
			(options
				(clearance outline)
				(anchor circle)
			)
			(primitives
				(gr_poly
					(pts
						(arc
							(start -0.1778 0.2794)
							(mid -0.249642 0.249642)
							(end -0.2794 0.1778)
						)
						(arc
							(start -0.2794 -0.1778)
							(mid -0.249642 -0.249642)
							(end -0.1778 -0.2794)
						)
						(arc
							(start 0.1778 -0.2794)
							(mid 0.249642 -0.249642)
							(end 0.2794 -0.1778)
						)
						(arc
							(start 0.2794 0.1778)
							(mid 0.249642 0.249642)
							(end 0.1778 0.2794)
						)
					)
					(width 0)
					(fill yes)
				)
			)
		)
	)
	(footprint ""
		(layer "B.Cu")
		(at 92.8116 -129.4892 180)
		(property "Reference" "C126"
			(at 0 0 0)
			(layer "B.SilkS")
			(hide yes)
			(effects
				(font
					(size 1.27 1.27)
				)
				(justify mirror)
			)
		)
		(property "Value" "SCD1U16V2KX-3GP"
			(at -1.1811 -2.7051 180)
			(unlocked yes)
			(layer "B.Fab")
			(hide yes)
			(effects
				(font
					(size 1.016 1.016)
					(thickness 0.1524)
				)
				(justify mirror)
			)
		)
		(property "Device Type" "C402H22"
			(at -1.1811 -4.2291 180)
			(unlocked yes)
			(layer "B.Fab")
			(hide yes)
			(effects
				(font
					(size 1.016 1.016)
					(thickness 0.1524)
				)
				(justify mirror)
			)
		)
		(duplicate_pad_numbers_are_jumpers no)
		(fp_rect
			(start 0.4318 0.9525)
			(end -0.4318 -0.9525)
			(stroke
				(width 0)
				(type default)
			)
			(fill no)
			(layer "B.CrtYd")
		)
		(fp_rect
			(start 0.4318 0.9525)
			(end -0.4318 -0.9525)
			(stroke
				(width 0)
				(type default)
			)
			(fill no)
			(layer "B.Fab")
		)
		(pad "1" smd custom
			(at 0 -0.4445)
			(size 0.1524 0.1524)
			(layers "B.Cu" "B.Mask" "B.Paste")
			(net "P3V3_STBY")
			(options
				(clearance outline)
				(anchor circle)
			)
			(primitives
				(gr_poly
					(pts
						(arc
							(start 0.3048 0.2032)
							(mid 0.275042 0.275042)
							(end 0.2032 0.3048)
						)
						(arc
							(start -0.2032 0.3048)
							(mid -0.275042 0.275042)
							(end -0.3048 0.2032)
						)
						(arc
							(start -0.3048 -0.2032)
							(mid -0.275042 -0.275042)
							(end -0.2032 -0.3048)
						)
						(arc
							(start 0.2032 -0.3048)
							(mid 0.275042 -0.275042)
							(end 0.3048 -0.2032)
						)
					)
					(width 0)
					(fill yes)
				)
			)
		)
		(pad "2" smd custom
			(at 0 0.4445)
			(size 0.1524 0.1524)
			(layers "B.Cu" "B.Mask" "B.Paste")
			(net "GND")
			(options
				(clearance outline)
				(anchor circle)
			)
			(primitives
				(gr_poly
					(pts
						(arc
							(start 0.3048 0.2032)
							(mid 0.275042 0.275042)
							(end 0.2032 0.3048)
						)
						(arc
							(start -0.2032 0.3048)
							(mid -0.275042 0.275042)
							(end -0.3048 0.2032)
						)
						(arc
							(start -0.3048 -0.2032)
							(mid -0.275042 -0.275042)
							(end -0.2032 -0.3048)
						)
						(arc
							(start 0.2032 -0.3048)
							(mid 0.275042 -0.275042)
							(end 0.3048 -0.2032)
						)
					)
					(width 0)
					(fill yes)
				)
			)
		)
	)
	(footprint ""
		(layer "B.Cu")
		(at 50.4825 -154.3304 90)
		(property "Reference" "R279"
			(at 0 0 90)
			(layer "B.SilkS")
			(hide yes)
			(effects
				(font
					(size 1.27 1.27)
				)
				(justify mirror)
			)
		)
		(property "Value" "0R2J-2-GP"
			(at -0.064008 -3.993896 90)
			(unlocked yes)
			(layer "B.Fab")
			(hide yes)
			(effects
				(font
					(size 1.016 1.016)
					(thickness 0.1524)
				)
				(justify mirror)
			)
		)
		(property "Device Type" "R402H16"
			(at -0.064008 -5.517896 90)
			(unlocked yes)
			(layer "B.Fab")
			(hide yes)
			(effects
				(font
					(size 1.016 1.016)
					(thickness 0.1524)
				)
				(justify mirror)
			)
		)
		(duplicate_pad_numbers_are_jumpers no)
		(fp_line
			(start 0.508 -0.9398)
			(end 0.508 0.9398)
			(stroke
				(width 0.1524)
				(type default)
			)
			(layer "B.SilkS")
		)
		(fp_line
			(start -0.508 -0.9398)
			(end 0.508 -0.9398)
			(stroke
				(width 0.1524)
				(type default)
			)
			(layer "B.SilkS")
		)
		(fp_rect
			(start 0.508 0.9398)
			(end -0.508 -0.9398)
			(stroke
				(width 0)
				(type default)
			)
			(fill no)
			(layer "B.CrtYd")
		)
		(fp_rect
			(start 0.508 0.9398)
			(end -0.508 -0.9398)
			(stroke
				(width 0)
				(type default)
			)
			(fill no)
			(layer "B.Fab")
		)
		(pad "1" smd custom
			(at 0 -0.4445 270)
			(size 0.1397 0.1397)
			(layers "B.Cu" "B.Mask" "B.Paste")
			(net "I2C_MEZZ_OOB_SCL")
			(options
				(clearance outline)
				(anchor circle)
			)
			(primitives
				(gr_poly
					(pts
						(arc
							(start -0.1778 0.2794)
							(mid -0.249642 0.249642)
							(end -0.2794 0.1778)
						)
						(arc
							(start -0.2794 -0.1778)
							(mid -0.249642 -0.249642)
							(end -0.1778 -0.2794)
						)
						(arc
							(start 0.1778 -0.2794)
							(mid 0.249642 -0.249642)
							(end 0.2794 -0.1778)
						)
						(arc
							(start 0.2794 0.1778)
							(mid 0.249642 0.249642)
							(end 0.1778 0.2794)
						)
					)
					(width 0)
					(fill yes)
				)
			)
		)
		(pad "2" smd custom
			(at 0 0.4445 270)
			(size 0.1397 0.1397)
			(layers "B.Cu" "B.Mask" "B.Paste")
			(net "BMC_SMB5_CLK")
			(options
				(clearance outline)
				(anchor circle)
			)
			(primitives
				(gr_poly
					(pts
						(arc
							(start -0.1778 0.2794)
							(mid -0.249642 0.249642)
							(end -0.2794 0.1778)
						)
						(arc
							(start -0.2794 -0.1778)
							(mid -0.249642 -0.249642)
							(end -0.1778 -0.2794)
						)
						(arc
							(start 0.1778 -0.2794)
							(mid 0.249642 -0.249642)
							(end 0.2794 -0.1778)
						)
						(arc
							(start 0.2794 0.1778)
							(mid 0.249642 0.249642)
							(end 0.1778 0.2794)
						)
					)
					(width 0)
					(fill yes)
				)
			)
		)
	)
	(footprint ""
		(layer "B.Cu")
		(at 46.10227 -146.962114)
		(property "Reference" "C108"
			(at 0 0 0)
			(layer "B.SilkS")
			(hide yes)
			(effects
				(font
					(size 1.27 1.27)
				)
				(justify mirror)
			)
		)
		(property "Value" "SC1U16V3KX-5GP"
			(at 0 -2.8194 0)
			(unlocked yes)
			(layer "B.Fab")
			(hide yes)
			(effects
				(font
					(size 1.016 1.016)
					(thickness 0.1524)
				)
				(justify mirror)
			)
		)
		(property "Device Type" "C603H36"
			(at 0 -4.3434 0)
			(unlocked yes)
			(layer "B.Fab")
			(hide yes)
			(effects
				(font
					(size 1.016 1.016)
					(thickness 0.1524)
				)
				(justify mirror)
			)
		)
		(duplicate_pad_numbers_are_jumpers no)
		(fp_line
			(start -0.508 0)
			(end 0.508 0)
			(stroke
				(width 0.2032)
				(type default)
			)
			(layer "B.SilkS")
		)
		(fp_rect
			(start 0.5842 1.3335)
			(end -0.5842 -1.3335)
			(stroke
				(width 0)
				(type default)
			)
			(fill no)
			(layer "B.CrtYd")
		)
		(fp_rect
			(start 0.5842 1.3335)
			(end -0.5842 -1.3335)
			(stroke
				(width 0)
				(type default)
			)
			(fill no)
			(layer "B.Fab")
		)
		(pad "1" smd custom
			(at 0 -0.762 180)
			(size 0.2159 0.2159)
			(layers "B.Cu" "B.Mask" "B.Paste")
			(net "P1V15_STBY")
			(options
				(clearance outline)
				(anchor circle)
			)
			(primitives
				(gr_poly
					(pts
						(arc
							(start -0.3302 0.4318)
							(mid -0.402042 0.402042)
							(end -0.4318 0.3302)
						)
						(arc
							(start -0.4318 -0.3302)
							(mid -0.402042 -0.402042)
							(end -0.3302 -0.4318)
						)
						(arc
							(start 0.3302 -0.4318)
							(mid 0.402042 -0.402042)
							(end 0.4318 -0.3302)
						)
						(arc
							(start 0.4318 0.3302)
							(mid 0.402042 0.402042)
							(end 0.3302 0.4318)
						)
					)
					(width 0)
					(fill yes)
				)
			)
		)
		(pad "2" smd custom
			(at 0 0.762 180)
			(size 0.2159 0.2159)
			(layers "B.Cu" "B.Mask" "B.Paste")
			(net "GND")
			(options
				(clearance outline)
				(anchor circle)
			)
			(primitives
				(gr_poly
					(pts
						(arc
							(start -0.3302 0.4318)
							(mid -0.402042 0.402042)
							(end -0.4318 0.3302)
						)
						(arc
							(start -0.4318 -0.3302)
							(mid -0.402042 -0.402042)
							(end -0.3302 -0.4318)
						)
						(arc
							(start 0.3302 -0.4318)
							(mid 0.402042 -0.402042)
							(end 0.4318 -0.3302)
						)
						(arc
							(start 0.4318 0.3302)
							(mid 0.402042 0.402042)
							(end 0.3302 0.4318)
						)
					)
					(width 0)
					(fill yes)
				)
			)
		)
	)
	(footprint ""
		(layer "B.Cu")
		(at 38.113716 -149.555708 -90)
		(property "Reference" "R318"
			(at 0 0 90)
			(layer "B.SilkS")
			(hide yes)
			(effects
				(font
					(size 1.27 1.27)
				)
				(justify mirror)
			)
		)
		(property "Value" "0R2J-2-GP"
			(at -0.064008 -3.993896 270)
			(unlocked yes)
			(layer "B.Fab")
			(hide yes)
			(effects
				(font
					(size 1.016 1.016)
					(thickness 0.1524)
				)
				(justify mirror)
			)
		)
		(property "Device Type" "R402H16"
			(at -0.064008 -5.517896 270)
			(unlocked yes)
			(layer "B.Fab")
			(hide yes)
			(effects
				(font
					(size 1.016 1.016)
					(thickness 0.1524)
				)
				(justify mirror)
			)
		)
		(duplicate_pad_numbers_are_jumpers no)
		(fp_line
			(start -0.508 -0.9398)
			(end 0.508 -0.9398)
			(stroke
				(width 0.1524)
				(type default)
			)
			(layer "B.SilkS")
		)
		(fp_line
			(start 0.508 -0.9398)
			(end 0.508 0.9398)
			(stroke
				(width 0.1524)
				(type default)
			)
			(layer "B.SilkS")
		)
		(fp_rect
			(start 0.508 0.9398)
			(end -0.508 -0.9398)
			(stroke
				(width 0)
				(type default)
			)
			(fill no)
			(layer "B.CrtYd")
		)
		(fp_rect
			(start 0.508 0.9398)
			(end -0.508 -0.9398)
			(stroke
				(width 0)
				(type default)
			)
			(fill no)
			(layer "B.Fab")
		)
		(pad "1" smd custom
			(at 0 -0.4445 90)
			(size 0.1397 0.1397)
			(layers "B.Cu" "B.Mask" "B.Paste")
			(net "COMP_PWR_EN_R")
			(options
				(clearance outline)
				(anchor circle)
			)
			(primitives
				(gr_poly
					(pts
						(arc
							(start -0.1778 0.2794)
							(mid -0.249642 0.249642)
							(end -0.2794 0.1778)
						)
						(arc
							(start -0.2794 -0.1778)
							(mid -0.249642 -0.249642)
							(end -0.1778 -0.2794)
						)
						(arc
							(start 0.1778 -0.2794)
							(mid 0.249642 -0.249642)
							(end 0.2794 -0.1778)
						)
						(arc
							(start 0.2794 0.1778)
							(mid 0.249642 0.249642)
							(end 0.1778 0.2794)
						)
					)
					(width 0)
					(fill yes)
				)
			)
		)
		(pad "2" smd custom
			(at 0 0.4445 90)
			(size 0.1397 0.1397)
			(layers "B.Cu" "B.Mask" "B.Paste")
			(net "COMP_PWR_EN")
			(options
				(clearance outline)
				(anchor circle)
			)
			(primitives
				(gr_poly
					(pts
						(arc
							(start -0.1778 0.2794)
							(mid -0.249642 0.249642)
							(end -0.2794 0.1778)
						)
						(arc
							(start -0.2794 -0.1778)
							(mid -0.249642 -0.249642)
							(end -0.1778 -0.2794)
						)
						(arc
							(start 0.1778 -0.2794)
							(mid 0.249642 -0.249642)
							(end 0.2794 -0.1778)
						)
						(arc
							(start 0.2794 0.1778)
							(mid 0.249642 0.249642)
							(end 0.1778 0.2794)
						)
					)
					(width 0)
					(fill yes)
				)
			)
		)
	)
	(footprint ""
		(layer "B.Cu")
		(at 12.11199 -142.463266 90)
		(property "Reference" "R212"
			(at 0 0 90)
			(layer "B.SilkS")
			(hide yes)
			(effects
				(font
					(size 1.27 1.27)
				)
				(justify mirror)
			)
		)
		(property "Value" "120R2F-GP"
			(at -0.064008 -3.993896 90)
			(unlocked yes)
			(layer "B.Fab")
			(hide yes)
			(effects
				(font
					(size 1.016 1.016)
					(thickness 0.1524)
				)
				(justify mirror)
			)
		)
		(property "Device Type" "R402H16"
			(at -0.064008 -5.517896 90)
			(unlocked yes)
			(layer "B.Fab")
			(hide yes)
			(effects
				(font
					(size 1.016 1.016)
					(thickness 0.1524)
				)
				(justify mirror)
			)
		)
		(duplicate_pad_numbers_are_jumpers no)
		(fp_line
			(start 0.508 -0.9398)
			(end 0.508 0.9398)
			(stroke
				(width 0.1524)
				(type default)
			)
			(layer "B.SilkS")
		)
		(fp_line
			(start -0.508 -0.9398)
			(end 0.508 -0.9398)
			(stroke
				(width 0.1524)
				(type default)
			)
			(layer "B.SilkS")
		)
		(fp_rect
			(start 0.508 0.9398)
			(end -0.508 -0.9398)
			(stroke
				(width 0)
				(type default)
			)
			(fill no)
			(layer "B.CrtYd")
		)
		(fp_rect
			(start 0.508 0.9398)
			(end -0.508 -0.9398)
			(stroke
				(width 0)
				(type default)
			)
			(fill no)
			(layer "B.Fab")
		)
		(pad "1" smd custom
			(at 0 -0.4445 270)
			(size 0.1397 0.1397)
			(layers "B.Cu" "B.Mask" "B.Paste")
			(net "MEMODT")
			(options
				(clearance outline)
				(anchor circle)
			)
			(primitives
				(gr_poly
					(pts
						(arc
							(start -0.1778 0.2794)
							(mid -0.249642 0.249642)
							(end -0.2794 0.1778)
						)
						(arc
							(start -0.2794 -0.1778)
							(mid -0.249642 -0.249642)
							(end -0.1778 -0.2794)
						)
						(arc
							(start 0.1778 -0.2794)
							(mid 0.249642 -0.249642)
							(end 0.2794 -0.1778)
						)
						(arc
							(start 0.2794 0.1778)
							(mid 0.249642 0.249642)
							(end 0.1778 0.2794)
						)
					)
					(width 0)
					(fill yes)
				)
			)
		)
		(pad "2" smd custom
			(at 0 0.4445 270)
			(size 0.1397 0.1397)
			(layers "B.Cu" "B.Mask" "B.Paste")
			(net "P1V2_STBY")
			(options
				(clearance outline)
				(anchor circle)
			)
			(primitives
				(gr_poly
					(pts
						(arc
							(start -0.1778 0.2794)
							(mid -0.249642 0.249642)
							(end -0.2794 0.1778)
						)
						(arc
							(start -0.2794 -0.1778)
							(mid -0.249642 -0.249642)
							(end -0.1778 -0.2794)
						)
						(arc
							(start 0.1778 -0.2794)
							(mid 0.249642 -0.249642)
							(end 0.2794 -0.1778)
						)
						(arc
							(start 0.2794 0.1778)
							(mid 0.249642 0.249642)
							(end 0.1778 0.2794)
						)
					)
					(width 0)
					(fill yes)
				)
			)
		)
	)
	(footprint ""
		(layer "B.Cu")
		(at 55.575454 -145.058384 90)
		(property "Reference" "TP83"
			(at 0 0 90)
			(layer "B.SilkS")
			(hide yes)
			(effects
				(font
					(size 1.27 1.27)
				)
				(justify mirror)
			)
		)
		(property "Value" "TPAD28-2-GP"
			(at 0.0127 -1.6637 90)
			(unlocked yes)
			(layer "B.Fab")
			(hide yes)
			(effects
				(font
					(size 1.016 1.016)
					(thickness 0.1524)
				)
				(justify mirror)
			)
		)
		(property "Device Type" "TPAD28"
			(at 0.0127 -3.1877 90)
			(unlocked yes)
			(layer "B.Fab")
			(hide yes)
			(effects
				(font
					(size 1.016 1.016)
					(thickness 0.1524)
				)
				(justify mirror)
			)
		)
		(duplicate_pad_numbers_are_jumpers no)
		(fp_poly
			(pts
				(arc
					(start 0 0.3556)
					(mid 0 -0.3556)
					(end 0 0.3556)
				)
			)
			(stroke
				(width 0)
				(type default)
			)
			(fill no)
			(layer "B.CrtYd")
		)
		(fp_poly
			(pts
				(arc
					(start 0 0.6096)
					(mid 0 -0.6096)
					(end 0 0.6096)
				)
			)
			(stroke
				(width 0)
				(type default)
			)
			(fill no)
			(layer "B.Fab")
		)
		(pad "1" smd circle
			(at 0 0 270)
			(size 0.7112 0.7112)
			(layers "B.Cu" "B.Mask" "B.Paste")
			(net "JTAG_BMC_TDO")
		)
	)
	(footprint ""
		(layer "B.Cu")
		(at 95.874078 -176.581562 -90)
		(property "Reference" "R100"
			(at 0 0 90)
			(layer "B.SilkS")
			(hide yes)
			(effects
				(font
					(size 1.27 1.27)
				)
				(justify mirror)
			)
		)
		(property "Value" "0R2J-2-GP"
			(at -0.064008 -3.993896 270)
			(unlocked yes)
			(layer "B.Fab")
			(hide yes)
			(effects
				(font
					(size 1.016 1.016)
					(thickness 0.1524)
				)
				(justify mirror)
			)
		)
		(property "Device Type" "R402H16"
			(at -0.064008 -5.517896 270)
			(unlocked yes)
			(layer "B.Fab")
			(hide yes)
			(effects
				(font
					(size 1.016 1.016)
					(thickness 0.1524)
				)
				(justify mirror)
			)
		)
		(duplicate_pad_numbers_are_jumpers no)
		(fp_line
			(start -0.508 -0.9398)
			(end 0.508 -0.9398)
			(stroke
				(width 0.1524)
				(type default)
			)
			(layer "B.SilkS")
		)
		(fp_line
			(start 0.508 -0.9398)
			(end 0.508 0.9398)
			(stroke
				(width 0.1524)
				(type default)
			)
			(layer "B.SilkS")
		)
		(fp_rect
			(start 0.508 0.9398)
			(end -0.508 -0.9398)
			(stroke
				(width 0)
				(type default)
			)
			(fill no)
			(layer "B.CrtYd")
		)
		(fp_rect
			(start 0.508 0.9398)
			(end -0.508 -0.9398)
			(stroke
				(width 0)
				(type default)
			)
			(fill no)
			(layer "B.Fab")
		)
		(pad "1" smd custom
			(at 0 -0.4445 90)
			(size 0.1397 0.1397)
			(layers "B.Cu" "B.Mask" "B.Paste")
			(net "I2C_BMC_COMP_ALERT_N_R")
			(options
				(clearance outline)
				(anchor circle)
			)
			(primitives
				(gr_poly
					(pts
						(arc
							(start -0.1778 0.2794)
							(mid -0.249642 0.249642)
							(end -0.2794 0.1778)
						)
						(arc
							(start -0.2794 -0.1778)
							(mid -0.249642 -0.249642)
							(end -0.1778 -0.2794)
						)
						(arc
							(start 0.1778 -0.2794)
							(mid 0.249642 -0.249642)
							(end 0.2794 -0.1778)
						)
						(arc
							(start 0.2794 0.1778)
							(mid 0.249642 0.249642)
							(end 0.1778 0.2794)
						)
					)
					(width 0)
					(fill yes)
				)
			)
		)
		(pad "2" smd custom
			(at 0 0.4445 90)
			(size 0.1397 0.1397)
			(layers "B.Cu" "B.Mask" "B.Paste")
			(net "I2C_BMC_COMP_ALERT_N")
			(options
				(clearance outline)
				(anchor circle)
			)
			(primitives
				(gr_poly
					(pts
						(arc
							(start -0.1778 0.2794)
							(mid -0.249642 0.249642)
							(end -0.2794 0.1778)
						)
						(arc
							(start -0.2794 -0.1778)
							(mid -0.249642 -0.249642)
							(end -0.1778 -0.2794)
						)
						(arc
							(start 0.1778 -0.2794)
							(mid 0.249642 -0.249642)
							(end 0.2794 -0.1778)
						)
						(arc
							(start 0.2794 0.1778)
							(mid 0.249642 0.249642)
							(end 0.1778 0.2794)
						)
					)
					(width 0)
					(fill yes)
				)
			)
		)
	)
	(footprint ""
		(layer "B.Cu")
		(at 54.229 -161.163 90)
		(property "Reference" "R404"
			(at 0 0 90)
			(layer "B.SilkS")
			(hide yes)
			(effects
				(font
					(size 1.27 1.27)
				)
				(justify mirror)
			)
		)
		(property "Value" "1KR2F-3-GP"
			(at -0.064008 -3.993896 90)
			(unlocked yes)
			(layer "B.Fab")
			(hide yes)
			(effects
				(font
					(size 1.016 1.016)
					(thickness 0.1524)
				)
				(justify mirror)
			)
		)
		(property "Device Type" "R402H16"
			(at -0.064008 -5.517896 90)
			(unlocked yes)
			(layer "B.Fab")
			(hide yes)
			(effects
				(font
					(size 1.016 1.016)
					(thickness 0.1524)
				)
				(justify mirror)
			)
		)
		(duplicate_pad_numbers_are_jumpers no)
		(fp_line
			(start 0.508 -0.9398)
			(end 0.508 0.9398)
			(stroke
				(width 0.1524)
				(type default)
			)
			(layer "B.SilkS")
		)
		(fp_line
			(start -0.508 -0.9398)
			(end 0.508 -0.9398)
			(stroke
				(width 0.1524)
				(type default)
			)
			(layer "B.SilkS")
		)
		(fp_rect
			(start 0.508 0.9398)
			(end -0.508 -0.9398)
			(stroke
				(width 0)
				(type default)
			)
			(fill no)
			(layer "B.CrtYd")
		)
		(fp_rect
			(start 0.508 0.9398)
			(end -0.508 -0.9398)
			(stroke
				(width 0)
				(type default)
			)
			(fill no)
			(layer "B.Fab")
		)
		(pad "1" smd custom
			(at 0 -0.4445 270)
			(size 0.1397 0.1397)
			(layers "B.Cu" "B.Mask" "B.Paste")
			(net "ADC_12V")
			(options
				(clearance outline)
				(anchor circle)
			)
			(primitives
				(gr_poly
					(pts
						(arc
							(start -0.1778 0.2794)
							(mid -0.249642 0.249642)
							(end -0.2794 0.1778)
						)
						(arc
							(start -0.2794 -0.1778)
							(mid -0.249642 -0.249642)
							(end -0.1778 -0.2794)
						)
						(arc
							(start 0.1778 -0.2794)
							(mid 0.249642 -0.249642)
							(end 0.2794 -0.1778)
						)
						(arc
							(start 0.2794 0.1778)
							(mid 0.249642 0.249642)
							(end 0.1778 0.2794)
						)
					)
					(width 0)
					(fill yes)
				)
			)
		)
		(pad "2" smd custom
			(at 0 0.4445 270)
			(size 0.1397 0.1397)
			(layers "B.Cu" "B.Mask" "B.Paste")
			(net "GND")
			(options
				(clearance outline)
				(anchor circle)
			)
			(primitives
				(gr_poly
					(pts
						(arc
							(start -0.1778 0.2794)
							(mid -0.249642 0.249642)
							(end -0.2794 0.1778)
						)
						(arc
							(start -0.2794 -0.1778)
							(mid -0.249642 -0.249642)
							(end -0.1778 -0.2794)
						)
						(arc
							(start 0.1778 -0.2794)
							(mid 0.249642 -0.249642)
							(end 0.2794 -0.1778)
						)
						(arc
							(start 0.2794 0.1778)
							(mid 0.249642 0.249642)
							(end 0.1778 0.2794)
						)
					)
					(width 0)
					(fill yes)
				)
			)
		)
	)
	(footprint ""
		(layer "B.Cu")
		(at 45.2374 -139.3698)
		(property "Reference" "TP21"
			(at 0 0 0)
			(layer "B.SilkS")
			(hide yes)
			(effects
				(font
					(size 1.27 1.27)
				)
				(justify mirror)
			)
		)
		(property "Value" "TPAD28-2-GP"
			(at 0.0127 -1.6637 0)
			(unlocked yes)
			(layer "B.Fab")
			(hide yes)
			(effects
				(font
					(size 1.016 1.016)
					(thickness 0.1524)
				)
				(justify mirror)
			)
		)
		(property "Device Type" "TPAD28"
			(at 0.0127 -3.1877 0)
			(unlocked yes)
			(layer "B.Fab")
			(hide yes)
			(effects
				(font
					(size 1.016 1.016)
					(thickness 0.1524)
				)
				(justify mirror)
			)
		)
		(duplicate_pad_numbers_are_jumpers no)
		(fp_poly
			(pts
				(arc
					(start 0.3556 0)
					(mid -0.3556 0)
					(end 0.3556 0)
				)
			)
			(stroke
				(width 0)
				(type default)
			)
			(fill no)
			(layer "B.CrtYd")
		)
		(fp_poly
			(pts
				(arc
					(start 0.6096 0)
					(mid -0.6096 0)
					(end 0.6096 0)
				)
			)
			(stroke
				(width 0)
				(type default)
			)
			(fill no)
			(layer "B.Fab")
		)
		(pad "1" smd circle
			(at 0 0 180)
			(size 0.7112 0.7112)
			(layers "B.Cu" "B.Mask" "B.Paste")
			(net "TP_M2_2_ALERT#")
		)
	)
	(footprint ""
		(layer "B.Cu")
		(at 191.68999 -21.844 -90)
		(property "Reference" "C486"
			(at 0 0 90)
			(layer "B.SilkS")
			(hide yes)
			(effects
				(font
					(size 1.27 1.27)
				)
				(justify mirror)
			)
		)
		(property "Value" "SCD01U16V1KX-GP"
			(at 2.8321 -1.7399 270)
			(unlocked yes)
			(layer "B.Fab")
			(hide yes)
			(effects
				(font
					(size 1.016 1.016)
					(thickness 0.1524)
				)
				(justify mirror)
			)
		)
		(property "Device Type" "C0201H13"
			(at 2.8321 -3.2639 270)
			(unlocked yes)
			(layer "B.Fab")
			(hide yes)
			(effects
				(font
					(size 1.016 1.016)
					(thickness 0.1524)
				)
				(justify mirror)
			)
		)
		(duplicate_pad_numbers_are_jumpers no)
		(fp_rect
			(start 0.2794 0.6477)
			(end -0.2794 -0.6477)
			(stroke
				(width 0)
				(type default)
			)
			(fill no)
			(layer "B.CrtYd")
		)
		(fp_rect
			(start 0.2794 0.6477)
			(end -0.2794 -0.6477)
			(stroke
				(width 0)
				(type default)
			)
			(fill no)
			(layer "B.Fab")
		)
		(pad "1" smd custom
			(at 0 -0.2794 90)
			(size 0.0762 0.0762)
			(layers "B.Cu" "B.Mask" "B.Paste")
			(net "PHY_CON_A_TO_IOC_1_DP")
			(options
				(clearance outline)
				(anchor circle)
			)
			(primitives
				(gr_poly
					(pts
						(arc
							(start 0.1524 0.127)
							(mid 0.137521 0.162921)
							(end 0.1016 0.1778)
						)
						(arc
							(start -0.1016 0.1778)
							(mid -0.137521 0.162921)
							(end -0.1524 0.127)
						)
						(arc
							(start -0.1524 -0.127)
							(mid -0.137521 -0.162921)
							(end -0.1016 -0.1778)
						)
						(arc
							(start 0.1016 -0.1778)
							(mid 0.137521 -0.162921)
							(end 0.1524 -0.127)
						)
					)
					(width 0)
					(fill yes)
				)
			)
		)
		(pad "2" smd custom
			(at 0 0.2794 90)
			(size 0.0762 0.0762)
			(layers "B.Cu" "B.Mask" "B.Paste")
			(net "PHY_CON_A_TO_IOC_1_DP_C")
			(options
				(clearance outline)
				(anchor circle)
			)
			(primitives
				(gr_poly
					(pts
						(arc
							(start 0.1524 0.127)
							(mid 0.137521 0.162921)
							(end 0.1016 0.1778)
						)
						(arc
							(start -0.1016 0.1778)
							(mid -0.137521 0.162921)
							(end -0.1524 0.127)
						)
						(arc
							(start -0.1524 -0.127)
							(mid -0.137521 -0.162921)
							(end -0.1016 -0.1778)
						)
						(arc
							(start 0.1016 -0.1778)
							(mid 0.137521 -0.162921)
							(end 0.1524 -0.127)
						)
					)
					(width 0)
					(fill yes)
				)
			)
		)
	)
	(footprint ""
		(layer "B.Cu")
		(at 42.418 -131.7752 180)
		(property "Reference" "R284"
			(at 0 0 0)
			(layer "B.SilkS")
			(hide yes)
			(effects
				(font
					(size 1.27 1.27)
				)
				(justify mirror)
			)
		)
		(property "Value" "33R2F-3-GP"
			(at -0.064008 -3.993896 180)
			(unlocked yes)
			(layer "B.Fab")
			(hide yes)
			(effects
				(font
					(size 1.016 1.016)
					(thickness 0.1524)
				)
				(justify mirror)
			)
		)
		(property "Device Type" "R402H16"
			(at -0.064008 -5.517896 180)
			(unlocked yes)
			(layer "B.Fab")
			(hide yes)
			(effects
				(font
					(size 1.016 1.016)
					(thickness 0.1524)
				)
				(justify mirror)
			)
		)
		(duplicate_pad_numbers_are_jumpers no)
		(fp_line
			(start 0.508 -0.9398)
			(end 0.508 0.9398)
			(stroke
				(width 0.1524)
				(type default)
			)
			(layer "B.SilkS")
		)
		(fp_line
			(start -0.508 -0.9398)
			(end 0.508 -0.9398)
			(stroke
				(width 0.1524)
				(type default)
			)
			(layer "B.SilkS")
		)
		(fp_rect
			(start 0.508 0.9398)
			(end -0.508 -0.9398)
			(stroke
				(width 0)
				(type default)
			)
			(fill no)
			(layer "B.CrtYd")
		)
		(fp_rect
			(start 0.508 0.9398)
			(end -0.508 -0.9398)
			(stroke
				(width 0)
				(type default)
			)
			(fill no)
			(layer "B.Fab")
		)
		(pad "1" smd custom
			(at 0 -0.4445)
			(size 0.1397 0.1397)
			(layers "B.Cu" "B.Mask" "B.Paste")
			(net "BMC_SPI_MOSI_R")
			(options
				(clearance outline)
				(anchor circle)
			)
			(primitives
				(gr_poly
					(pts
						(arc
							(start -0.1778 0.2794)
							(mid -0.249642 0.249642)
							(end -0.2794 0.1778)
						)
						(arc
							(start -0.2794 -0.1778)
							(mid -0.249642 -0.249642)
							(end -0.1778 -0.2794)
						)
						(arc
							(start 0.1778 -0.2794)
							(mid 0.249642 -0.249642)
							(end 0.2794 -0.1778)
						)
						(arc
							(start 0.2794 0.1778)
							(mid 0.249642 0.249642)
							(end 0.1778 0.2794)
						)
					)
					(width 0)
					(fill yes)
				)
			)
		)
		(pad "2" smd custom
			(at 0 0.4445)
			(size 0.1397 0.1397)
			(layers "B.Cu" "B.Mask" "B.Paste")
			(net "BMC_SPI_MOSI")
			(options
				(clearance outline)
				(anchor circle)
			)
			(primitives
				(gr_poly
					(pts
						(arc
							(start -0.1778 0.2794)
							(mid -0.249642 0.249642)
							(end -0.2794 0.1778)
						)
						(arc
							(start -0.2794 -0.1778)
							(mid -0.249642 -0.249642)
							(end -0.1778 -0.2794)
						)
						(arc
							(start 0.1778 -0.2794)
							(mid 0.249642 -0.249642)
							(end 0.2794 -0.1778)
						)
						(arc
							(start 0.2794 0.1778)
							(mid 0.249642 0.249642)
							(end 0.1778 0.2794)
						)
					)
					(width 0)
					(fill yes)
				)
			)
		)
	)
	(footprint ""
		(layer "B.Cu")
		(at 39.457122 -154.728672)
		(property "Reference" "TP64"
			(at 0 0 0)
			(layer "B.SilkS")
			(hide yes)
			(effects
				(font
					(size 1.27 1.27)
				)
				(justify mirror)
			)
		)
		(property "Value" "TPAD28-2-GP"
			(at 0.0127 -1.6637 0)
			(unlocked yes)
			(layer "B.Fab")
			(hide yes)
			(effects
				(font
					(size 1.016 1.016)
					(thickness 0.1524)
				)
				(justify mirror)
			)
		)
		(property "Device Type" "TPAD28"
			(at 0.0127 -3.1877 0)
			(unlocked yes)
			(layer "B.Fab")
			(hide yes)
			(effects
				(font
					(size 1.016 1.016)
					(thickness 0.1524)
				)
				(justify mirror)
			)
		)
		(duplicate_pad_numbers_are_jumpers no)
		(fp_poly
			(pts
				(arc
					(start 0.3556 0)
					(mid -0.3556 0)
					(end 0.3556 0)
				)
			)
			(stroke
				(width 0)
				(type default)
			)
			(fill no)
			(layer "B.CrtYd")
		)
		(fp_poly
			(pts
				(arc
					(start 0.6096 0)
					(mid -0.6096 0)
					(end 0.6096 0)
				)
			)
			(stroke
				(width 0)
				(type default)
			)
			(fill no)
			(layer "B.Fab")
		)
		(pad "1" smd circle
			(at 0 0 180)
			(size 0.7112 0.7112)
			(layers "B.Cu" "B.Mask" "B.Paste")
			(net "TP_BMC_GPION4")
		)
	)
	(footprint ""
		(layer "B.Cu")
		(at 52.2097 -160.8963 -90)
		(property "Reference" "C121"
			(at 0 0 90)
			(layer "B.SilkS")
			(hide yes)
			(effects
				(font
					(size 1.27 1.27)
				)
				(justify mirror)
			)
		)
		(property "Value" "SCD1U25V2KX-2-GP"
			(at -1.1811 -2.7051 270)
			(unlocked yes)
			(layer "B.Fab")
			(hide yes)
			(effects
				(font
					(size 1.016 1.016)
					(thickness 0.1524)
				)
				(justify mirror)
			)
		)
		(property "Device Type" "C402H22"
			(at -1.1811 -4.2291 270)
			(unlocked yes)
			(layer "B.Fab")
			(hide yes)
			(effects
				(font
					(size 1.016 1.016)
					(thickness 0.1524)
				)
				(justify mirror)
			)
		)
		(duplicate_pad_numbers_are_jumpers no)
		(fp_rect
			(start 0.4318 0.9525)
			(end -0.4318 -0.9525)
			(stroke
				(width 0)
				(type default)
			)
			(fill no)
			(layer "B.CrtYd")
		)
		(fp_rect
			(start 0.4318 0.9525)
			(end -0.4318 -0.9525)
			(stroke
				(width 0)
				(type default)
			)
			(fill no)
			(layer "B.Fab")
		)
		(pad "1" smd custom
			(at 0 -0.4445 90)
			(size 0.1524 0.1524)
			(layers "B.Cu" "B.Mask" "B.Paste")
			(net "ADC_P1V5")
			(options
				(clearance outline)
				(anchor circle)
			)
			(primitives
				(gr_poly
					(pts
						(arc
							(start 0.3048 0.2032)
							(mid 0.275042 0.275042)
							(end 0.2032 0.3048)
						)
						(arc
							(start -0.2032 0.3048)
							(mid -0.275042 0.275042)
							(end -0.3048 0.2032)
						)
						(arc
							(start -0.3048 -0.2032)
							(mid -0.275042 -0.275042)
							(end -0.2032 -0.3048)
						)
						(arc
							(start 0.2032 -0.3048)
							(mid 0.275042 -0.275042)
							(end 0.3048 -0.2032)
						)
					)
					(width 0)
					(fill yes)
				)
			)
		)
		(pad "2" smd custom
			(at 0 0.4445 90)
			(size 0.1524 0.1524)
			(layers "B.Cu" "B.Mask" "B.Paste")
			(net "GND")
			(options
				(clearance outline)
				(anchor circle)
			)
			(primitives
				(gr_poly
					(pts
						(arc
							(start 0.3048 0.2032)
							(mid 0.275042 0.275042)
							(end 0.2032 0.3048)
						)
						(arc
							(start -0.2032 0.3048)
							(mid -0.275042 0.275042)
							(end -0.3048 0.2032)
						)
						(arc
							(start -0.3048 -0.2032)
							(mid -0.275042 -0.275042)
							(end -0.2032 -0.3048)
						)
						(arc
							(start 0.2032 -0.3048)
							(mid 0.275042 -0.275042)
							(end 0.3048 -0.2032)
						)
					)
					(width 0)
					(fill yes)
				)
			)
		)
	)
	(footprint ""
		(layer "B.Cu")
		(at 10.20699 -141.008862 90)
		(property "Reference" "R254"
			(at 0 0 90)
			(layer "B.SilkS")
			(hide yes)
			(effects
				(font
					(size 1.27 1.27)
				)
				(justify mirror)
			)
		)
		(property "Value" "120R2F-GP"
			(at -0.064008 -3.993896 90)
			(unlocked yes)
			(layer "B.Fab")
			(hide yes)
			(effects
				(font
					(size 1.016 1.016)
					(thickness 0.1524)
				)
				(justify mirror)
			)
		)
		(property "Device Type" "R402H16"
			(at -0.064008 -5.517896 90)
			(unlocked yes)
			(layer "B.Fab")
			(hide yes)
			(effects
				(font
					(size 1.016 1.016)
					(thickness 0.1524)
				)
				(justify mirror)
			)
		)
		(duplicate_pad_numbers_are_jumpers no)
		(fp_line
			(start 0.508 -0.9398)
			(end 0.508 0.9398)
			(stroke
				(width 0.1524)
				(type default)
			)
			(layer "B.SilkS")
		)
		(fp_line
			(start -0.508 -0.9398)
			(end 0.508 -0.9398)
			(stroke
				(width 0.1524)
				(type default)
			)
			(layer "B.SilkS")
		)
		(fp_rect
			(start 0.508 0.9398)
			(end -0.508 -0.9398)
			(stroke
				(width 0)
				(type default)
			)
			(fill no)
			(layer "B.CrtYd")
		)
		(fp_rect
			(start 0.508 0.9398)
			(end -0.508 -0.9398)
			(stroke
				(width 0)
				(type default)
			)
			(fill no)
			(layer "B.Fab")
		)
		(pad "1" smd custom
			(at 0 -0.4445 270)
			(size 0.1397 0.1397)
			(layers "B.Cu" "B.Mask" "B.Paste")
			(net "GND")
			(options
				(clearance outline)
				(anchor circle)
			)
			(primitives
				(gr_poly
					(pts
						(arc
							(start -0.1778 0.2794)
							(mid -0.249642 0.249642)
							(end -0.2794 0.1778)
						)
						(arc
							(start -0.2794 -0.1778)
							(mid -0.249642 -0.249642)
							(end -0.1778 -0.2794)
						)
						(arc
							(start 0.1778 -0.2794)
							(mid 0.249642 -0.249642)
							(end 0.2794 -0.1778)
						)
						(arc
							(start 0.2794 0.1778)
							(mid 0.249642 0.249642)
							(end 0.1778 0.2794)
						)
					)
					(width 0)
					(fill yes)
				)
			)
		)
		(pad "2" smd custom
			(at 0 0.4445 270)
			(size 0.1397 0.1397)
			(layers "B.Cu" "B.Mask" "B.Paste")
			(net "MEMA_10")
			(options
				(clearance outline)
				(anchor circle)
			)
			(primitives
				(gr_poly
					(pts
						(arc
							(start -0.1778 0.2794)
							(mid -0.249642 0.249642)
							(end -0.2794 0.1778)
						)
						(arc
							(start -0.2794 -0.1778)
							(mid -0.249642 -0.249642)
							(end -0.1778 -0.2794)
						)
						(arc
							(start 0.1778 -0.2794)
							(mid 0.249642 -0.249642)
							(end 0.2794 -0.1778)
						)
						(arc
							(start 0.2794 0.1778)
							(mid 0.249642 0.249642)
							(end 0.1778 0.2794)
						)
					)
					(width 0)
					(fill yes)
				)
			)
		)
	)
	(footprint ""
		(layer "B.Cu")
		(at 200.3933 -58.7629 -90)
		(property "Reference" "C443"
			(at 0 0 90)
			(layer "B.SilkS")
			(hide yes)
			(effects
				(font
					(size 1.27 1.27)
				)
				(justify mirror)
			)
		)
		(property "Value" "SCD1U16V2KX-3GP"
			(at -1.1811 -2.7051 270)
			(unlocked yes)
			(layer "B.Fab")
			(hide yes)
			(effects
				(font
					(size 1.016 1.016)
					(thickness 0.1524)
				)
				(justify mirror)
			)
		)
		(property "Device Type" "C402H22"
			(at -1.1811 -4.2291 270)
			(unlocked yes)
			(layer "B.Fab")
			(hide yes)
			(effects
				(font
					(size 1.016 1.016)
					(thickness 0.1524)
				)
				(justify mirror)
			)
		)
		(duplicate_pad_numbers_are_jumpers no)
		(fp_rect
			(start 0.4318 0.9525)
			(end -0.4318 -0.9525)
			(stroke
				(width 0)
				(type default)
			)
			(fill no)
			(layer "B.CrtYd")
		)
		(fp_rect
			(start 0.4318 0.9525)
			(end -0.4318 -0.9525)
			(stroke
				(width 0)
				(type default)
			)
			(fill no)
			(layer "B.Fab")
		)
		(pad "1" smd custom
			(at 0 -0.4445 90)
			(size 0.1524 0.1524)
			(layers "B.Cu" "B.Mask" "B.Paste")
			(net "P1V8")
			(options
				(clearance outline)
				(anchor circle)
			)
			(primitives
				(gr_poly
					(pts
						(arc
							(start 0.3048 0.2032)
							(mid 0.275042 0.275042)
							(end 0.2032 0.3048)
						)
						(arc
							(start -0.2032 0.3048)
							(mid -0.275042 0.275042)
							(end -0.3048 0.2032)
						)
						(arc
							(start -0.3048 -0.2032)
							(mid -0.275042 -0.275042)
							(end -0.2032 -0.3048)
						)
						(arc
							(start 0.2032 -0.3048)
							(mid 0.275042 -0.275042)
							(end 0.3048 -0.2032)
						)
					)
					(width 0)
					(fill yes)
				)
			)
		)
		(pad "2" smd custom
			(at 0 0.4445 90)
			(size 0.1524 0.1524)
			(layers "B.Cu" "B.Mask" "B.Paste")
			(net "GND")
			(options
				(clearance outline)
				(anchor circle)
			)
			(primitives
				(gr_poly
					(pts
						(arc
							(start 0.3048 0.2032)
							(mid 0.275042 0.275042)
							(end 0.2032 0.3048)
						)
						(arc
							(start -0.2032 0.3048)
							(mid -0.275042 0.275042)
							(end -0.3048 0.2032)
						)
						(arc
							(start -0.3048 -0.2032)
							(mid -0.275042 -0.275042)
							(end -0.2032 -0.3048)
						)
						(arc
							(start 0.2032 -0.3048)
							(mid 0.275042 -0.275042)
							(end 0.3048 -0.2032)
						)
					)
					(width 0)
					(fill yes)
				)
			)
		)
	)
	(footprint ""
		(layer "B.Cu")
		(at 90.86088 -175.768 90)
		(property "Reference" "U12"
			(at 0 0 90)
			(layer "B.SilkS")
			(hide yes)
			(effects
				(font
					(size 1.27 1.27)
				)
				(justify mirror)
			)
		)
		(property "Value" "NX3L1G66GW-GP"
			(at 2.3368 -8.6868 90)
			(unlocked yes)
			(layer "B.Fab")
			(hide yes)
			(effects
				(font
					(size 1.016 1.016)
					(thickness 0.1524)
				)
				(justify mirror)
			)
		)
		(property "Device Type" "SC70-5H44"
			(at 2.3114 -10.414 90)
			(unlocked yes)
			(layer "B.Fab")
			(hide yes)
			(effects
				(font
					(size 1.016 1.016)
					(thickness 0.1524)
				)
				(justify mirror)
			)
		)
		(duplicate_pad_numbers_are_jumpers no)
		(fp_line
			(start -0.6604 -1.8034)
			(end -1.3843 -1.8034)
			(stroke
				(width 0.3302)
				(type default)
			)
			(layer "B.SilkS")
		)
		(fp_line
			(start -1.3843 -1.8034)
			(end -1.3843 -1.1176)
			(stroke
				(width 0.3302)
				(type default)
			)
			(layer "B.SilkS")
		)
		(fp_line
			(start 1.27 -1.7018)
			(end -1.27 -1.7018)
			(stroke
				(width 0.1524)
				(type default)
			)
			(layer "B.SilkS")
		)
		(fp_line
			(start -1.27 -1.7018)
			(end -1.27 1.7018)
			(stroke
				(width 0.1524)
				(type default)
			)
			(layer "B.SilkS")
		)
		(fp_line
			(start 1.27 1.7018)
			(end 1.27 -1.7018)
			(stroke
				(width 0.1524)
				(type default)
			)
			(layer "B.SilkS")
		)
		(fp_line
			(start -1.27 1.7018)
			(end 1.27 1.7018)
			(stroke
				(width 0.1524)
				(type default)
			)
			(layer "B.SilkS")
		)
		(fp_rect
			(start 1.524 1.9558)
			(end -1.524 -1.9558)
			(stroke
				(width 0)
				(type default)
			)
			(fill no)
			(layer "B.CrtYd")
		)
		(fp_poly
			(pts
				(xy 1.524 -1.9558) (xy -1.524 -1.9558) (xy -1.524 1.9558) (xy 1.524 1.9558)
			)
			(stroke
				(width 0)
				(type default)
			)
			(fill no)
			(layer "B.Fab")
		)
		(pad "1" smd rect
			(at -0.65024 -0.8255 270)
			(size 0.4064 1.2192)
			(layers "B.Cu" "B.Mask" "B.Paste")
			(net "I2C_BMC_COMP_SCL_R")
		)
		(pad "2" smd rect
			(at 0 -0.8255 270)
			(size 0.4064 1.2192)
			(layers "B.Cu" "B.Mask" "B.Paste")
			(net "I2C_BMC_COMP_SCL_OUT")
		)
		(pad "3" smd rect
			(at 0.65024 -0.8255 270)
			(size 0.4064 1.2192)
			(layers "B.Cu" "B.Mask" "B.Paste")
			(net "GND")
		)
		(pad "4" smd rect
			(at 0.65024 0.8255 270)
			(size 0.4064 1.2192)
			(layers "B.Cu" "B.Mask" "B.Paste")
			(net "COMP_PWR_EN")
		)
		(pad "5" smd rect
			(at -0.65024 0.8255 270)
			(size 0.4064 1.2192)
			(layers "B.Cu" "B.Mask" "B.Paste")
			(net "P3V3_STBY")
		)
	)
	(footprint ""
		(layer "B.Cu")
		(at 200.3933 -59.63158 -90)
		(property "Reference" "C440"
			(at 0 0 90)
			(layer "B.SilkS")
			(hide yes)
			(effects
				(font
					(size 1.27 1.27)
				)
				(justify mirror)
			)
		)
		(property "Value" "SCD1U16V2KX-3GP"
			(at -1.1811 -2.7051 270)
			(unlocked yes)
			(layer "B.Fab")
			(hide yes)
			(effects
				(font
					(size 1.016 1.016)
					(thickness 0.1524)
				)
				(justify mirror)
			)
		)
		(property "Device Type" "C402H22"
			(at -1.1811 -4.2291 270)
			(unlocked yes)
			(layer "B.Fab")
			(hide yes)
			(effects
				(font
					(size 1.016 1.016)
					(thickness 0.1524)
				)
				(justify mirror)
			)
		)
		(duplicate_pad_numbers_are_jumpers no)
		(fp_rect
			(start 0.4318 0.9525)
			(end -0.4318 -0.9525)
			(stroke
				(width 0)
				(type default)
			)
			(fill no)
			(layer "B.CrtYd")
		)
		(fp_rect
			(start 0.4318 0.9525)
			(end -0.4318 -0.9525)
			(stroke
				(width 0)
				(type default)
			)
			(fill no)
			(layer "B.Fab")
		)
		(pad "1" smd custom
			(at 0 -0.4445 90)
			(size 0.1524 0.1524)
			(layers "B.Cu" "B.Mask" "B.Paste")
			(net "P1V8")
			(options
				(clearance outline)
				(anchor circle)
			)
			(primitives
				(gr_poly
					(pts
						(arc
							(start 0.3048 0.2032)
							(mid 0.275042 0.275042)
							(end 0.2032 0.3048)
						)
						(arc
							(start -0.2032 0.3048)
							(mid -0.275042 0.275042)
							(end -0.3048 0.2032)
						)
						(arc
							(start -0.3048 -0.2032)
							(mid -0.275042 -0.275042)
							(end -0.2032 -0.3048)
						)
						(arc
							(start 0.2032 -0.3048)
							(mid 0.275042 -0.275042)
							(end 0.3048 -0.2032)
						)
					)
					(width 0)
					(fill yes)
				)
			)
		)
		(pad "2" smd custom
			(at 0 0.4445 90)
			(size 0.1524 0.1524)
			(layers "B.Cu" "B.Mask" "B.Paste")
			(net "GND")
			(options
				(clearance outline)
				(anchor circle)
			)
			(primitives
				(gr_poly
					(pts
						(arc
							(start 0.3048 0.2032)
							(mid 0.275042 0.275042)
							(end 0.2032 0.3048)
						)
						(arc
							(start -0.2032 0.3048)
							(mid -0.275042 0.275042)
							(end -0.3048 0.2032)
						)
						(arc
							(start -0.3048 -0.2032)
							(mid -0.275042 -0.275042)
							(end -0.2032 -0.3048)
						)
						(arc
							(start 0.2032 -0.3048)
							(mid 0.275042 -0.275042)
							(end 0.3048 -0.2032)
						)
					)
					(width 0)
					(fill yes)
				)
			)
		)
	)
	(footprint ""
		(layer "B.Cu")
		(at 31.3944 -123.8631 -90)
		(property "Reference" "U104"
			(at 0 0 90)
			(layer "B.SilkS")
			(hide yes)
			(effects
				(font
					(size 1.27 1.27)
				)
				(justify mirror)
			)
		)
		(property "Value" "SNLVC1G126DCKR-GP"
			(at 2.3368 -8.6868 270)
			(unlocked yes)
			(layer "B.Fab")
			(hide yes)
			(effects
				(font
					(size 1.016 1.016)
					(thickness 0.1524)
				)
				(justify mirror)
			)
		)
		(property "Device Type" "SC70-5H44"
			(at 2.3114 -10.414 270)
			(unlocked yes)
			(layer "B.Fab")
			(hide yes)
			(effects
				(font
					(size 1.016 1.016)
					(thickness 0.1524)
				)
				(justify mirror)
			)
		)
		(duplicate_pad_numbers_are_jumpers no)
		(fp_line
			(start -1.27 1.7018)
			(end 1.27 1.7018)
			(stroke
				(width 0.1524)
				(type default)
			)
			(layer "B.SilkS")
		)
		(fp_line
			(start 1.27 1.7018)
			(end 1.27 -1.7018)
			(stroke
				(width 0.1524)
				(type default)
			)
			(layer "B.SilkS")
		)
		(fp_line
			(start -1.27 -1.7018)
			(end -1.27 1.7018)
			(stroke
				(width 0.1524)
				(type default)
			)
			(layer "B.SilkS")
		)
		(fp_line
			(start 1.27 -1.7018)
			(end -1.27 -1.7018)
			(stroke
				(width 0.1524)
				(type default)
			)
			(layer "B.SilkS")
		)
		(fp_line
			(start -1.3843 -1.8034)
			(end -1.3843 -1.1176)
			(stroke
				(width 0.3302)
				(type default)
			)
			(layer "B.SilkS")
		)
		(fp_line
			(start -0.6604 -1.8034)
			(end -1.3843 -1.8034)
			(stroke
				(width 0.3302)
				(type default)
			)
			(layer "B.SilkS")
		)
		(fp_rect
			(start 1.524 1.9558)
			(end -1.524 -1.9558)
			(stroke
				(width 0)
				(type default)
			)
			(fill no)
			(layer "B.CrtYd")
		)
		(fp_poly
			(pts
				(xy 1.524 -1.9558) (xy -1.524 -1.9558) (xy -1.524 1.9558) (xy 1.524 1.9558)
			)
			(stroke
				(width 0)
				(type default)
			)
			(fill no)
			(layer "B.Fab")
		)
		(pad "1" smd rect
			(at -0.65024 -0.8255 90)
			(size 0.4064 1.2192)
			(layers "B.Cu" "B.Mask" "B.Paste")
			(net "U104_EN")
		)
		(pad "2" smd rect
			(at 0 -0.8255 90)
			(size 0.4064 1.2192)
			(layers "B.Cu" "B.Mask" "B.Paste")
			(net "SYS_RESET_N_OUT")
		)
		(pad "3" smd rect
			(at 0.65024 -0.8255 90)
			(size 0.4064 1.2192)
			(layers "B.Cu" "B.Mask" "B.Paste")
			(net "GND")
		)
		(pad "4" smd rect
			(at 0.65024 0.8255 90)
			(size 0.4064 1.2192)
			(layers "B.Cu" "B.Mask" "B.Paste")
			(net "SYS_RESET_N")
		)
		(pad "5" smd rect
			(at -0.65024 0.8255 90)
			(size 0.4064 1.2192)
			(layers "B.Cu" "B.Mask" "B.Paste")
			(net "P3V3_STBY")
		)
	)
	(footprint ""
		(layer "B.Cu")
		(at 182.43804 -74.917554)
		(property "Reference" "TP110"
			(at 0 0 0)
			(layer "B.SilkS")
			(hide yes)
			(effects
				(font
					(size 1.27 1.27)
				)
				(justify mirror)
			)
		)
		(property "Value" "TPAD28-2-GP"
			(at 0.0127 -1.6637 0)
			(unlocked yes)
			(layer "B.Fab")
			(hide yes)
			(effects
				(font
					(size 1.016 1.016)
					(thickness 0.1524)
				)
				(justify mirror)
			)
		)
		(property "Device Type" "TPAD28"
			(at 0.0127 -3.1877 0)
			(unlocked yes)
			(layer "B.Fab")
			(hide yes)
			(effects
				(font
					(size 1.016 1.016)
					(thickness 0.1524)
				)
				(justify mirror)
			)
		)
		(duplicate_pad_numbers_are_jumpers no)
		(fp_poly
			(pts
				(arc
					(start 0.3556 0)
					(mid -0.3556 0)
					(end 0.3556 0)
				)
			)
			(stroke
				(width 0)
				(type default)
			)
			(fill no)
			(layer "B.CrtYd")
		)
		(fp_poly
			(pts
				(arc
					(start 0.6096 0)
					(mid -0.6096 0)
					(end 0.6096 0)
				)
			)
			(stroke
				(width 0)
				(type default)
			)
			(fill no)
			(layer "B.Fab")
		)
		(pad "1" smd circle
			(at 0 0 180)
			(size 0.7112 0.7112)
			(layers "B.Cu" "B.Mask" "B.Paste")
			(net "IOC_GPIO_25")
		)
	)
	(footprint ""
		(layer "B.Cu")
		(at 197.5612 -52.451 -90)
		(property "Reference" "C349"
			(at 0 0 90)
			(layer "B.SilkS")
			(hide yes)
			(effects
				(font
					(size 1.27 1.27)
				)
				(justify mirror)
			)
		)
		(property "Value" "SCD1U6D3V1KX-GP"
			(at 2.8321 -1.7399 270)
			(unlocked yes)
			(layer "B.Fab")
			(hide yes)
			(effects
				(font
					(size 1.016 1.016)
					(thickness 0.1524)
				)
				(justify mirror)
			)
		)
		(property "Device Type" "C0201H13"
			(at 2.8321 -3.2639 270)
			(unlocked yes)
			(layer "B.Fab")
			(hide yes)
			(effects
				(font
					(size 1.016 1.016)
					(thickness 0.1524)
				)
				(justify mirror)
			)
		)
		(duplicate_pad_numbers_are_jumpers no)
		(fp_rect
			(start 0.2794 0.6477)
			(end -0.2794 -0.6477)
			(stroke
				(width 0)
				(type default)
			)
			(fill no)
			(layer "B.CrtYd")
		)
		(fp_rect
			(start 0.2794 0.6477)
			(end -0.2794 -0.6477)
			(stroke
				(width 0)
				(type default)
			)
			(fill no)
			(layer "B.Fab")
		)
		(pad "1" smd custom
			(at 0 -0.2794 90)
			(size 0.0762 0.0762)
			(layers "B.Cu" "B.Mask" "B.Paste")
			(net "VDDA_SAS_REF_CLK")
			(options
				(clearance outline)
				(anchor circle)
			)
			(primitives
				(gr_poly
					(pts
						(arc
							(start 0.1524 0.127)
							(mid 0.137521 0.162921)
							(end 0.1016 0.1778)
						)
						(arc
							(start -0.1016 0.1778)
							(mid -0.137521 0.162921)
							(end -0.1524 0.127)
						)
						(arc
							(start -0.1524 -0.127)
							(mid -0.137521 -0.162921)
							(end -0.1016 -0.1778)
						)
						(arc
							(start 0.1016 -0.1778)
							(mid 0.137521 -0.162921)
							(end 0.1524 -0.127)
						)
					)
					(width 0)
					(fill yes)
				)
			)
		)
		(pad "2" smd custom
			(at 0 0.2794 90)
			(size 0.0762 0.0762)
			(layers "B.Cu" "B.Mask" "B.Paste")
			(net "GND")
			(options
				(clearance outline)
				(anchor circle)
			)
			(primitives
				(gr_poly
					(pts
						(arc
							(start 0.1524 0.127)
							(mid 0.137521 0.162921)
							(end 0.1016 0.1778)
						)
						(arc
							(start -0.1016 0.1778)
							(mid -0.137521 0.162921)
							(end -0.1524 0.127)
						)
						(arc
							(start -0.1524 -0.127)
							(mid -0.137521 -0.162921)
							(end -0.1016 -0.1778)
						)
						(arc
							(start 0.1016 -0.1778)
							(mid 0.137521 -0.162921)
							(end 0.1524 -0.127)
						)
					)
					(width 0)
					(fill yes)
				)
			)
		)
	)
	(footprint ""
		(layer "B.Cu")
		(at 38.231064 -144.857216 -90)
		(property "Reference" "C71"
			(at 0 0 90)
			(layer "B.SilkS")
			(hide yes)
			(effects
				(font
					(size 1.27 1.27)
				)
				(justify mirror)
			)
		)
		(property "Value" "SCD1U16V2KX-3GP"
			(at -1.1811 -2.7051 270)
			(unlocked yes)
			(layer "B.Fab")
			(hide yes)
			(effects
				(font
					(size 1.016 1.016)
					(thickness 0.1524)
				)
				(justify mirror)
			)
		)
		(property "Device Type" "C402H22"
			(at -1.1811 -4.2291 270)
			(unlocked yes)
			(layer "B.Fab")
			(hide yes)
			(effects
				(font
					(size 1.016 1.016)
					(thickness 0.1524)
				)
				(justify mirror)
			)
		)
		(duplicate_pad_numbers_are_jumpers no)
		(fp_rect
			(start 0.4318 0.9525)
			(end -0.4318 -0.9525)
			(stroke
				(width 0)
				(type default)
			)
			(fill no)
			(layer "B.CrtYd")
		)
		(fp_rect
			(start 0.4318 0.9525)
			(end -0.4318 -0.9525)
			(stroke
				(width 0)
				(type default)
			)
			(fill no)
			(layer "B.Fab")
		)
		(pad "1" smd custom
			(at 0 -0.4445 90)
			(size 0.1524 0.1524)
			(layers "B.Cu" "B.Mask" "B.Paste")
			(net "GND")
			(options
				(clearance outline)
				(anchor circle)
			)
			(primitives
				(gr_poly
					(pts
						(arc
							(start 0.3048 0.2032)
							(mid 0.275042 0.275042)
							(end 0.2032 0.3048)
						)
						(arc
							(start -0.2032 0.3048)
							(mid -0.275042 0.275042)
							(end -0.3048 0.2032)
						)
						(arc
							(start -0.3048 -0.2032)
							(mid -0.275042 -0.275042)
							(end -0.2032 -0.3048)
						)
						(arc
							(start 0.2032 -0.3048)
							(mid 0.275042 -0.275042)
							(end 0.3048 -0.2032)
						)
					)
					(width 0)
					(fill yes)
				)
			)
		)
		(pad "2" smd custom
			(at 0 0.4445 90)
			(size 0.1524 0.1524)
			(layers "B.Cu" "B.Mask" "B.Paste")
			(net "P1V2_STBY")
			(options
				(clearance outline)
				(anchor circle)
			)
			(primitives
				(gr_poly
					(pts
						(arc
							(start 0.3048 0.2032)
							(mid 0.275042 0.275042)
							(end 0.2032 0.3048)
						)
						(arc
							(start -0.2032 0.3048)
							(mid -0.275042 0.275042)
							(end -0.3048 0.2032)
						)
						(arc
							(start -0.3048 -0.2032)
							(mid -0.275042 -0.275042)
							(end -0.2032 -0.3048)
						)
						(arc
							(start 0.2032 -0.3048)
							(mid 0.275042 -0.275042)
							(end 0.3048 -0.2032)
						)
					)
					(width 0)
					(fill yes)
				)
			)
		)
	)
	(footprint ""
		(layer "B.Cu")
		(at 93.6752 -170.6626 90)
		(property "Reference" "R795"
			(at 0 0 90)
			(layer "B.SilkS")
			(hide yes)
			(effects
				(font
					(size 1.27 1.27)
				)
				(justify mirror)
			)
		)
		(property "Value" "0R2J-2-GP"
			(at -0.064008 -3.993896 90)
			(unlocked yes)
			(layer "B.Fab")
			(hide yes)
			(effects
				(font
					(size 1.016 1.016)
					(thickness 0.1524)
				)
				(justify mirror)
			)
		)
		(property "Device Type" "R402H16"
			(at -0.064008 -5.517896 90)
			(unlocked yes)
			(layer "B.Fab")
			(hide yes)
			(effects
				(font
					(size 1.016 1.016)
					(thickness 0.1524)
				)
				(justify mirror)
			)
		)
		(duplicate_pad_numbers_are_jumpers no)
		(fp_line
			(start 0.508 -0.9398)
			(end 0.508 0.9398)
			(stroke
				(width 0.1524)
				(type default)
			)
			(layer "B.SilkS")
		)
		(fp_line
			(start -0.508 -0.9398)
			(end 0.508 -0.9398)
			(stroke
				(width 0.1524)
				(type default)
			)
			(layer "B.SilkS")
		)
		(fp_rect
			(start 0.508 0.9398)
			(end -0.508 -0.9398)
			(stroke
				(width 0)
				(type default)
			)
			(fill no)
			(layer "B.CrtYd")
		)
		(fp_rect
			(start 0.508 0.9398)
			(end -0.508 -0.9398)
			(stroke
				(width 0)
				(type default)
			)
			(fill no)
			(layer "B.Fab")
		)
		(pad "1" smd custom
			(at 0 -0.4445 270)
			(size 0.1397 0.1397)
			(layers "B.Cu" "B.Mask" "B.Paste")
			(net "UART_COMP_IN_RX_AND_R")
			(options
				(clearance outline)
				(anchor circle)
			)
			(primitives
				(gr_poly
					(pts
						(arc
							(start -0.1778 0.2794)
							(mid -0.249642 0.249642)
							(end -0.2794 0.1778)
						)
						(arc
							(start -0.2794 -0.1778)
							(mid -0.249642 -0.249642)
							(end -0.1778 -0.2794)
						)
						(arc
							(start 0.1778 -0.2794)
							(mid 0.249642 -0.249642)
							(end 0.2794 -0.1778)
						)
						(arc
							(start 0.2794 0.1778)
							(mid 0.249642 0.249642)
							(end 0.1778 0.2794)
						)
					)
					(width 0)
					(fill yes)
				)
			)
		)
		(pad "2" smd custom
			(at 0 0.4445 270)
			(size 0.1397 0.1397)
			(layers "B.Cu" "B.Mask" "B.Paste")
			(net "UART_COMP_IN_RX_AND")
			(options
				(clearance outline)
				(anchor circle)
			)
			(primitives
				(gr_poly
					(pts
						(arc
							(start -0.1778 0.2794)
							(mid -0.249642 0.249642)
							(end -0.2794 0.1778)
						)
						(arc
							(start -0.2794 -0.1778)
							(mid -0.249642 -0.249642)
							(end -0.1778 -0.2794)
						)
						(arc
							(start 0.1778 -0.2794)
							(mid 0.249642 -0.249642)
							(end 0.2794 -0.1778)
						)
						(arc
							(start 0.2794 0.1778)
							(mid 0.249642 0.249642)
							(end 0.1778 0.2794)
						)
					)
					(width 0)
					(fill yes)
				)
			)
		)
	)
	(footprint ""
		(layer "B.Cu")
		(at 180.512466 -65.522856 90)
		(property "Reference" "R575"
			(at 0 0 90)
			(layer "B.SilkS")
			(hide yes)
			(effects
				(font
					(size 1.27 1.27)
				)
				(justify mirror)
			)
		)
		(property "Value" "10KR2F-2-GP"
			(at -0.064008 -3.993896 90)
			(unlocked yes)
			(layer "B.Fab")
			(hide yes)
			(effects
				(font
					(size 1.016 1.016)
					(thickness 0.1524)
				)
				(justify mirror)
			)
		)
		(property "Device Type" "R402H16"
			(at -0.064008 -5.517896 90)
			(unlocked yes)
			(layer "B.Fab")
			(hide yes)
			(effects
				(font
					(size 1.016 1.016)
					(thickness 0.1524)
				)
				(justify mirror)
			)
		)
		(duplicate_pad_numbers_are_jumpers no)
		(fp_line
			(start 0.508 -0.9398)
			(end 0.508 0.9398)
			(stroke
				(width 0.1524)
				(type default)
			)
			(layer "B.SilkS")
		)
		(fp_line
			(start -0.508 -0.9398)
			(end 0.508 -0.9398)
			(stroke
				(width 0.1524)
				(type default)
			)
			(layer "B.SilkS")
		)
		(fp_rect
			(start 0.508 0.9398)
			(end -0.508 -0.9398)
			(stroke
				(width 0)
				(type default)
			)
			(fill no)
			(layer "B.CrtYd")
		)
		(fp_rect
			(start 0.508 0.9398)
			(end -0.508 -0.9398)
			(stroke
				(width 0)
				(type default)
			)
			(fill no)
			(layer "B.Fab")
		)
		(pad "1" smd custom
			(at 0 -0.4445 270)
			(size 0.1397 0.1397)
			(layers "B.Cu" "B.Mask" "B.Paste")
			(net "GND")
			(options
				(clearance outline)
				(anchor circle)
			)
			(primitives
				(gr_poly
					(pts
						(arc
							(start -0.1778 0.2794)
							(mid -0.249642 0.249642)
							(end -0.2794 0.1778)
						)
						(arc
							(start -0.2794 -0.1778)
							(mid -0.249642 -0.249642)
							(end -0.1778 -0.2794)
						)
						(arc
							(start 0.1778 -0.2794)
							(mid 0.249642 -0.249642)
							(end 0.2794 -0.1778)
						)
						(arc
							(start 0.2794 0.1778)
							(mid 0.249642 0.249642)
							(end 0.1778 0.2794)
						)
					)
					(width 0)
					(fill yes)
				)
			)
		)
		(pad "2" smd custom
			(at 0 0.4445 270)
			(size 0.1397 0.1397)
			(layers "B.Cu" "B.Mask" "B.Paste")
			(net "IOC_CLK_SEL1")
			(options
				(clearance outline)
				(anchor circle)
			)
			(primitives
				(gr_poly
					(pts
						(arc
							(start -0.1778 0.2794)
							(mid -0.249642 0.249642)
							(end -0.2794 0.1778)
						)
						(arc
							(start -0.2794 -0.1778)
							(mid -0.249642 -0.249642)
							(end -0.1778 -0.2794)
						)
						(arc
							(start 0.1778 -0.2794)
							(mid 0.249642 -0.249642)
							(end 0.2794 -0.1778)
						)
						(arc
							(start 0.2794 0.1778)
							(mid 0.249642 0.249642)
							(end 0.1778 0.2794)
						)
					)
					(width 0)
					(fill yes)
				)
			)
		)
	)
	(footprint ""
		(layer "B.Cu")
		(at 164.7444 -63.2714 180)
		(property "Reference" "U42"
			(at 0 0 0)
			(layer "B.SilkS")
			(hide yes)
			(effects
				(font
					(size 1.27 1.27)
				)
				(justify mirror)
			)
		)
		(property "Value" "S29GL128S10TFIV20-GP"
			(at 0.1778 -20.32 180)
			(unlocked yes)
			(layer "B.Fab")
			(hide yes)
			(effects
				(font
					(size 1.016 1.016)
					(thickness 0.1524)
				)
				(justify mirror)
			)
		)
		(property "Device Type" "TSOP56-1H48"
			(at 0.1778 -22.225 180)
			(unlocked yes)
			(layer "B.Fab")
			(hide yes)
			(effects
				(font
					(size 1.016 1.016)
					(thickness 0.1524)
				)
				(justify mirror)
			)
		)
		(duplicate_pad_numbers_are_jumpers no)
		(fp_line
			(start 7.5438 8.5598)
			(end -6.8326 8.5598)
			(stroke
				(width 0.1524)
				(type default)
			)
			(layer "B.SilkS")
		)
		(fp_line
			(start 7.5438 -0.4318)
			(end 7.112 0)
			(stroke
				(width 0.1524)
				(type default)
			)
			(layer "B.SilkS")
		)
		(fp_line
			(start 7.5438 -8.5598)
			(end 7.5438 8.5598)
			(stroke
				(width 0.1524)
				(type default)
			)
			(layer "B.SilkS")
		)
		(fp_line
			(start 7.366 8.5598)
			(end 7.366 10.795)
			(stroke
				(width 0.508)
				(type default)
			)
			(layer "B.SilkS")
		)
		(fp_line
			(start 7.112 0)
			(end 7.5438 0.4318)
			(stroke
				(width 0.1524)
				(type default)
			)
			(layer "B.SilkS")
		)
		(fp_line
			(start -6.8326 8.5598)
			(end -6.8326 -8.5598)
			(stroke
				(width 0.1524)
				(type default)
			)
			(layer "B.SilkS")
		)
		(fp_line
			(start -6.8326 -8.5598)
			(end 7.5438 -8.5598)
			(stroke
				(width 0.1524)
				(type default)
			)
			(layer "B.SilkS")
		)
		(fp_poly
			(pts
				(xy 7.62 11.049) (xy -7.62 11.049) (xy -7.62 -11.049) (xy 7.62 -11.049)
			)
			(stroke
				(width 0)
				(type default)
			)
			(fill no)
			(layer "B.CrtYd")
		)
		(fp_poly
			(pts
				(xy 7.62 -11.049) (xy -7.62 -11.049) (xy -7.62 11.049) (xy 7.62 11.049)
			)
			(stroke
				(width 0)
				(type default)
			)
			(fill no)
			(layer "B.Fab")
		)
		(pad "1" smd rect
			(at 6.75005 9.6139)
			(size 0.3048 1.524)
			(layers "B.Cu" "B.Mask" "B.Paste")
			(net "Net_319")
		)
		(pad "2" smd rect
			(at 6.24967 9.6139)
			(size 0.3048 1.524)
			(layers "B.Cu" "B.Mask" "B.Paste")
			(net "XM_ADDR_23")
		)
		(pad "3" smd rect
			(at 5.75056 9.6139)
			(size 0.3048 1.524)
			(layers "B.Cu" "B.Mask" "B.Paste")
			(net "XM_ADDR_16")
		)
		(pad "4" smd rect
			(at 5.25018 9.6139)
			(size 0.3048 1.524)
			(layers "B.Cu" "B.Mask" "B.Paste")
			(net "XM_ADDR_15")
		)
		(pad "5" smd rect
			(at 4.7498 9.6139)
			(size 0.3048 1.524)
			(layers "B.Cu" "B.Mask" "B.Paste")
			(net "XM_ADDR_14")
		)
		(pad "6" smd rect
			(at 4.24942 9.6139)
			(size 0.3048 1.524)
			(layers "B.Cu" "B.Mask" "B.Paste")
			(net "XM_ADDR_13")
		)
		(pad "7" smd rect
			(at 3.75031 9.6139)
			(size 0.3048 1.524)
			(layers "B.Cu" "B.Mask" "B.Paste")
			(net "XM_ADDR_12")
		)
		(pad "8" smd rect
			(at 3.24993 9.6139)
			(size 0.3048 1.524)
			(layers "B.Cu" "B.Mask" "B.Paste")
			(net "XM_ADDR_11")
		)
		(pad "9" smd rect
			(at 2.74955 9.6139)
			(size 0.3048 1.524)
			(layers "B.Cu" "B.Mask" "B.Paste")
			(net "XM_ADDR_10")
		)
		(pad "10" smd rect
			(at 2.25044 9.6139)
			(size 0.3048 1.524)
			(layers "B.Cu" "B.Mask" "B.Paste")
			(net "XM_ADDR_9")
		)
		(pad "11" smd rect
			(at 1.75006 9.6139)
			(size 0.3048 1.524)
			(layers "B.Cu" "B.Mask" "B.Paste")
			(net "XM_ADDR_20")
		)
		(pad "12" smd rect
			(at 1.24968 9.6139)
			(size 0.3048 1.524)
			(layers "B.Cu" "B.Mask" "B.Paste")
			(net "XM_ADDR_21")
		)
		(pad "13" smd rect
			(at 0.75057 9.6139)
			(size 0.3048 1.524)
			(layers "B.Cu" "B.Mask" "B.Paste")
			(net "XM_WE_N")
		)
		(pad "14" smd rect
			(at 0.25019 9.6139)
			(size 0.3048 1.524)
			(layers "B.Cu" "B.Mask" "B.Paste")
			(net "XM_F_RST_N")
		)
		(pad "15" smd rect
			(at -0.25019 9.6139)
			(size 0.3048 1.524)
			(layers "B.Cu" "B.Mask" "B.Paste")
			(net "XM_ADDR_22")
		)
		(pad "16" smd rect
			(at -0.75057 9.6139)
			(size 0.3048 1.524)
			(layers "B.Cu" "B.Mask" "B.Paste")
			(net "IOC_WP_N")
		)
		(pad "17" smd rect
			(at -1.24968 9.6139)
			(size 0.3048 1.524)
			(layers "B.Cu" "B.Mask" "B.Paste")
			(net "Net_314")
		)
		(pad "18" smd rect
			(at -1.75006 9.6139)
			(size 0.3048 1.524)
			(layers "B.Cu" "B.Mask" "B.Paste")
			(net "XM_ADDR_19")
		)
		(pad "19" smd rect
			(at -2.25044 9.6139)
			(size 0.3048 1.524)
			(layers "B.Cu" "B.Mask" "B.Paste")
			(net "XM_ADDR_18")
		)
		(pad "20" smd rect
			(at -2.74955 9.6139)
			(size 0.3048 1.524)
			(layers "B.Cu" "B.Mask" "B.Paste")
			(net "XM_ADDR_8")
		)
		(pad "21" smd rect
			(at -3.24993 9.6139)
			(size 0.3048 1.524)
			(layers "B.Cu" "B.Mask" "B.Paste")
			(net "XM_ADDR_7")
		)
		(pad "22" smd rect
			(at -3.75031 9.6139)
			(size 0.3048 1.524)
			(layers "B.Cu" "B.Mask" "B.Paste")
			(net "XM_ADDR_6")
		)
		(pad "23" smd rect
			(at -4.24942 9.6139)
			(size 0.3048 1.524)
			(layers "B.Cu" "B.Mask" "B.Paste")
			(net "XM_ADDR_5")
		)
		(pad "24" smd rect
			(at -4.7498 9.6139)
			(size 0.3048 1.524)
			(layers "B.Cu" "B.Mask" "B.Paste")
			(net "XM_ADDR_4")
		)
		(pad "25" smd rect
			(at -5.25018 9.6139)
			(size 0.3048 1.524)
			(layers "B.Cu" "B.Mask" "B.Paste")
			(net "XM_ADDR_3")
		)
		(pad "26" smd rect
			(at -5.75056 9.6139)
			(size 0.3048 1.524)
			(layers "B.Cu" "B.Mask" "B.Paste")
			(net "XM_ADDR_2")
		)
		(pad "27" smd rect
			(at -6.24967 9.6139)
			(size 0.3048 1.524)
			(layers "B.Cu" "B.Mask" "B.Paste")
			(net "Net_315")
		)
		(pad "28" smd rect
			(at -6.75005 9.6139)
			(size 0.3048 1.524)
			(layers "B.Cu" "B.Mask" "B.Paste")
			(net "Net_316")
		)
		(pad "29" smd rect
			(at -6.75005 -9.6139)
			(size 0.3048 1.524)
			(layers "B.Cu" "B.Mask" "B.Paste")
			(net "P1V8")
		)
		(pad "30" smd rect
			(at -6.24967 -9.6139)
			(size 0.3048 1.524)
			(layers "B.Cu" "B.Mask" "B.Paste")
			(net "Net_313")
		)
		(pad "31" smd rect
			(at -5.75056 -9.6139)
			(size 0.3048 1.524)
			(layers "B.Cu" "B.Mask" "B.Paste")
			(net "XM_ADDR_1")
		)
		(pad "32" smd rect
			(at -5.25018 -9.6139)
			(size 0.3048 1.524)
			(layers "B.Cu" "B.Mask" "B.Paste")
			(net "XM_NOR_CS_N")
		)
		(pad "33" smd rect
			(at -4.7498 -9.6139)
			(size 0.3048 1.524)
			(layers "B.Cu" "B.Mask" "B.Paste")
			(net "GND")
		)
		(pad "34" smd rect
			(at -4.24942 -9.6139)
			(size 0.3048 1.524)
			(layers "B.Cu" "B.Mask" "B.Paste")
			(net "XM_OE_N")
		)
		(pad "35" smd rect
			(at -3.75031 -9.6139)
			(size 0.3048 1.524)
			(layers "B.Cu" "B.Mask" "B.Paste")
			(net "XM_DATA_0")
		)
		(pad "36" smd rect
			(at -3.24993 -9.6139)
			(size 0.3048 1.524)
			(layers "B.Cu" "B.Mask" "B.Paste")
			(net "XM_DATA_8")
		)
		(pad "37" smd rect
			(at -2.74955 -9.6139)
			(size 0.3048 1.524)
			(layers "B.Cu" "B.Mask" "B.Paste")
			(net "XM_DATA_1")
		)
		(pad "38" smd rect
			(at -2.25044 -9.6139)
			(size 0.3048 1.524)
			(layers "B.Cu" "B.Mask" "B.Paste")
			(net "XM_DATA_9")
		)
		(pad "39" smd rect
			(at -1.75006 -9.6139)
			(size 0.3048 1.524)
			(layers "B.Cu" "B.Mask" "B.Paste")
			(net "XM_DATA_2")
		)
		(pad "40" smd rect
			(at -1.24968 -9.6139)
			(size 0.3048 1.524)
			(layers "B.Cu" "B.Mask" "B.Paste")
			(net "XM_DATA_10")
		)
		(pad "41" smd rect
			(at -0.75057 -9.6139)
			(size 0.3048 1.524)
			(layers "B.Cu" "B.Mask" "B.Paste")
			(net "XM_DATA_3")
		)
		(pad "42" smd rect
			(at -0.25019 -9.6139)
			(size 0.3048 1.524)
			(layers "B.Cu" "B.Mask" "B.Paste")
			(net "XM_DATA_11")
		)
		(pad "43" smd rect
			(at 0.25019 -9.6139)
			(size 0.3048 1.524)
			(layers "B.Cu" "B.Mask" "B.Paste")
			(net "P3V3_STBY")
		)
		(pad "44" smd rect
			(at 0.75057 -9.6139)
			(size 0.3048 1.524)
			(layers "B.Cu" "B.Mask" "B.Paste")
			(net "XM_DATA_4")
		)
		(pad "45" smd rect
			(at 1.24968 -9.6139)
			(size 0.3048 1.524)
			(layers "B.Cu" "B.Mask" "B.Paste")
			(net "XM_DATA_12")
		)
		(pad "46" smd rect
			(at 1.75006 -9.6139)
			(size 0.3048 1.524)
			(layers "B.Cu" "B.Mask" "B.Paste")
			(net "XM_DATA_5")
		)
		(pad "47" smd rect
			(at 2.25044 -9.6139)
			(size 0.3048 1.524)
			(layers "B.Cu" "B.Mask" "B.Paste")
			(net "XM_DATA_13")
		)
		(pad "48" smd rect
			(at 2.74955 -9.6139)
			(size 0.3048 1.524)
			(layers "B.Cu" "B.Mask" "B.Paste")
			(net "XM_DATA_6")
		)
		(pad "49" smd rect
			(at 3.24993 -9.6139)
			(size 0.3048 1.524)
			(layers "B.Cu" "B.Mask" "B.Paste")
			(net "XM_DATA_14")
		)
		(pad "50" smd rect
			(at 3.75031 -9.6139)
			(size 0.3048 1.524)
			(layers "B.Cu" "B.Mask" "B.Paste")
			(net "XM_DATA_7")
		)
		(pad "51" smd rect
			(at 4.24942 -9.6139)
			(size 0.3048 1.524)
			(layers "B.Cu" "B.Mask" "B.Paste")
			(net "XM_DATA_15")
		)
		(pad "52" smd rect
			(at 4.7498 -9.6139)
			(size 0.3048 1.524)
			(layers "B.Cu" "B.Mask" "B.Paste")
			(net "GND")
		)
		(pad "53" smd rect
			(at 5.25018 -9.6139)
			(size 0.3048 1.524)
			(layers "B.Cu" "B.Mask" "B.Paste")
			(net "BYTE_N")
		)
		(pad "54" smd rect
			(at 5.75056 -9.6139)
			(size 0.3048 1.524)
			(layers "B.Cu" "B.Mask" "B.Paste")
			(net "XM_ADDR_17")
		)
		(pad "55" smd rect
			(at 6.24967 -9.6139)
			(size 0.3048 1.524)
			(layers "B.Cu" "B.Mask" "B.Paste")
			(net "Net_317")
		)
		(pad "56" smd rect
			(at 6.75005 -9.6139)
			(size 0.3048 1.524)
			(layers "B.Cu" "B.Mask" "B.Paste")
			(net "Net_318")
		)
	)
	(footprint ""
		(layer "B.Cu")
		(at 13.323824 -145.23593 90)
		(property "Reference" "R209"
			(at 0 0 90)
			(layer "B.SilkS")
			(hide yes)
			(effects
				(font
					(size 1.27 1.27)
				)
				(justify mirror)
			)
		)
		(property "Value" "120R2F-GP"
			(at -0.064008 -3.993896 90)
			(unlocked yes)
			(layer "B.Fab")
			(hide yes)
			(effects
				(font
					(size 1.016 1.016)
					(thickness 0.1524)
				)
				(justify mirror)
			)
		)
		(property "Device Type" "R402H16"
			(at -0.064008 -5.517896 90)
			(unlocked yes)
			(layer "B.Fab")
			(hide yes)
			(effects
				(font
					(size 1.016 1.016)
					(thickness 0.1524)
				)
				(justify mirror)
			)
		)
		(duplicate_pad_numbers_are_jumpers no)
		(fp_line
			(start 0.508 -0.9398)
			(end 0.508 0.9398)
			(stroke
				(width 0.1524)
				(type default)
			)
			(layer "B.SilkS")
		)
		(fp_line
			(start -0.508 -0.9398)
			(end 0.508 -0.9398)
			(stroke
				(width 0.1524)
				(type default)
			)
			(layer "B.SilkS")
		)
		(fp_rect
			(start 0.508 0.9398)
			(end -0.508 -0.9398)
			(stroke
				(width 0)
				(type default)
			)
			(fill no)
			(layer "B.CrtYd")
		)
		(fp_rect
			(start 0.508 0.9398)
			(end -0.508 -0.9398)
			(stroke
				(width 0)
				(type default)
			)
			(fill no)
			(layer "B.Fab")
		)
		(pad "1" smd custom
			(at 0 -0.4445 270)
			(size 0.1397 0.1397)
			(layers "B.Cu" "B.Mask" "B.Paste")
			(net "GND")
			(options
				(clearance outline)
				(anchor circle)
			)
			(primitives
				(gr_poly
					(pts
						(arc
							(start -0.1778 0.2794)
							(mid -0.249642 0.249642)
							(end -0.2794 0.1778)
						)
						(arc
							(start -0.2794 -0.1778)
							(mid -0.249642 -0.249642)
							(end -0.1778 -0.2794)
						)
						(arc
							(start 0.1778 -0.2794)
							(mid 0.249642 -0.249642)
							(end 0.2794 -0.1778)
						)
						(arc
							(start 0.2794 0.1778)
							(mid 0.249642 0.249642)
							(end 0.1778 0.2794)
						)
					)
					(width 0)
					(fill yes)
				)
			)
		)
		(pad "2" smd custom
			(at 0 0.4445 270)
			(size 0.1397 0.1397)
			(layers "B.Cu" "B.Mask" "B.Paste")
			(net "MEMCKE")
			(options
				(clearance outline)
				(anchor circle)
			)
			(primitives
				(gr_poly
					(pts
						(arc
							(start -0.1778 0.2794)
							(mid -0.249642 0.249642)
							(end -0.2794 0.1778)
						)
						(arc
							(start -0.2794 -0.1778)
							(mid -0.249642 -0.249642)
							(end -0.1778 -0.2794)
						)
						(arc
							(start 0.1778 -0.2794)
							(mid 0.249642 -0.249642)
							(end 0.2794 -0.1778)
						)
						(arc
							(start 0.2794 0.1778)
							(mid 0.249642 0.249642)
							(end 0.1778 0.2794)
						)
					)
					(width 0)
					(fill yes)
				)
			)
		)
	)
	(footprint ""
		(layer "B.Cu")
		(at 45.07484 -154.29992 -90)
		(property "Reference" "C105"
			(at 0 0 90)
			(layer "B.SilkS")
			(hide yes)
			(effects
				(font
					(size 1.27 1.27)
				)
				(justify mirror)
			)
		)
		(property "Value" "SC100P50V2JN-3GP"
			(at -1.1811 -2.7051 270)
			(unlocked yes)
			(layer "B.Fab")
			(hide yes)
			(effects
				(font
					(size 1.016 1.016)
					(thickness 0.1524)
				)
				(justify mirror)
			)
		)
		(property "Device Type" "C402H22"
			(at -1.1811 -4.2291 270)
			(unlocked yes)
			(layer "B.Fab")
			(hide yes)
			(effects
				(font
					(size 1.016 1.016)
					(thickness 0.1524)
				)
				(justify mirror)
			)
		)
		(duplicate_pad_numbers_are_jumpers no)
		(fp_rect
			(start 0.4318 0.9525)
			(end -0.4318 -0.9525)
			(stroke
				(width 0)
				(type default)
			)
			(fill no)
			(layer "B.CrtYd")
		)
		(fp_rect
			(start 0.4318 0.9525)
			(end -0.4318 -0.9525)
			(stroke
				(width 0)
				(type default)
			)
			(fill no)
			(layer "B.Fab")
		)
		(pad "1" smd custom
			(at 0 -0.4445 90)
			(size 0.1524 0.1524)
			(layers "B.Cu" "B.Mask" "B.Paste")
			(net "V1PLLAV11")
			(options
				(clearance outline)
				(anchor circle)
			)
			(primitives
				(gr_poly
					(pts
						(arc
							(start 0.3048 0.2032)
							(mid 0.275042 0.275042)
							(end 0.2032 0.3048)
						)
						(arc
							(start -0.2032 0.3048)
							(mid -0.275042 0.275042)
							(end -0.3048 0.2032)
						)
						(arc
							(start -0.3048 -0.2032)
							(mid -0.275042 -0.275042)
							(end -0.2032 -0.3048)
						)
						(arc
							(start 0.2032 -0.3048)
							(mid 0.275042 -0.275042)
							(end 0.3048 -0.2032)
						)
					)
					(width 0)
					(fill yes)
				)
			)
		)
		(pad "2" smd custom
			(at 0 0.4445 90)
			(size 0.1524 0.1524)
			(layers "B.Cu" "B.Mask" "B.Paste")
			(net "GND")
			(options
				(clearance outline)
				(anchor circle)
			)
			(primitives
				(gr_poly
					(pts
						(arc
							(start 0.3048 0.2032)
							(mid 0.275042 0.275042)
							(end 0.2032 0.3048)
						)
						(arc
							(start -0.2032 0.3048)
							(mid -0.275042 0.275042)
							(end -0.3048 0.2032)
						)
						(arc
							(start -0.3048 -0.2032)
							(mid -0.275042 -0.275042)
							(end -0.2032 -0.3048)
						)
						(arc
							(start 0.2032 -0.3048)
							(mid 0.275042 -0.275042)
							(end 0.3048 -0.2032)
						)
					)
					(width 0)
					(fill yes)
				)
			)
		)
	)
	(footprint ""
		(layer "B.Cu")
		(at 191.68999 -23.876 -90)
		(property "Reference" "C492"
			(at 0 0 90)
			(layer "B.SilkS")
			(hide yes)
			(effects
				(font
					(size 1.27 1.27)
				)
				(justify mirror)
			)
		)
		(property "Value" "SCD01U16V1KX-GP"
			(at 2.8321 -1.7399 270)
			(unlocked yes)
			(layer "B.Fab")
			(hide yes)
			(effects
				(font
					(size 1.016 1.016)
					(thickness 0.1524)
				)
				(justify mirror)
			)
		)
		(property "Device Type" "C0201H13"
			(at 2.8321 -3.2639 270)
			(unlocked yes)
			(layer "B.Fab")
			(hide yes)
			(effects
				(font
					(size 1.016 1.016)
					(thickness 0.1524)
				)
				(justify mirror)
			)
		)
		(duplicate_pad_numbers_are_jumpers no)
		(fp_rect
			(start 0.2794 0.6477)
			(end -0.2794 -0.6477)
			(stroke
				(width 0)
				(type default)
			)
			(fill no)
			(layer "B.CrtYd")
		)
		(fp_rect
			(start 0.2794 0.6477)
			(end -0.2794 -0.6477)
			(stroke
				(width 0)
				(type default)
			)
			(fill no)
			(layer "B.Fab")
		)
		(pad "1" smd custom
			(at 0 -0.2794 90)
			(size 0.0762 0.0762)
			(layers "B.Cu" "B.Mask" "B.Paste")
			(net "PHY_CON_A_TO_IOC_2_DP")
			(options
				(clearance outline)
				(anchor circle)
			)
			(primitives
				(gr_poly
					(pts
						(arc
							(start 0.1524 0.127)
							(mid 0.137521 0.162921)
							(end 0.1016 0.1778)
						)
						(arc
							(start -0.1016 0.1778)
							(mid -0.137521 0.162921)
							(end -0.1524 0.127)
						)
						(arc
							(start -0.1524 -0.127)
							(mid -0.137521 -0.162921)
							(end -0.1016 -0.1778)
						)
						(arc
							(start 0.1016 -0.1778)
							(mid 0.137521 -0.162921)
							(end 0.1524 -0.127)
						)
					)
					(width 0)
					(fill yes)
				)
			)
		)
		(pad "2" smd custom
			(at 0 0.2794 90)
			(size 0.0762 0.0762)
			(layers "B.Cu" "B.Mask" "B.Paste")
			(net "PHY_CON_A_TO_IOC_2_DP_C")
			(options
				(clearance outline)
				(anchor circle)
			)
			(primitives
				(gr_poly
					(pts
						(arc
							(start 0.1524 0.127)
							(mid 0.137521 0.162921)
							(end 0.1016 0.1778)
						)
						(arc
							(start -0.1016 0.1778)
							(mid -0.137521 0.162921)
							(end -0.1524 0.127)
						)
						(arc
							(start -0.1524 -0.127)
							(mid -0.137521 -0.162921)
							(end -0.1016 -0.1778)
						)
						(arc
							(start 0.1016 -0.1778)
							(mid 0.137521 -0.162921)
							(end 0.1524 -0.127)
						)
					)
					(width 0)
					(fill yes)
				)
			)
		)
	)
	(footprint ""
		(layer "B.Cu")
		(at 62.865 -153.99004 -90)
		(property "Reference" "R303"
			(at 0 0 90)
			(layer "B.SilkS")
			(hide yes)
			(effects
				(font
					(size 1.27 1.27)
				)
				(justify mirror)
			)
		)
		(property "Value" "47KR2F-GP"
			(at -0.064008 -3.993896 270)
			(unlocked yes)
			(layer "B.Fab")
			(hide yes)
			(effects
				(font
					(size 1.016 1.016)
					(thickness 0.1524)
				)
				(justify mirror)
			)
		)
		(property "Device Type" "R402H16"
			(at -0.064008 -5.517896 270)
			(unlocked yes)
			(layer "B.Fab")
			(hide yes)
			(effects
				(font
					(size 1.016 1.016)
					(thickness 0.1524)
				)
				(justify mirror)
			)
		)
		(duplicate_pad_numbers_are_jumpers no)
		(fp_line
			(start -0.508 -0.9398)
			(end 0.508 -0.9398)
			(stroke
				(width 0.1524)
				(type default)
			)
			(layer "B.SilkS")
		)
		(fp_line
			(start 0.508 -0.9398)
			(end 0.508 0.9398)
			(stroke
				(width 0.1524)
				(type default)
			)
			(layer "B.SilkS")
		)
		(fp_rect
			(start 0.508 0.9398)
			(end -0.508 -0.9398)
			(stroke
				(width 0)
				(type default)
			)
			(fill no)
			(layer "B.CrtYd")
		)
		(fp_rect
			(start 0.508 0.9398)
			(end -0.508 -0.9398)
			(stroke
				(width 0)
				(type default)
			)
			(fill no)
			(layer "B.Fab")
		)
		(pad "1" smd custom
			(at 0 -0.4445 90)
			(size 0.1397 0.1397)
			(layers "B.Cu" "B.Mask" "B.Paste")
			(net "GND")
			(options
				(clearance outline)
				(anchor circle)
			)
			(primitives
				(gr_poly
					(pts
						(arc
							(start -0.1778 0.2794)
							(mid -0.249642 0.249642)
							(end -0.2794 0.1778)
						)
						(arc
							(start -0.2794 -0.1778)
							(mid -0.249642 -0.249642)
							(end -0.1778 -0.2794)
						)
						(arc
							(start 0.1778 -0.2794)
							(mid 0.249642 -0.249642)
							(end 0.2794 -0.1778)
						)
						(arc
							(start 0.2794 0.1778)
							(mid 0.249642 0.249642)
							(end 0.1778 0.2794)
						)
					)
					(width 0)
					(fill yes)
				)
			)
		)
		(pad "2" smd custom
			(at 0 0.4445 90)
			(size 0.1397 0.1397)
			(layers "B.Cu" "B.Mask" "B.Paste")
			(net "BMC_RGMII_C2_C3_D1_D2_E6")
			(options
				(clearance outline)
				(anchor circle)
			)
			(primitives
				(gr_poly
					(pts
						(arc
							(start -0.1778 0.2794)
							(mid -0.249642 0.249642)
							(end -0.2794 0.1778)
						)
						(arc
							(start -0.2794 -0.1778)
							(mid -0.249642 -0.249642)
							(end -0.1778 -0.2794)
						)
						(arc
							(start 0.1778 -0.2794)
							(mid 0.249642 -0.249642)
							(end 0.2794 -0.1778)
						)
						(arc
							(start 0.2794 0.1778)
							(mid 0.249642 0.249642)
							(end 0.1778 0.2794)
						)
					)
					(width 0)
					(fill yes)
				)
			)
		)
	)
	(footprint ""
		(layer "B.Cu")
		(at 26.079196 -136.099296 90)
		(property "Reference" "C64"
			(at 0 0 90)
			(layer "B.SilkS")
			(hide yes)
			(effects
				(font
					(size 1.27 1.27)
				)
				(justify mirror)
			)
		)
		(property "Value" "SC1U16V3KX-5GP"
			(at 0 -2.8194 90)
			(unlocked yes)
			(layer "B.Fab")
			(hide yes)
			(effects
				(font
					(size 1.016 1.016)
					(thickness 0.1524)
				)
				(justify mirror)
			)
		)
		(property "Device Type" "C603H36"
			(at 0 -4.3434 90)
			(unlocked yes)
			(layer "B.Fab")
			(hide yes)
			(effects
				(font
					(size 1.016 1.016)
					(thickness 0.1524)
				)
				(justify mirror)
			)
		)
		(duplicate_pad_numbers_are_jumpers no)
		(fp_line
			(start -0.508 0)
			(end 0.508 0)
			(stroke
				(width 0.2032)
				(type default)
			)
			(layer "B.SilkS")
		)
		(fp_rect
			(start 0.5842 1.3335)
			(end -0.5842 -1.3335)
			(stroke
				(width 0)
				(type default)
			)
			(fill no)
			(layer "B.CrtYd")
		)
		(fp_rect
			(start 0.5842 1.3335)
			(end -0.5842 -1.3335)
			(stroke
				(width 0)
				(type default)
			)
			(fill no)
			(layer "B.Fab")
		)
		(pad "1" smd custom
			(at 0 -0.762 270)
			(size 0.2159 0.2159)
			(layers "B.Cu" "B.Mask" "B.Paste")
			(net "P2V5_STBY")
			(options
				(clearance outline)
				(anchor circle)
			)
			(primitives
				(gr_poly
					(pts
						(arc
							(start -0.3302 0.4318)
							(mid -0.402042 0.402042)
							(end -0.4318 0.3302)
						)
						(arc
							(start -0.4318 -0.3302)
							(mid -0.402042 -0.402042)
							(end -0.3302 -0.4318)
						)
						(arc
							(start 0.3302 -0.4318)
							(mid 0.402042 -0.402042)
							(end 0.4318 -0.3302)
						)
						(arc
							(start 0.4318 0.3302)
							(mid 0.402042 0.402042)
							(end 0.3302 0.4318)
						)
					)
					(width 0)
					(fill yes)
				)
			)
		)
		(pad "2" smd custom
			(at 0 0.762 270)
			(size 0.2159 0.2159)
			(layers "B.Cu" "B.Mask" "B.Paste")
			(net "GND")
			(options
				(clearance outline)
				(anchor circle)
			)
			(primitives
				(gr_poly
					(pts
						(arc
							(start -0.3302 0.4318)
							(mid -0.402042 0.402042)
							(end -0.4318 0.3302)
						)
						(arc
							(start -0.4318 -0.3302)
							(mid -0.402042 -0.402042)
							(end -0.3302 -0.4318)
						)
						(arc
							(start 0.3302 -0.4318)
							(mid 0.402042 -0.402042)
							(end 0.4318 -0.3302)
						)
						(arc
							(start 0.4318 0.3302)
							(mid 0.402042 0.402042)
							(end 0.3302 0.4318)
						)
					)
					(width 0)
					(fill yes)
				)
			)
		)
	)
	(footprint ""
		(layer "B.Cu")
		(at 20.591272 -129.074164 180)
		(property "Reference" "R252"
			(at 0 0 0)
			(layer "B.SilkS")
			(hide yes)
			(effects
				(font
					(size 1.27 1.27)
				)
				(justify mirror)
			)
		)
		(property "Value" "120R2F-GP"
			(at -0.064008 -3.993896 180)
			(unlocked yes)
			(layer "B.Fab")
			(hide yes)
			(effects
				(font
					(size 1.016 1.016)
					(thickness 0.1524)
				)
				(justify mirror)
			)
		)
		(property "Device Type" "R402H16"
			(at -0.064008 -5.517896 180)
			(unlocked yes)
			(layer "B.Fab")
			(hide yes)
			(effects
				(font
					(size 1.016 1.016)
					(thickness 0.1524)
				)
				(justify mirror)
			)
		)
		(duplicate_pad_numbers_are_jumpers no)
		(fp_line
			(start 0.508 -0.9398)
			(end 0.508 0.9398)
			(stroke
				(width 0.1524)
				(type default)
			)
			(layer "B.SilkS")
		)
		(fp_line
			(start -0.508 -0.9398)
			(end 0.508 -0.9398)
			(stroke
				(width 0.1524)
				(type default)
			)
			(layer "B.SilkS")
		)
		(fp_rect
			(start 0.508 0.9398)
			(end -0.508 -0.9398)
			(stroke
				(width 0)
				(type default)
			)
			(fill no)
			(layer "B.CrtYd")
		)
		(fp_rect
			(start 0.508 0.9398)
			(end -0.508 -0.9398)
			(stroke
				(width 0)
				(type default)
			)
			(fill no)
			(layer "B.Fab")
		)
		(pad "1" smd custom
			(at 0 -0.4445)
			(size 0.1397 0.1397)
			(layers "B.Cu" "B.Mask" "B.Paste")
			(net "GND")
			(options
				(clearance outline)
				(anchor circle)
			)
			(primitives
				(gr_poly
					(pts
						(arc
							(start -0.1778 0.2794)
							(mid -0.249642 0.249642)
							(end -0.2794 0.1778)
						)
						(arc
							(start -0.2794 -0.1778)
							(mid -0.249642 -0.249642)
							(end -0.1778 -0.2794)
						)
						(arc
							(start 0.1778 -0.2794)
							(mid 0.249642 -0.249642)
							(end 0.2794 -0.1778)
						)
						(arc
							(start 0.2794 0.1778)
							(mid 0.249642 0.249642)
							(end 0.1778 0.2794)
						)
					)
					(width 0)
					(fill yes)
				)
			)
		)
		(pad "2" smd custom
			(at 0 0.4445)
			(size 0.1397 0.1397)
			(layers "B.Cu" "B.Mask" "B.Paste")
			(net "MEMA_9")
			(options
				(clearance outline)
				(anchor circle)
			)
			(primitives
				(gr_poly
					(pts
						(arc
							(start -0.1778 0.2794)
							(mid -0.249642 0.249642)
							(end -0.2794 0.1778)
						)
						(arc
							(start -0.2794 -0.1778)
							(mid -0.249642 -0.249642)
							(end -0.1778 -0.2794)
						)
						(arc
							(start 0.1778 -0.2794)
							(mid 0.249642 -0.249642)
							(end 0.2794 -0.1778)
						)
						(arc
							(start 0.2794 0.1778)
							(mid 0.249642 0.249642)
							(end 0.1778 0.2794)
						)
					)
					(width 0)
					(fill yes)
				)
			)
		)
	)
	(footprint ""
		(layer "B.Cu")
		(at 59.5884 -161.0106 -90)
		(property "Reference" "C119"
			(at 0 0 90)
			(layer "B.SilkS")
			(hide yes)
			(effects
				(font
					(size 1.27 1.27)
				)
				(justify mirror)
			)
		)
		(property "Value" "SCD1U25V2KX-2-GP"
			(at -1.1811 -2.7051 270)
			(unlocked yes)
			(layer "B.Fab")
			(hide yes)
			(effects
				(font
					(size 1.016 1.016)
					(thickness 0.1524)
				)
				(justify mirror)
			)
		)
		(property "Device Type" "C402H22"
			(at -1.1811 -4.2291 270)
			(unlocked yes)
			(layer "B.Fab")
			(hide yes)
			(effects
				(font
					(size 1.016 1.016)
					(thickness 0.1524)
				)
				(justify mirror)
			)
		)
		(duplicate_pad_numbers_are_jumpers no)
		(fp_rect
			(start 0.4318 0.9525)
			(end -0.4318 -0.9525)
			(stroke
				(width 0)
				(type default)
			)
			(fill no)
			(layer "B.CrtYd")
		)
		(fp_rect
			(start 0.4318 0.9525)
			(end -0.4318 -0.9525)
			(stroke
				(width 0)
				(type default)
			)
			(fill no)
			(layer "B.Fab")
		)
		(pad "1" smd custom
			(at 0 -0.4445 90)
			(size 0.1524 0.1524)
			(layers "B.Cu" "B.Mask" "B.Paste")
			(net "ADC_P1V8")
			(options
				(clearance outline)
				(anchor circle)
			)
			(primitives
				(gr_poly
					(pts
						(arc
							(start 0.3048 0.2032)
							(mid 0.275042 0.275042)
							(end 0.2032 0.3048)
						)
						(arc
							(start -0.2032 0.3048)
							(mid -0.275042 0.275042)
							(end -0.3048 0.2032)
						)
						(arc
							(start -0.3048 -0.2032)
							(mid -0.275042 -0.275042)
							(end -0.2032 -0.3048)
						)
						(arc
							(start 0.2032 -0.3048)
							(mid 0.275042 -0.275042)
							(end 0.3048 -0.2032)
						)
					)
					(width 0)
					(fill yes)
				)
			)
		)
		(pad "2" smd custom
			(at 0 0.4445 90)
			(size 0.1524 0.1524)
			(layers "B.Cu" "B.Mask" "B.Paste")
			(net "GND")
			(options
				(clearance outline)
				(anchor circle)
			)
			(primitives
				(gr_poly
					(pts
						(arc
							(start 0.3048 0.2032)
							(mid 0.275042 0.275042)
							(end 0.2032 0.3048)
						)
						(arc
							(start -0.2032 0.3048)
							(mid -0.275042 0.275042)
							(end -0.3048 0.2032)
						)
						(arc
							(start -0.3048 -0.2032)
							(mid -0.275042 -0.275042)
							(end -0.2032 -0.3048)
						)
						(arc
							(start 0.2032 -0.3048)
							(mid 0.275042 -0.275042)
							(end 0.3048 -0.2032)
						)
					)
					(width 0)
					(fill yes)
				)
			)
		)
	)
	(footprint ""
		(layer "B.Cu")
		(at 61.9506 -137.9474 -90)
		(property "Reference" "R785"
			(at 0 0 90)
			(layer "B.SilkS")
			(hide yes)
			(effects
				(font
					(size 1.27 1.27)
				)
				(justify mirror)
			)
		)
		(property "Value" "10KR2F-2-GP"
			(at -0.064008 -3.993896 270)
			(unlocked yes)
			(layer "B.Fab")
			(hide yes)
			(effects
				(font
					(size 1.016 1.016)
					(thickness 0.1524)
				)
				(justify mirror)
			)
		)
		(property "Device Type" "R402H16"
			(at -0.064008 -5.517896 270)
			(unlocked yes)
			(layer "B.Fab")
			(hide yes)
			(effects
				(font
					(size 1.016 1.016)
					(thickness 0.1524)
				)
				(justify mirror)
			)
		)
		(duplicate_pad_numbers_are_jumpers no)
		(fp_line
			(start -0.508 -0.9398)
			(end 0.508 -0.9398)
			(stroke
				(width 0.1524)
				(type default)
			)
			(layer "B.SilkS")
		)
		(fp_line
			(start 0.508 -0.9398)
			(end 0.508 0.9398)
			(stroke
				(width 0.1524)
				(type default)
			)
			(layer "B.SilkS")
		)
		(fp_rect
			(start 0.508 0.9398)
			(end -0.508 -0.9398)
			(stroke
				(width 0)
				(type default)
			)
			(fill no)
			(layer "B.CrtYd")
		)
		(fp_rect
			(start 0.508 0.9398)
			(end -0.508 -0.9398)
			(stroke
				(width 0)
				(type default)
			)
			(fill no)
			(layer "B.Fab")
		)
		(pad "1" smd custom
			(at 0 -0.4445 90)
			(size 0.1397 0.1397)
			(layers "B.Cu" "B.Mask" "B.Paste")
			(net "P3V3_STBY")
			(options
				(clearance outline)
				(anchor circle)
			)
			(primitives
				(gr_poly
					(pts
						(arc
							(start -0.1778 0.2794)
							(mid -0.249642 0.249642)
							(end -0.2794 0.1778)
						)
						(arc
							(start -0.2794 -0.1778)
							(mid -0.249642 -0.249642)
							(end -0.1778 -0.2794)
						)
						(arc
							(start 0.1778 -0.2794)
							(mid 0.249642 -0.249642)
							(end 0.2794 -0.1778)
						)
						(arc
							(start 0.2794 0.1778)
							(mid 0.249642 0.249642)
							(end 0.1778 0.2794)
						)
					)
					(width 0)
					(fill yes)
				)
			)
		)
		(pad "2" smd custom
			(at 0 0.4445 90)
			(size 0.1397 0.1397)
			(layers "B.Cu" "B.Mask" "B.Paste")
			(net "TP_BMC_GPIOA0")
			(options
				(clearance outline)
				(anchor circle)
			)
			(primitives
				(gr_poly
					(pts
						(arc
							(start -0.1778 0.2794)
							(mid -0.249642 0.249642)
							(end -0.2794 0.1778)
						)
						(arc
							(start -0.2794 -0.1778)
							(mid -0.249642 -0.249642)
							(end -0.1778 -0.2794)
						)
						(arc
							(start 0.1778 -0.2794)
							(mid 0.249642 -0.249642)
							(end 0.2794 -0.1778)
						)
						(arc
							(start 0.2794 0.1778)
							(mid 0.249642 0.249642)
							(end 0.1778 0.2794)
						)
					)
					(width 0)
					(fill yes)
				)
			)
		)
	)
	(footprint ""
		(layer "B.Cu")
		(at 54.6354 -135.7122 180)
		(property "Reference" "R353"
			(at 0 0 0)
			(layer "B.SilkS")
			(hide yes)
			(effects
				(font
					(size 1.27 1.27)
				)
				(justify mirror)
			)
		)
		(property "Value" "4K7R2F-GP"
			(at -0.064008 -3.993896 180)
			(unlocked yes)
			(layer "B.Fab")
			(hide yes)
			(effects
				(font
					(size 1.016 1.016)
					(thickness 0.1524)
				)
				(justify mirror)
			)
		)
		(property "Device Type" "R402H16"
			(at -0.064008 -5.517896 180)
			(unlocked yes)
			(layer "B.Fab")
			(hide yes)
			(effects
				(font
					(size 1.016 1.016)
					(thickness 0.1524)
				)
				(justify mirror)
			)
		)
		(duplicate_pad_numbers_are_jumpers no)
		(fp_line
			(start 0.508 -0.9398)
			(end 0.508 0.9398)
			(stroke
				(width 0.1524)
				(type default)
			)
			(layer "B.SilkS")
		)
		(fp_line
			(start -0.508 -0.9398)
			(end 0.508 -0.9398)
			(stroke
				(width 0.1524)
				(type default)
			)
			(layer "B.SilkS")
		)
		(fp_rect
			(start 0.508 0.9398)
			(end -0.508 -0.9398)
			(stroke
				(width 0)
				(type default)
			)
			(fill no)
			(layer "B.CrtYd")
		)
		(fp_rect
			(start 0.508 0.9398)
			(end -0.508 -0.9398)
			(stroke
				(width 0)
				(type default)
			)
			(fill no)
			(layer "B.Fab")
		)
		(pad "1" smd custom
			(at 0 -0.4445)
			(size 0.1397 0.1397)
			(layers "B.Cu" "B.Mask" "B.Paste")
			(net "P3V3_STBY")
			(options
				(clearance outline)
				(anchor circle)
			)
			(primitives
				(gr_poly
					(pts
						(arc
							(start -0.1778 0.2794)
							(mid -0.249642 0.249642)
							(end -0.2794 0.1778)
						)
						(arc
							(start -0.2794 -0.1778)
							(mid -0.249642 -0.249642)
							(end -0.1778 -0.2794)
						)
						(arc
							(start 0.1778 -0.2794)
							(mid 0.249642 -0.249642)
							(end 0.2794 -0.1778)
						)
						(arc
							(start 0.2794 0.1778)
							(mid 0.249642 0.249642)
							(end 0.1778 0.2794)
						)
					)
					(width 0)
					(fill yes)
				)
			)
		)
		(pad "2" smd custom
			(at 0 0.4445)
			(size 0.1397 0.1397)
			(layers "B.Cu" "B.Mask" "B.Paste")
			(net "SLOTID_1")
			(options
				(clearance outline)
				(anchor circle)
			)
			(primitives
				(gr_poly
					(pts
						(arc
							(start -0.1778 0.2794)
							(mid -0.249642 0.249642)
							(end -0.2794 0.1778)
						)
						(arc
							(start -0.2794 -0.1778)
							(mid -0.249642 -0.249642)
							(end -0.1778 -0.2794)
						)
						(arc
							(start 0.1778 -0.2794)
							(mid 0.249642 -0.249642)
							(end 0.2794 -0.1778)
						)
						(arc
							(start 0.2794 0.1778)
							(mid 0.249642 0.249642)
							(end 0.1778 0.2794)
						)
					)
					(width 0)
					(fill yes)
				)
			)
		)
	)
	(footprint ""
		(layer "B.Cu")
		(at 24.666702 -143.811244 180)
		(property "Reference" "C69"
			(at 0 0 0)
			(layer "B.SilkS")
			(hide yes)
			(effects
				(font
					(size 1.27 1.27)
				)
				(justify mirror)
			)
		)
		(property "Value" "SCD1U16V2KX-3GP"
			(at -1.1811 -2.7051 180)
			(unlocked yes)
			(layer "B.Fab")
			(hide yes)
			(effects
				(font
					(size 1.016 1.016)
					(thickness 0.1524)
				)
				(justify mirror)
			)
		)
		(property "Device Type" "C402H22"
			(at -1.1811 -4.2291 180)
			(unlocked yes)
			(layer "B.Fab")
			(hide yes)
			(effects
				(font
					(size 1.016 1.016)
					(thickness 0.1524)
				)
				(justify mirror)
			)
		)
		(duplicate_pad_numbers_are_jumpers no)
		(fp_rect
			(start 0.4318 0.9525)
			(end -0.4318 -0.9525)
			(stroke
				(width 0)
				(type default)
			)
			(fill no)
			(layer "B.CrtYd")
		)
		(fp_rect
			(start 0.4318 0.9525)
			(end -0.4318 -0.9525)
			(stroke
				(width 0)
				(type default)
			)
			(fill no)
			(layer "B.Fab")
		)
		(pad "1" smd custom
			(at 0 -0.4445)
			(size 0.1524 0.1524)
			(layers "B.Cu" "B.Mask" "B.Paste")
			(net "GND")
			(options
				(clearance outline)
				(anchor circle)
			)
			(primitives
				(gr_poly
					(pts
						(arc
							(start 0.3048 0.2032)
							(mid 0.275042 0.275042)
							(end 0.2032 0.3048)
						)
						(arc
							(start -0.2032 0.3048)
							(mid -0.275042 0.275042)
							(end -0.3048 0.2032)
						)
						(arc
							(start -0.3048 -0.2032)
							(mid -0.275042 -0.275042)
							(end -0.2032 -0.3048)
						)
						(arc
							(start 0.2032 -0.3048)
							(mid 0.275042 -0.275042)
							(end 0.3048 -0.2032)
						)
					)
					(width 0)
					(fill yes)
				)
			)
		)
		(pad "2" smd custom
			(at 0 0.4445)
			(size 0.1524 0.1524)
			(layers "B.Cu" "B.Mask" "B.Paste")
			(net "P1V2_STBY")
			(options
				(clearance outline)
				(anchor circle)
			)
			(primitives
				(gr_poly
					(pts
						(arc
							(start 0.3048 0.2032)
							(mid 0.275042 0.275042)
							(end 0.2032 0.3048)
						)
						(arc
							(start -0.2032 0.3048)
							(mid -0.275042 0.275042)
							(end -0.3048 0.2032)
						)
						(arc
							(start -0.3048 -0.2032)
							(mid -0.275042 -0.275042)
							(end -0.2032 -0.3048)
						)
						(arc
							(start 0.2032 -0.3048)
							(mid 0.275042 -0.275042)
							(end 0.3048 -0.2032)
						)
					)
					(width 0)
					(fill yes)
				)
			)
		)
	)
	(footprint ""
		(layer "B.Cu")
		(at 62.52083 -142.142972)
		(property "Reference" "R195"
			(at 0 0 0)
			(layer "B.SilkS")
			(hide yes)
			(effects
				(font
					(size 1.27 1.27)
				)
				(justify mirror)
			)
		)
		(property "Value" "2K2R2F-GP"
			(at -0.064008 -3.993896 0)
			(unlocked yes)
			(layer "B.Fab")
			(hide yes)
			(effects
				(font
					(size 1.016 1.016)
					(thickness 0.1524)
				)
				(justify mirror)
			)
		)
		(property "Device Type" "R402H16"
			(at -0.064008 -5.517896 0)
			(unlocked yes)
			(layer "B.Fab")
			(hide yes)
			(effects
				(font
					(size 1.016 1.016)
					(thickness 0.1524)
				)
				(justify mirror)
			)
		)
		(duplicate_pad_numbers_are_jumpers no)
		(fp_line
			(start -0.508 -0.9398)
			(end 0.508 -0.9398)
			(stroke
				(width 0.1524)
				(type default)
			)
			(layer "B.SilkS")
		)
		(fp_line
			(start 0.508 -0.9398)
			(end 0.508 0.9398)
			(stroke
				(width 0.1524)
				(type default)
			)
			(layer "B.SilkS")
		)
		(fp_rect
			(start 0.508 0.9398)
			(end -0.508 -0.9398)
			(stroke
				(width 0)
				(type default)
			)
			(fill no)
			(layer "B.CrtYd")
		)
		(fp_rect
			(start 0.508 0.9398)
			(end -0.508 -0.9398)
			(stroke
				(width 0)
				(type default)
			)
			(fill no)
			(layer "B.Fab")
		)
		(pad "1" smd custom
			(at 0 -0.4445 180)
			(size 0.1397 0.1397)
			(layers "B.Cu" "B.Mask" "B.Paste")
			(net "I2C_EXP_LOC_SCL_OUT")
			(options
				(clearance outline)
				(anchor circle)
			)
			(primitives
				(gr_poly
					(pts
						(arc
							(start -0.1778 0.2794)
							(mid -0.249642 0.249642)
							(end -0.2794 0.1778)
						)
						(arc
							(start -0.2794 -0.1778)
							(mid -0.249642 -0.249642)
							(end -0.1778 -0.2794)
						)
						(arc
							(start 0.1778 -0.2794)
							(mid 0.249642 -0.249642)
							(end 0.2794 -0.1778)
						)
						(arc
							(start 0.2794 0.1778)
							(mid 0.249642 0.249642)
							(end 0.1778 0.2794)
						)
					)
					(width 0)
					(fill yes)
				)
			)
		)
		(pad "2" smd custom
			(at 0 0.4445 180)
			(size 0.1397 0.1397)
			(layers "B.Cu" "B.Mask" "B.Paste")
			(net "P3V3_STBY")
			(options
				(clearance outline)
				(anchor circle)
			)
			(primitives
				(gr_poly
					(pts
						(arc
							(start -0.1778 0.2794)
							(mid -0.249642 0.249642)
							(end -0.2794 0.1778)
						)
						(arc
							(start -0.2794 -0.1778)
							(mid -0.249642 -0.249642)
							(end -0.1778 -0.2794)
						)
						(arc
							(start 0.1778 -0.2794)
							(mid 0.249642 -0.249642)
							(end 0.2794 -0.1778)
						)
						(arc
							(start 0.2794 0.1778)
							(mid 0.249642 0.249642)
							(end 0.1778 0.2794)
						)
					)
					(width 0)
					(fill yes)
				)
			)
		)
	)
	(footprint ""
		(layer "B.Cu")
		(at 187.989718 -81.153 180)
		(property "Reference" "C304"
			(at 0 0 0)
			(layer "B.SilkS")
			(hide yes)
			(effects
				(font
					(size 1.27 1.27)
				)
				(justify mirror)
			)
		)
		(property "Value" "SCD22U10V1KX-GP"
			(at 2.8321 -1.7399 180)
			(unlocked yes)
			(layer "B.Fab")
			(hide yes)
			(effects
				(font
					(size 1.016 1.016)
					(thickness 0.1524)
				)
				(justify mirror)
			)
		)
		(property "Device Type" "C0201H13"
			(at 2.8321 -3.2639 180)
			(unlocked yes)
			(layer "B.Fab")
			(hide yes)
			(effects
				(font
					(size 1.016 1.016)
					(thickness 0.1524)
				)
				(justify mirror)
			)
		)
		(duplicate_pad_numbers_are_jumpers no)
		(fp_rect
			(start 0.2794 0.6477)
			(end -0.2794 -0.6477)
			(stroke
				(width 0)
				(type default)
			)
			(fill no)
			(layer "B.CrtYd")
		)
		(fp_rect
			(start 0.2794 0.6477)
			(end -0.2794 -0.6477)
			(stroke
				(width 0)
				(type default)
			)
			(fill no)
			(layer "B.Fab")
		)
		(pad "1" smd custom
			(at 0 -0.2794)
			(size 0.0762 0.0762)
			(layers "B.Cu" "B.Mask" "B.Paste")
			(net "PCIE_IOM_TO_COMP_15_DN_C")
			(options
				(clearance outline)
				(anchor circle)
			)
			(primitives
				(gr_poly
					(pts
						(arc
							(start 0.1524 0.127)
							(mid 0.137521 0.162921)
							(end 0.1016 0.1778)
						)
						(arc
							(start -0.1016 0.1778)
							(mid -0.137521 0.162921)
							(end -0.1524 0.127)
						)
						(arc
							(start -0.1524 -0.127)
							(mid -0.137521 -0.162921)
							(end -0.1016 -0.1778)
						)
						(arc
							(start 0.1016 -0.1778)
							(mid 0.137521 -0.162921)
							(end 0.1524 -0.127)
						)
					)
					(width 0)
					(fill yes)
				)
			)
		)
		(pad "2" smd custom
			(at 0 0.2794)
			(size 0.0762 0.0762)
			(layers "B.Cu" "B.Mask" "B.Paste")
			(net "PCIE_IOM_TO_COMP_15_DN")
			(options
				(clearance outline)
				(anchor circle)
			)
			(primitives
				(gr_poly
					(pts
						(arc
							(start 0.1524 0.127)
							(mid 0.137521 0.162921)
							(end 0.1016 0.1778)
						)
						(arc
							(start -0.1016 0.1778)
							(mid -0.137521 0.162921)
							(end -0.1524 0.127)
						)
						(arc
							(start -0.1524 -0.127)
							(mid -0.137521 -0.162921)
							(end -0.1016 -0.1778)
						)
						(arc
							(start 0.1016 -0.1778)
							(mid 0.137521 -0.162921)
							(end 0.1524 -0.127)
						)
					)
					(width 0)
					(fill yes)
				)
			)
		)
	)
	(footprint ""
		(layer "B.Cu")
		(at 44.6024 -131.318 -90)
		(property "Reference" "R293"
			(at 0 0 90)
			(layer "B.SilkS")
			(hide yes)
			(effects
				(font
					(size 1.27 1.27)
				)
				(justify mirror)
			)
		)
		(property "Value" "0R2J-2-GP"
			(at -0.064008 -3.993896 270)
			(unlocked yes)
			(layer "B.Fab")
			(hide yes)
			(effects
				(font
					(size 1.016 1.016)
					(thickness 0.1524)
				)
				(justify mirror)
			)
		)
		(property "Device Type" "R402H16"
			(at -0.064008 -5.517896 270)
			(unlocked yes)
			(layer "B.Fab")
			(hide yes)
			(effects
				(font
					(size 1.016 1.016)
					(thickness 0.1524)
				)
				(justify mirror)
			)
		)
		(duplicate_pad_numbers_are_jumpers no)
		(fp_line
			(start -0.508 -0.9398)
			(end 0.508 -0.9398)
			(stroke
				(width 0.1524)
				(type default)
			)
			(layer "B.SilkS")
		)
		(fp_line
			(start 0.508 -0.9398)
			(end 0.508 0.9398)
			(stroke
				(width 0.1524)
				(type default)
			)
			(layer "B.SilkS")
		)
		(fp_rect
			(start 0.508 0.9398)
			(end -0.508 -0.9398)
			(stroke
				(width 0)
				(type default)
			)
			(fill no)
			(layer "B.CrtYd")
		)
		(fp_rect
			(start 0.508 0.9398)
			(end -0.508 -0.9398)
			(stroke
				(width 0)
				(type default)
			)
			(fill no)
			(layer "B.Fab")
		)
		(pad "1" smd custom
			(at 0 -0.4445 90)
			(size 0.1397 0.1397)
			(layers "B.Cu" "B.Mask" "B.Paste")
			(net "IOM_FULL_PWR_EN")
			(options
				(clearance outline)
				(anchor circle)
			)
			(primitives
				(gr_poly
					(pts
						(arc
							(start -0.1778 0.2794)
							(mid -0.249642 0.249642)
							(end -0.2794 0.1778)
						)
						(arc
							(start -0.2794 -0.1778)
							(mid -0.249642 -0.249642)
							(end -0.1778 -0.2794)
						)
						(arc
							(start 0.1778 -0.2794)
							(mid 0.249642 -0.249642)
							(end 0.2794 -0.1778)
						)
						(arc
							(start 0.2794 0.1778)
							(mid 0.249642 0.249642)
							(end 0.1778 0.2794)
						)
					)
					(width 0)
					(fill yes)
				)
			)
		)
		(pad "2" smd custom
			(at 0 0.4445 90)
			(size 0.1397 0.1397)
			(layers "B.Cu" "B.Mask" "B.Paste")
			(net "IOM_FULL_PWR_EN_R")
			(options
				(clearance outline)
				(anchor circle)
			)
			(primitives
				(gr_poly
					(pts
						(arc
							(start -0.1778 0.2794)
							(mid -0.249642 0.249642)
							(end -0.2794 0.1778)
						)
						(arc
							(start -0.2794 -0.1778)
							(mid -0.249642 -0.249642)
							(end -0.1778 -0.2794)
						)
						(arc
							(start 0.1778 -0.2794)
							(mid 0.249642 -0.249642)
							(end 0.2794 -0.1778)
						)
						(arc
							(start 0.2794 0.1778)
							(mid 0.249642 0.249642)
							(end 0.1778 0.2794)
						)
					)
					(width 0)
					(fill yes)
				)
			)
		)
	)
	(footprint ""
		(layer "B.Cu")
		(at 96.139 -146.431)
		(property "Reference" "C127"
			(at 0 0 0)
			(layer "B.SilkS")
			(hide yes)
			(effects
				(font
					(size 1.27 1.27)
				)
				(justify mirror)
			)
		)
		(property "Value" "SCD1U16V2KX-3GP"
			(at -1.1811 -2.7051 0)
			(unlocked yes)
			(layer "B.Fab")
			(hide yes)
			(effects
				(font
					(size 1.016 1.016)
					(thickness 0.1524)
				)
				(justify mirror)
			)
		)
		(property "Device Type" "C402H22"
			(at -1.1811 -4.2291 0)
			(unlocked yes)
			(layer "B.Fab")
			(hide yes)
			(effects
				(font
					(size 1.016 1.016)
					(thickness 0.1524)
				)
				(justify mirror)
			)
		)
		(duplicate_pad_numbers_are_jumpers no)
		(fp_rect
			(start 0.4318 0.9525)
			(end -0.4318 -0.9525)
			(stroke
				(width 0)
				(type default)
			)
			(fill no)
			(layer "B.CrtYd")
		)
		(fp_rect
			(start 0.4318 0.9525)
			(end -0.4318 -0.9525)
			(stroke
				(width 0)
				(type default)
			)
			(fill no)
			(layer "B.Fab")
		)
		(pad "1" smd custom
			(at 0 -0.4445 180)
			(size 0.1524 0.1524)
			(layers "B.Cu" "B.Mask" "B.Paste")
			(net "P3V3_STBY")
			(options
				(clearance outline)
				(anchor circle)
			)
			(primitives
				(gr_poly
					(pts
						(arc
							(start 0.3048 0.2032)
							(mid 0.275042 0.275042)
							(end 0.2032 0.3048)
						)
						(arc
							(start -0.2032 0.3048)
							(mid -0.275042 0.275042)
							(end -0.3048 0.2032)
						)
						(arc
							(start -0.3048 -0.2032)
							(mid -0.275042 -0.275042)
							(end -0.2032 -0.3048)
						)
						(arc
							(start 0.2032 -0.3048)
							(mid 0.275042 -0.275042)
							(end 0.3048 -0.2032)
						)
					)
					(width 0)
					(fill yes)
				)
			)
		)
		(pad "2" smd custom
			(at 0 0.4445 180)
			(size 0.1524 0.1524)
			(layers "B.Cu" "B.Mask" "B.Paste")
			(net "GND")
			(options
				(clearance outline)
				(anchor circle)
			)
			(primitives
				(gr_poly
					(pts
						(arc
							(start 0.3048 0.2032)
							(mid 0.275042 0.275042)
							(end 0.2032 0.3048)
						)
						(arc
							(start -0.2032 0.3048)
							(mid -0.275042 0.275042)
							(end -0.3048 0.2032)
						)
						(arc
							(start -0.3048 -0.2032)
							(mid -0.275042 -0.275042)
							(end -0.2032 -0.3048)
						)
						(arc
							(start 0.2032 -0.3048)
							(mid 0.275042 -0.275042)
							(end 0.3048 -0.2032)
						)
					)
					(width 0)
					(fill yes)
				)
			)
		)
	)
	(footprint ""
		(layer "B.Cu")
		(at 195.9356 -66.6623 90)
		(property "Reference" "C390"
			(at 0 0 90)
			(layer "B.SilkS")
			(hide yes)
			(effects
				(font
					(size 1.27 1.27)
				)
				(justify mirror)
			)
		)
		(property "Value" "SC1U16V2KX-7-GP"
			(at -1.7526 -1.6002 90)
			(unlocked yes)
			(layer "B.Fab")
			(hide yes)
			(effects
				(font
					(size 1.016 1.016)
					(thickness 0.1524)
				)
				(justify mirror)
			)
		)
		(property "Device Type" "C402-TO0D2H24"
			(at -1.7526 -3.1242 90)
			(unlocked yes)
			(layer "B.Fab")
			(hide yes)
			(effects
				(font
					(size 1.016 1.016)
					(thickness 0.1524)
				)
				(justify mirror)
			)
		)
		(duplicate_pad_numbers_are_jumpers no)
		(fp_rect
			(start 0.4826 0.889)
			(end -0.4826 -0.889)
			(stroke
				(width 0)
				(type default)
			)
			(fill no)
			(layer "B.CrtYd")
		)
		(fp_rect
			(start 0.4826 0.889)
			(end -0.4826 -0.889)
			(stroke
				(width 0)
				(type default)
			)
			(fill no)
			(layer "B.Fab")
		)
		(pad "1" smd custom
			(at 0 -0.4572 270)
			(size 0.1524 0.1524)
			(layers "B.Cu" "B.Mask" "B.Paste")
			(net "P0V975")
			(options
				(clearance outline)
				(anchor circle)
			)
			(primitives
				(gr_poly
					(pts
						(arc
							(start -0.254 -0.3048)
							(mid -0.325842 -0.275042)
							(end -0.3556 -0.2032)
						)
						(arc
							(start -0.3556 0.2032)
							(mid -0.325842 0.275042)
							(end -0.254 0.3048)
						)
						(arc
							(start 0.254 0.3048)
							(mid 0.325842 0.275042)
							(end 0.3556 0.2032)
						)
						(arc
							(start 0.3556 -0.2032)
							(mid 0.325842 -0.275042)
							(end 0.254 -0.3048)
						)
					)
					(width 0)
					(fill yes)
				)
			)
		)
		(pad "2" smd custom
			(at 0 0.4572 270)
			(size 0.1524 0.1524)
			(layers "B.Cu" "B.Mask" "B.Paste")
			(net "GND")
			(options
				(clearance outline)
				(anchor circle)
			)
			(primitives
				(gr_poly
					(pts
						(arc
							(start -0.254 -0.3048)
							(mid -0.325842 -0.275042)
							(end -0.3556 -0.2032)
						)
						(arc
							(start -0.3556 0.2032)
							(mid -0.325842 0.275042)
							(end -0.254 0.3048)
						)
						(arc
							(start 0.254 0.3048)
							(mid 0.325842 0.275042)
							(end 0.3556 0.2032)
						)
						(arc
							(start 0.3556 -0.2032)
							(mid 0.325842 -0.275042)
							(end 0.254 -0.3048)
						)
					)
					(width 0)
					(fill yes)
				)
			)
		)
	)
	(footprint ""
		(layer "B.Cu")
		(at 192.405 -65.3796 90)
		(property "Reference" "C406"
			(at 0 0 90)
			(layer "B.SilkS")
			(hide yes)
			(effects
				(font
					(size 1.27 1.27)
				)
				(justify mirror)
			)
		)
		(property "Value" "SCD1U6D3V1KX-GP"
			(at 2.8321 -1.7399 90)
			(unlocked yes)
			(layer "B.Fab")
			(hide yes)
			(effects
				(font
					(size 1.016 1.016)
					(thickness 0.1524)
				)
				(justify mirror)
			)
		)
		(property "Device Type" "C0201H13"
			(at 2.8321 -3.2639 90)
			(unlocked yes)
			(layer "B.Fab")
			(hide yes)
			(effects
				(font
					(size 1.016 1.016)
					(thickness 0.1524)
				)
				(justify mirror)
			)
		)
		(duplicate_pad_numbers_are_jumpers no)
		(fp_rect
			(start 0.2794 0.6477)
			(end -0.2794 -0.6477)
			(stroke
				(width 0)
				(type default)
			)
			(fill no)
			(layer "B.CrtYd")
		)
		(fp_rect
			(start 0.2794 0.6477)
			(end -0.2794 -0.6477)
			(stroke
				(width 0)
				(type default)
			)
			(fill no)
			(layer "B.Fab")
		)
		(pad "1" smd custom
			(at 0 -0.2794 270)
			(size 0.0762 0.0762)
			(layers "B.Cu" "B.Mask" "B.Paste")
			(net "P0V975")
			(options
				(clearance outline)
				(anchor circle)
			)
			(primitives
				(gr_poly
					(pts
						(arc
							(start 0.1524 0.127)
							(mid 0.137521 0.162921)
							(end 0.1016 0.1778)
						)
						(arc
							(start -0.1016 0.1778)
							(mid -0.137521 0.162921)
							(end -0.1524 0.127)
						)
						(arc
							(start -0.1524 -0.127)
							(mid -0.137521 -0.162921)
							(end -0.1016 -0.1778)
						)
						(arc
							(start 0.1016 -0.1778)
							(mid 0.137521 -0.162921)
							(end 0.1524 -0.127)
						)
					)
					(width 0)
					(fill yes)
				)
			)
		)
		(pad "2" smd custom
			(at 0 0.2794 270)
			(size 0.0762 0.0762)
			(layers "B.Cu" "B.Mask" "B.Paste")
			(net "GND")
			(options
				(clearance outline)
				(anchor circle)
			)
			(primitives
				(gr_poly
					(pts
						(arc
							(start 0.1524 0.127)
							(mid 0.137521 0.162921)
							(end 0.1016 0.1778)
						)
						(arc
							(start -0.1016 0.1778)
							(mid -0.137521 0.162921)
							(end -0.1524 0.127)
						)
						(arc
							(start -0.1524 -0.127)
							(mid -0.137521 -0.162921)
							(end -0.1016 -0.1778)
						)
						(arc
							(start 0.1016 -0.1778)
							(mid 0.137521 -0.162921)
							(end 0.1524 -0.127)
						)
					)
					(width 0)
					(fill yes)
				)
			)
		)
	)
	(footprint ""
		(layer "B.Cu")
		(at 94.687136 -159.012128 90)
		(property "Reference" "R21"
			(at 0 0 90)
			(layer "B.SilkS")
			(hide yes)
			(effects
				(font
					(size 1.27 1.27)
				)
				(justify mirror)
			)
		)
		(property "Value" "4K7R2F-GP"
			(at -0.064008 -3.993896 90)
			(unlocked yes)
			(layer "B.Fab")
			(hide yes)
			(effects
				(font
					(size 1.016 1.016)
					(thickness 0.1524)
				)
				(justify mirror)
			)
		)
		(property "Device Type" "R402H16"
			(at -0.064008 -5.517896 90)
			(unlocked yes)
			(layer "B.Fab")
			(hide yes)
			(effects
				(font
					(size 1.016 1.016)
					(thickness 0.1524)
				)
				(justify mirror)
			)
		)
		(duplicate_pad_numbers_are_jumpers no)
		(fp_line
			(start 0.508 -0.9398)
			(end 0.508 0.9398)
			(stroke
				(width 0.1524)
				(type default)
			)
			(layer "B.SilkS")
		)
		(fp_line
			(start -0.508 -0.9398)
			(end 0.508 -0.9398)
			(stroke
				(width 0.1524)
				(type default)
			)
			(layer "B.SilkS")
		)
		(fp_rect
			(start 0.508 0.9398)
			(end -0.508 -0.9398)
			(stroke
				(width 0)
				(type default)
			)
			(fill no)
			(layer "B.CrtYd")
		)
		(fp_rect
			(start 0.508 0.9398)
			(end -0.508 -0.9398)
			(stroke
				(width 0)
				(type default)
			)
			(fill no)
			(layer "B.Fab")
		)
		(pad "1" smd custom
			(at 0 -0.4445 270)
			(size 0.1397 0.1397)
			(layers "B.Cu" "B.Mask" "B.Paste")
			(net "P3V3_STBY")
			(options
				(clearance outline)
				(anchor circle)
			)
			(primitives
				(gr_poly
					(pts
						(arc
							(start -0.1778 0.2794)
							(mid -0.249642 0.249642)
							(end -0.2794 0.1778)
						)
						(arc
							(start -0.2794 -0.1778)
							(mid -0.249642 -0.249642)
							(end -0.1778 -0.2794)
						)
						(arc
							(start 0.1778 -0.2794)
							(mid 0.249642 -0.249642)
							(end 0.2794 -0.1778)
						)
						(arc
							(start 0.2794 0.1778)
							(mid 0.249642 0.249642)
							(end 0.1778 0.2794)
						)
					)
					(width 0)
					(fill yes)
				)
			)
		)
		(pad "2" smd custom
			(at 0 0.4445 270)
			(size 0.1397 0.1397)
			(layers "B.Cu" "B.Mask" "B.Paste")
			(net "USB_RESET_N")
			(options
				(clearance outline)
				(anchor circle)
			)
			(primitives
				(gr_poly
					(pts
						(arc
							(start -0.1778 0.2794)
							(mid -0.249642 0.249642)
							(end -0.2794 0.1778)
						)
						(arc
							(start -0.2794 -0.1778)
							(mid -0.249642 -0.249642)
							(end -0.1778 -0.2794)
						)
						(arc
							(start 0.1778 -0.2794)
							(mid 0.249642 -0.249642)
							(end 0.2794 -0.1778)
						)
						(arc
							(start 0.2794 0.1778)
							(mid 0.249642 0.249642)
							(end 0.1778 0.2794)
						)
					)
					(width 0)
					(fill yes)
				)
			)
		)
	)
	(footprint ""
		(layer "B.Cu")
		(at 191.383666 -52.810156)
		(property "Reference" "TP150"
			(at 0 0 0)
			(layer "B.SilkS")
			(hide yes)
			(effects
				(font
					(size 1.27 1.27)
				)
				(justify mirror)
			)
		)
		(property "Value" "TPAD28-2-GP"
			(at 0.0127 -1.6637 0)
			(unlocked yes)
			(layer "B.Fab")
			(hide yes)
			(effects
				(font
					(size 1.016 1.016)
					(thickness 0.1524)
				)
				(justify mirror)
			)
		)
		(property "Device Type" "TPAD28"
			(at 0.0127 -3.1877 0)
			(unlocked yes)
			(layer "B.Fab")
			(hide yes)
			(effects
				(font
					(size 1.016 1.016)
					(thickness 0.1524)
				)
				(justify mirror)
			)
		)
		(duplicate_pad_numbers_are_jumpers no)
		(fp_poly
			(pts
				(arc
					(start 0.3556 0)
					(mid -0.3556 0)
					(end 0.3556 0)
				)
			)
			(stroke
				(width 0)
				(type default)
			)
			(fill no)
			(layer "B.CrtYd")
		)
		(fp_poly
			(pts
				(arc
					(start 0.6096 0)
					(mid -0.6096 0)
					(end 0.6096 0)
				)
			)
			(stroke
				(width 0)
				(type default)
			)
			(fill no)
			(layer "B.Fab")
		)
		(pad "1" smd circle
			(at 0 0 180)
			(size 0.7112 0.7112)
			(layers "B.Cu" "B.Mask" "B.Paste")
			(net "JTAG_IOC_TCK")
		)
	)
	(footprint ""
		(layer "B.Cu")
		(at 191.1858 -54.3814)
		(property "Reference" "TP153"
			(at 0 0 0)
			(layer "B.SilkS")
			(hide yes)
			(effects
				(font
					(size 1.27 1.27)
				)
				(justify mirror)
			)
		)
		(property "Value" "TPAD28-2-GP"
			(at 0.0127 -1.6637 0)
			(unlocked yes)
			(layer "B.Fab")
			(hide yes)
			(effects
				(font
					(size 1.016 1.016)
					(thickness 0.1524)
				)
				(justify mirror)
			)
		)
		(property "Device Type" "TPAD28"
			(at 0.0127 -3.1877 0)
			(unlocked yes)
			(layer "B.Fab")
			(hide yes)
			(effects
				(font
					(size 1.016 1.016)
					(thickness 0.1524)
				)
				(justify mirror)
			)
		)
		(duplicate_pad_numbers_are_jumpers no)
		(fp_poly
			(pts
				(arc
					(start 0.3556 0)
					(mid -0.3556 0)
					(end 0.3556 0)
				)
			)
			(stroke
				(width 0)
				(type default)
			)
			(fill no)
			(layer "B.CrtYd")
		)
		(fp_poly
			(pts
				(arc
					(start 0.6096 0)
					(mid -0.6096 0)
					(end 0.6096 0)
				)
			)
			(stroke
				(width 0)
				(type default)
			)
			(fill no)
			(layer "B.Fab")
		)
		(pad "1" smd circle
			(at 0 0 180)
			(size 0.7112 0.7112)
			(layers "B.Cu" "B.Mask" "B.Paste")
			(net "IOC_TDO")
		)
	)
	(footprint ""
		(layer "B.Cu")
		(at 184.1754 -116.0526 90)
		(property "Reference" "C275"
			(at 0 0 90)
			(layer "B.SilkS")
			(hide yes)
			(effects
				(font
					(size 1.27 1.27)
				)
				(justify mirror)
			)
		)
		(property "Value" "SC10U16V5KX-7-GP-U"
			(at 0.0762 -6.1214 90)
			(unlocked yes)
			(layer "B.Fab")
			(hide yes)
			(effects
				(font
					(size 1.016 1.016)
					(thickness 0.1524)
				)
				(justify mirror)
			)
		)
		(property "Device Type" "C805H58"
			(at 0.0762 -8.1534 90)
			(unlocked yes)
			(layer "B.Fab")
			(hide yes)
			(effects
				(font
					(size 1.016 1.016)
					(thickness 0.1524)
				)
				(justify mirror)
			)
		)
		(duplicate_pad_numbers_are_jumpers no)
		(fp_line
			(start -0.635 0)
			(end 0.635 0)
			(stroke
				(width 0.508)
				(type default)
			)
			(layer "B.SilkS")
		)
		(fp_rect
			(start 0.9652 1.778)
			(end -0.9652 -1.778)
			(stroke
				(width 0)
				(type default)
			)
			(fill no)
			(layer "B.CrtYd")
		)
		(fp_poly
			(pts
				(xy 0.9652 -1.778) (xy -0.9652 -1.778) (xy -0.9652 1.778) (xy 0.9652 1.778)
			)
			(stroke
				(width 0)
				(type default)
			)
			(fill no)
			(layer "B.Fab")
		)
		(pad "1" smd rect
			(at 0 -0.9652 270)
			(size 1.397 1.143)
			(layers "B.Cu" "B.Mask" "B.Paste")
			(net "VT235_VDDH")
		)
		(pad "2" smd rect
			(at 0 0.9652 270)
			(size 1.397 1.143)
			(layers "B.Cu" "B.Mask" "B.Paste")
			(net "GND")
		)
	)
	(footprint ""
		(layer "B.Cu")
		(at 201.092308 -52.334668 -90)
		(property "Reference" "C336"
			(at 0 0 90)
			(layer "B.SilkS")
			(hide yes)
			(effects
				(font
					(size 1.27 1.27)
				)
				(justify mirror)
			)
		)
		(property "Value" "SCD1U6D3V1KX-GP"
			(at 2.8321 -1.7399 270)
			(unlocked yes)
			(layer "B.Fab")
			(hide yes)
			(effects
				(font
					(size 1.016 1.016)
					(thickness 0.1524)
				)
				(justify mirror)
			)
		)
		(property "Device Type" "C0201H13"
			(at 2.8321 -3.2639 270)
			(unlocked yes)
			(layer "B.Fab")
			(hide yes)
			(effects
				(font
					(size 1.016 1.016)
					(thickness 0.1524)
				)
				(justify mirror)
			)
		)
		(duplicate_pad_numbers_are_jumpers no)
		(fp_rect
			(start 0.2794 0.6477)
			(end -0.2794 -0.6477)
			(stroke
				(width 0)
				(type default)
			)
			(fill no)
			(layer "B.CrtYd")
		)
		(fp_rect
			(start 0.2794 0.6477)
			(end -0.2794 -0.6477)
			(stroke
				(width 0)
				(type default)
			)
			(fill no)
			(layer "B.Fab")
		)
		(pad "1" smd custom
			(at 0 -0.2794 90)
			(size 0.0762 0.0762)
			(layers "B.Cu" "B.Mask" "B.Paste")
			(net "SYS_PLL_VDD")
			(options
				(clearance outline)
				(anchor circle)
			)
			(primitives
				(gr_poly
					(pts
						(arc
							(start 0.1524 0.127)
							(mid 0.137521 0.162921)
							(end 0.1016 0.1778)
						)
						(arc
							(start -0.1016 0.1778)
							(mid -0.137521 0.162921)
							(end -0.1524 0.127)
						)
						(arc
							(start -0.1524 -0.127)
							(mid -0.137521 -0.162921)
							(end -0.1016 -0.1778)
						)
						(arc
							(start 0.1016 -0.1778)
							(mid 0.137521 -0.162921)
							(end 0.1524 -0.127)
						)
					)
					(width 0)
					(fill yes)
				)
			)
		)
		(pad "2" smd custom
			(at 0 0.2794 90)
			(size 0.0762 0.0762)
			(layers "B.Cu" "B.Mask" "B.Paste")
			(net "GND")
			(options
				(clearance outline)
				(anchor circle)
			)
			(primitives
				(gr_poly
					(pts
						(arc
							(start 0.1524 0.127)
							(mid 0.137521 0.162921)
							(end 0.1016 0.1778)
						)
						(arc
							(start -0.1016 0.1778)
							(mid -0.137521 0.162921)
							(end -0.1524 0.127)
						)
						(arc
							(start -0.1524 -0.127)
							(mid -0.137521 -0.162921)
							(end -0.1016 -0.1778)
						)
						(arc
							(start 0.1016 -0.1778)
							(mid 0.137521 -0.162921)
							(end 0.1524 -0.127)
						)
					)
					(width 0)
					(fill yes)
				)
			)
		)
	)
	(footprint ""
		(layer "B.Cu")
		(at 12.7762 -148.9329 -90)
		(property "Reference" "C63"
			(at 0 0 90)
			(layer "B.SilkS")
			(hide yes)
			(effects
				(font
					(size 1.27 1.27)
				)
				(justify mirror)
			)
		)
		(property "Value" "SC4D7U25V5KX-1-GP"
			(at 0.0762 -6.1214 270)
			(unlocked yes)
			(layer "B.Fab")
			(hide yes)
			(effects
				(font
					(size 1.016 1.016)
					(thickness 0.1524)
				)
				(justify mirror)
			)
		)
		(property "Device Type" "C805H58"
			(at 0.0762 -8.1534 270)
			(unlocked yes)
			(layer "B.Fab")
			(hide yes)
			(effects
				(font
					(size 1.016 1.016)
					(thickness 0.1524)
				)
				(justify mirror)
			)
		)
		(duplicate_pad_numbers_are_jumpers no)
		(fp_line
			(start -0.635 0)
			(end 0.635 0)
			(stroke
				(width 0.508)
				(type default)
			)
			(layer "B.SilkS")
		)
		(fp_rect
			(start 0.9652 1.778)
			(end -0.9652 -1.778)
			(stroke
				(width 0)
				(type default)
			)
			(fill no)
			(layer "B.CrtYd")
		)
		(fp_poly
			(pts
				(xy 0.9652 -1.778) (xy -0.9652 -1.778) (xy -0.9652 1.778) (xy 0.9652 1.778)
			)
			(stroke
				(width 0)
				(type default)
			)
			(fill no)
			(layer "B.Fab")
		)
		(pad "1" smd rect
			(at 0 -0.9652 90)
			(size 1.397 1.143)
			(layers "B.Cu" "B.Mask" "B.Paste")
			(net "P1V2_STBY")
		)
		(pad "2" smd rect
			(at 0 0.9652 90)
			(size 1.397 1.143)
			(layers "B.Cu" "B.Mask" "B.Paste")
			(net "GND")
		)
	)
	(footprint ""
		(layer "B.Cu")
		(at 89.916 -161.2646 180)
		(property "Reference" "C16"
			(at 0 0 0)
			(layer "B.SilkS")
			(hide yes)
			(effects
				(font
					(size 1.27 1.27)
				)
				(justify mirror)
			)
		)
		(property "Value" "SC1U16V3KX-5GP"
			(at 0 -2.8194 180)
			(unlocked yes)
			(layer "B.Fab")
			(hide yes)
			(effects
				(font
					(size 1.016 1.016)
					(thickness 0.1524)
				)
				(justify mirror)
			)
		)
		(property "Device Type" "C603H36"
			(at 0 -4.3434 180)
			(unlocked yes)
			(layer "B.Fab")
			(hide yes)
			(effects
				(font
					(size 1.016 1.016)
					(thickness 0.1524)
				)
				(justify mirror)
			)
		)
		(duplicate_pad_numbers_are_jumpers no)
		(fp_line
			(start -0.508 0)
			(end 0.508 0)
			(stroke
				(width 0.2032)
				(type default)
			)
			(layer "B.SilkS")
		)
		(fp_rect
			(start 0.5842 1.3335)
			(end -0.5842 -1.3335)
			(stroke
				(width 0)
				(type default)
			)
			(fill no)
			(layer "B.CrtYd")
		)
		(fp_rect
			(start 0.5842 1.3335)
			(end -0.5842 -1.3335)
			(stroke
				(width 0)
				(type default)
			)
			(fill no)
			(layer "B.Fab")
		)
		(pad "1" smd custom
			(at 0 -0.762)
			(size 0.2159 0.2159)
			(layers "B.Cu" "B.Mask" "B.Paste")
			(net "P3V3_STBY")
			(options
				(clearance outline)
				(anchor circle)
			)
			(primitives
				(gr_poly
					(pts
						(arc
							(start -0.3302 0.4318)
							(mid -0.402042 0.402042)
							(end -0.4318 0.3302)
						)
						(arc
							(start -0.4318 -0.3302)
							(mid -0.402042 -0.402042)
							(end -0.3302 -0.4318)
						)
						(arc
							(start 0.3302 -0.4318)
							(mid 0.402042 -0.402042)
							(end 0.4318 -0.3302)
						)
						(arc
							(start 0.4318 0.3302)
							(mid 0.402042 0.402042)
							(end 0.3302 0.4318)
						)
					)
					(width 0)
					(fill yes)
				)
			)
		)
		(pad "2" smd custom
			(at 0 0.762)
			(size 0.2159 0.2159)
			(layers "B.Cu" "B.Mask" "B.Paste")
			(net "GND")
			(options
				(clearance outline)
				(anchor circle)
			)
			(primitives
				(gr_poly
					(pts
						(arc
							(start -0.3302 0.4318)
							(mid -0.402042 0.402042)
							(end -0.4318 0.3302)
						)
						(arc
							(start -0.4318 -0.3302)
							(mid -0.402042 -0.402042)
							(end -0.3302 -0.4318)
						)
						(arc
							(start 0.3302 -0.4318)
							(mid 0.402042 -0.402042)
							(end 0.4318 -0.3302)
						)
						(arc
							(start 0.4318 0.3302)
							(mid 0.402042 0.402042)
							(end 0.3302 0.4318)
						)
					)
					(width 0)
					(fill yes)
				)
			)
		)
	)
	(footprint ""
		(layer "B.Cu")
		(at 191.68999 -23.241 -90)
		(property "Reference" "C493"
			(at 0 0 90)
			(layer "B.SilkS")
			(hide yes)
			(effects
				(font
					(size 1.27 1.27)
				)
				(justify mirror)
			)
		)
		(property "Value" "SCD01U16V1KX-GP"
			(at 2.8321 -1.7399 270)
			(unlocked yes)
			(layer "B.Fab")
			(hide yes)
			(effects
				(font
					(size 1.016 1.016)
					(thickness 0.1524)
				)
				(justify mirror)
			)
		)
		(property "Device Type" "C0201H13"
			(at 2.8321 -3.2639 270)
			(unlocked yes)
			(layer "B.Fab")
			(hide yes)
			(effects
				(font
					(size 1.016 1.016)
					(thickness 0.1524)
				)
				(justify mirror)
			)
		)
		(duplicate_pad_numbers_are_jumpers no)
		(fp_rect
			(start 0.2794 0.6477)
			(end -0.2794 -0.6477)
			(stroke
				(width 0)
				(type default)
			)
			(fill no)
			(layer "B.CrtYd")
		)
		(fp_rect
			(start 0.2794 0.6477)
			(end -0.2794 -0.6477)
			(stroke
				(width 0)
				(type default)
			)
			(fill no)
			(layer "B.Fab")
		)
		(pad "1" smd custom
			(at 0 -0.2794 90)
			(size 0.0762 0.0762)
			(layers "B.Cu" "B.Mask" "B.Paste")
			(net "PHY_CON_A_TO_IOC_2_DN")
			(options
				(clearance outline)
				(anchor circle)
			)
			(primitives
				(gr_poly
					(pts
						(arc
							(start 0.1524 0.127)
							(mid 0.137521 0.162921)
							(end 0.1016 0.1778)
						)
						(arc
							(start -0.1016 0.1778)
							(mid -0.137521 0.162921)
							(end -0.1524 0.127)
						)
						(arc
							(start -0.1524 -0.127)
							(mid -0.137521 -0.162921)
							(end -0.1016 -0.1778)
						)
						(arc
							(start 0.1016 -0.1778)
							(mid 0.137521 -0.162921)
							(end 0.1524 -0.127)
						)
					)
					(width 0)
					(fill yes)
				)
			)
		)
		(pad "2" smd custom
			(at 0 0.2794 90)
			(size 0.0762 0.0762)
			(layers "B.Cu" "B.Mask" "B.Paste")
			(net "PHY_CON_A_TO_IOC_2_DN_C")
			(options
				(clearance outline)
				(anchor circle)
			)
			(primitives
				(gr_poly
					(pts
						(arc
							(start 0.1524 0.127)
							(mid 0.137521 0.162921)
							(end 0.1016 0.1778)
						)
						(arc
							(start -0.1016 0.1778)
							(mid -0.137521 0.162921)
							(end -0.1524 0.127)
						)
						(arc
							(start -0.1524 -0.127)
							(mid -0.137521 -0.162921)
							(end -0.1016 -0.1778)
						)
						(arc
							(start 0.1016 -0.1778)
							(mid 0.137521 -0.162921)
							(end 0.1524 -0.127)
						)
					)
					(width 0)
					(fill yes)
				)
			)
		)
	)
	(footprint ""
		(layer "B.Cu")
		(at 184.4929 -81.50352)
		(property "Reference" "C392"
			(at 0 0 0)
			(layer "B.SilkS")
			(hide yes)
			(effects
				(font
					(size 1.27 1.27)
				)
				(justify mirror)
			)
		)
		(property "Value" "SC1U16V2KX-7-GP"
			(at -1.7526 -1.6002 0)
			(unlocked yes)
			(layer "B.Fab")
			(hide yes)
			(effects
				(font
					(size 1.016 1.016)
					(thickness 0.1524)
				)
				(justify mirror)
			)
		)
		(property "Device Type" "C402-TO0D2H24"
			(at -1.7526 -3.1242 0)
			(unlocked yes)
			(layer "B.Fab")
			(hide yes)
			(effects
				(font
					(size 1.016 1.016)
					(thickness 0.1524)
				)
				(justify mirror)
			)
		)
		(duplicate_pad_numbers_are_jumpers no)
		(fp_rect
			(start 0.4826 0.889)
			(end -0.4826 -0.889)
			(stroke
				(width 0)
				(type default)
			)
			(fill no)
			(layer "B.CrtYd")
		)
		(fp_rect
			(start 0.4826 0.889)
			(end -0.4826 -0.889)
			(stroke
				(width 0)
				(type default)
			)
			(fill no)
			(layer "B.Fab")
		)
		(pad "1" smd custom
			(at 0 -0.4572 180)
			(size 0.1524 0.1524)
			(layers "B.Cu" "B.Mask" "B.Paste")
			(net "P0V975")
			(options
				(clearance outline)
				(anchor circle)
			)
			(primitives
				(gr_poly
					(pts
						(arc
							(start -0.254 -0.3048)
							(mid -0.325842 -0.275042)
							(end -0.3556 -0.2032)
						)
						(arc
							(start -0.3556 0.2032)
							(mid -0.325842 0.275042)
							(end -0.254 0.3048)
						)
						(arc
							(start 0.254 0.3048)
							(mid 0.325842 0.275042)
							(end 0.3556 0.2032)
						)
						(arc
							(start 0.3556 -0.2032)
							(mid 0.325842 -0.275042)
							(end 0.254 -0.3048)
						)
					)
					(width 0)
					(fill yes)
				)
			)
		)
		(pad "2" smd custom
			(at 0 0.4572 180)
			(size 0.1524 0.1524)
			(layers "B.Cu" "B.Mask" "B.Paste")
			(net "GND")
			(options
				(clearance outline)
				(anchor circle)
			)
			(primitives
				(gr_poly
					(pts
						(arc
							(start -0.254 -0.3048)
							(mid -0.325842 -0.275042)
							(end -0.3556 -0.2032)
						)
						(arc
							(start -0.3556 0.2032)
							(mid -0.325842 0.275042)
							(end -0.254 0.3048)
						)
						(arc
							(start 0.254 0.3048)
							(mid 0.325842 0.275042)
							(end 0.3556 0.2032)
						)
						(arc
							(start 0.3556 -0.2032)
							(mid 0.325842 -0.275042)
							(end 0.254 -0.3048)
						)
					)
					(width 0)
					(fill yes)
				)
			)
		)
	)
	(footprint ""
		(layer "B.Cu")
		(at 61.0362 -145.034 90)
		(property "Reference" "R165"
			(at 0 0 90)
			(layer "B.SilkS")
			(hide yes)
			(effects
				(font
					(size 1.27 1.27)
				)
				(justify mirror)
			)
		)
		(property "Value" "0R2J-2-GP"
			(at -0.064008 -3.993896 90)
			(unlocked yes)
			(layer "B.Fab")
			(hide yes)
			(effects
				(font
					(size 1.016 1.016)
					(thickness 0.1524)
				)
				(justify mirror)
			)
		)
		(property "Device Type" "R402H16"
			(at -0.064008 -5.517896 90)
			(unlocked yes)
			(layer "B.Fab")
			(hide yes)
			(effects
				(font
					(size 1.016 1.016)
					(thickness 0.1524)
				)
				(justify mirror)
			)
		)
		(duplicate_pad_numbers_are_jumpers no)
		(fp_line
			(start 0.508 -0.9398)
			(end 0.508 0.9398)
			(stroke
				(width 0.1524)
				(type default)
			)
			(layer "B.SilkS")
		)
		(fp_line
			(start -0.508 -0.9398)
			(end 0.508 -0.9398)
			(stroke
				(width 0.1524)
				(type default)
			)
			(layer "B.SilkS")
		)
		(fp_rect
			(start 0.508 0.9398)
			(end -0.508 -0.9398)
			(stroke
				(width 0)
				(type default)
			)
			(fill no)
			(layer "B.CrtYd")
		)
		(fp_rect
			(start 0.508 0.9398)
			(end -0.508 -0.9398)
			(stroke
				(width 0)
				(type default)
			)
			(fill no)
			(layer "B.Fab")
		)
		(pad "1" smd custom
			(at 0 -0.4445 270)
			(size 0.1397 0.1397)
			(layers "B.Cu" "B.Mask" "B.Paste")
			(net "BMC_SMB13_DAT")
			(options
				(clearance outline)
				(anchor circle)
			)
			(primitives
				(gr_poly
					(pts
						(arc
							(start -0.1778 0.2794)
							(mid -0.249642 0.249642)
							(end -0.2794 0.1778)
						)
						(arc
							(start -0.2794 -0.1778)
							(mid -0.249642 -0.249642)
							(end -0.1778 -0.2794)
						)
						(arc
							(start 0.1778 -0.2794)
							(mid 0.249642 -0.249642)
							(end 0.2794 -0.1778)
						)
						(arc
							(start 0.2794 0.1778)
							(mid 0.249642 0.249642)
							(end 0.1778 0.2794)
						)
					)
					(width 0)
					(fill yes)
				)
			)
		)
		(pad "2" smd custom
			(at 0 0.4445 270)
			(size 0.1397 0.1397)
			(layers "B.Cu" "B.Mask" "B.Paste")
			(net "I2C_MEZZ_FRU_SENSOR_SDA")
			(options
				(clearance outline)
				(anchor circle)
			)
			(primitives
				(gr_poly
					(pts
						(arc
							(start -0.1778 0.2794)
							(mid -0.249642 0.249642)
							(end -0.2794 0.1778)
						)
						(arc
							(start -0.2794 -0.1778)
							(mid -0.249642 -0.249642)
							(end -0.1778 -0.2794)
						)
						(arc
							(start 0.1778 -0.2794)
							(mid 0.249642 -0.249642)
							(end 0.2794 -0.1778)
						)
						(arc
							(start 0.2794 0.1778)
							(mid 0.249642 0.249642)
							(end 0.1778 0.2794)
						)
					)
					(width 0)
					(fill yes)
				)
			)
		)
	)
	(footprint ""
		(layer "B.Cu")
		(at 199.7964 -113.538 180)
		(property "Reference" "C260"
			(at 0 0 0)
			(layer "B.SilkS")
			(hide yes)
			(effects
				(font
					(size 1.27 1.27)
				)
				(justify mirror)
			)
		)
		(property "Value" "SC22U6D3V6KX-2-GP"
			(at 0.0762 -5.1308 180)
			(unlocked yes)
			(layer "B.Fab")
			(hide yes)
			(effects
				(font
					(size 1.016 1.016)
					(thickness 0.1524)
				)
				(justify mirror)
			)
		)
		(property "Device Type" "C1206H71"
			(at 0.127 -6.6548 180)
			(unlocked yes)
			(layer "B.Fab")
			(hide yes)
			(effects
				(font
					(size 1.016 1.016)
					(thickness 0.1524)
				)
				(justify mirror)
			)
		)
		(duplicate_pad_numbers_are_jumpers no)
		(fp_line
			(start 1.016 2.2352)
			(end 1.016 0.8382)
			(stroke
				(width 0.1524)
				(type default)
			)
			(layer "B.SilkS")
		)
		(fp_line
			(start 1.016 -0.8382)
			(end 1.016 -2.2352)
			(stroke
				(width 0.1524)
				(type default)
			)
			(layer "B.SilkS")
		)
		(fp_line
			(start 1.016 -2.2352)
			(end -1.016 -2.2352)
			(stroke
				(width 0.1524)
				(type default)
			)
			(layer "B.SilkS")
		)
		(fp_line
			(start -1.016 2.2352)
			(end 1.016 2.2352)
			(stroke
				(width 0.1524)
				(type default)
			)
			(layer "B.SilkS")
		)
		(fp_line
			(start -1.016 0.8382)
			(end -1.016 2.2352)
			(stroke
				(width 0.1524)
				(type default)
			)
			(layer "B.SilkS")
		)
		(fp_line
			(start -1.016 -2.2352)
			(end -1.016 -0.8382)
			(stroke
				(width 0.1524)
				(type default)
			)
			(layer "B.SilkS")
		)
		(fp_rect
			(start 1.0922 2.3114)
			(end -1.0922 -2.3114)
			(stroke
				(width 0)
				(type default)
			)
			(fill no)
			(layer "B.CrtYd")
		)
		(fp_poly
			(pts
				(xy -1.0922 -2.3114) (xy -1.0922 2.3114) (xy 1.0922 2.3114) (xy 1.0922 -2.3114)
			)
			(stroke
				(width 0)
				(type default)
			)
			(fill no)
			(layer "B.Fab")
		)
		(pad "1" smd rect
			(at 0 -1.397)
			(size 1.651 1.27)
			(layers "B.Cu" "B.Mask" "B.Paste")
			(net "P0V975")
		)
		(pad "2" smd rect
			(at 0 1.397)
			(size 1.651 1.27)
			(layers "B.Cu" "B.Mask" "B.Paste")
			(net "GND")
		)
	)
	(footprint ""
		(layer "B.Cu")
		(at 93.37548 -152.746456 180)
		(property "Reference" "C9"
			(at 0 0 0)
			(layer "B.SilkS")
			(hide yes)
			(effects
				(font
					(size 1.27 1.27)
				)
				(justify mirror)
			)
		)
		(property "Value" "SC1U16V2KX-7-GP"
			(at -1.7526 -1.6002 180)
			(unlocked yes)
			(layer "B.Fab")
			(hide yes)
			(effects
				(font
					(size 1.016 1.016)
					(thickness 0.1524)
				)
				(justify mirror)
			)
		)
		(property "Device Type" "C402-TO0D2H24"
			(at -1.7526 -3.1242 180)
			(unlocked yes)
			(layer "B.Fab")
			(hide yes)
			(effects
				(font
					(size 1.016 1.016)
					(thickness 0.1524)
				)
				(justify mirror)
			)
		)
		(duplicate_pad_numbers_are_jumpers no)
		(fp_rect
			(start 0.4826 0.889)
			(end -0.4826 -0.889)
			(stroke
				(width 0)
				(type default)
			)
			(fill no)
			(layer "B.CrtYd")
		)
		(fp_rect
			(start 0.4826 0.889)
			(end -0.4826 -0.889)
			(stroke
				(width 0)
				(type default)
			)
			(fill no)
			(layer "B.Fab")
		)
		(pad "1" smd custom
			(at 0 -0.4572)
			(size 0.1524 0.1524)
			(layers "B.Cu" "B.Mask" "B.Paste")
			(net "P3V3_STBY")
			(options
				(clearance outline)
				(anchor circle)
			)
			(primitives
				(gr_poly
					(pts
						(arc
							(start -0.254 -0.3048)
							(mid -0.325842 -0.275042)
							(end -0.3556 -0.2032)
						)
						(arc
							(start -0.3556 0.2032)
							(mid -0.325842 0.275042)
							(end -0.254 0.3048)
						)
						(arc
							(start 0.254 0.3048)
							(mid 0.325842 0.275042)
							(end 0.3556 0.2032)
						)
						(arc
							(start 0.3556 -0.2032)
							(mid 0.325842 -0.275042)
							(end 0.254 -0.3048)
						)
					)
					(width 0)
					(fill yes)
				)
			)
		)
		(pad "2" smd custom
			(at 0 0.4572)
			(size 0.1524 0.1524)
			(layers "B.Cu" "B.Mask" "B.Paste")
			(net "GND")
			(options
				(clearance outline)
				(anchor circle)
			)
			(primitives
				(gr_poly
					(pts
						(arc
							(start -0.254 -0.3048)
							(mid -0.325842 -0.275042)
							(end -0.3556 -0.2032)
						)
						(arc
							(start -0.3556 0.2032)
							(mid -0.325842 0.275042)
							(end -0.254 0.3048)
						)
						(arc
							(start 0.254 0.3048)
							(mid 0.325842 0.275042)
							(end 0.3556 0.2032)
						)
						(arc
							(start 0.3556 -0.2032)
							(mid 0.325842 -0.275042)
							(end 0.254 -0.3048)
						)
					)
					(width 0)
					(fill yes)
				)
			)
		)
	)
	(footprint ""
		(layer "B.Cu")
		(at 184.1754 -118.0338 90)
		(property "Reference" "C273"
			(at 0 0 90)
			(layer "B.SilkS")
			(hide yes)
			(effects
				(font
					(size 1.27 1.27)
				)
				(justify mirror)
			)
		)
		(property "Value" "SC10U16V5KX-7-GP-U"
			(at 0.0762 -6.1214 90)
			(unlocked yes)
			(layer "B.Fab")
			(hide yes)
			(effects
				(font
					(size 1.016 1.016)
					(thickness 0.1524)
				)
				(justify mirror)
			)
		)
		(property "Device Type" "C805H58"
			(at 0.0762 -8.1534 90)
			(unlocked yes)
			(layer "B.Fab")
			(hide yes)
			(effects
				(font
					(size 1.016 1.016)
					(thickness 0.1524)
				)
				(justify mirror)
			)
		)
		(duplicate_pad_numbers_are_jumpers no)
		(fp_line
			(start -0.635 0)
			(end 0.635 0)
			(stroke
				(width 0.508)
				(type default)
			)
			(layer "B.SilkS")
		)
		(fp_rect
			(start 0.9652 1.778)
			(end -0.9652 -1.778)
			(stroke
				(width 0)
				(type default)
			)
			(fill no)
			(layer "B.CrtYd")
		)
		(fp_poly
			(pts
				(xy 0.9652 -1.778) (xy -0.9652 -1.778) (xy -0.9652 1.778) (xy 0.9652 1.778)
			)
			(stroke
				(width 0)
				(type default)
			)
			(fill no)
			(layer "B.Fab")
		)
		(pad "1" smd rect
			(at 0 -0.9652 270)
			(size 1.397 1.143)
			(layers "B.Cu" "B.Mask" "B.Paste")
			(net "VT235_VDDH")
		)
		(pad "2" smd rect
			(at 0 0.9652 270)
			(size 1.397 1.143)
			(layers "B.Cu" "B.Mask" "B.Paste")
			(net "GND")
		)
	)
	(footprint ""
		(layer "B.Cu")
		(at 62.2554 -134.93496 -90)
		(property "Reference" "R343"
			(at 0 0 90)
			(layer "B.SilkS")
			(hide yes)
			(effects
				(font
					(size 1.27 1.27)
				)
				(justify mirror)
			)
		)
		(property "Value" "0R2J-2-GP"
			(at -0.064008 -3.993896 270)
			(unlocked yes)
			(layer "B.Fab")
			(hide yes)
			(effects
				(font
					(size 1.016 1.016)
					(thickness 0.1524)
				)
				(justify mirror)
			)
		)
		(property "Device Type" "R402H16"
			(at -0.064008 -5.517896 270)
			(unlocked yes)
			(layer "B.Fab")
			(hide yes)
			(effects
				(font
					(size 1.016 1.016)
					(thickness 0.1524)
				)
				(justify mirror)
			)
		)
		(duplicate_pad_numbers_are_jumpers no)
		(fp_line
			(start -0.508 -0.9398)
			(end 0.508 -0.9398)
			(stroke
				(width 0.1524)
				(type default)
			)
			(layer "B.SilkS")
		)
		(fp_line
			(start 0.508 -0.9398)
			(end 0.508 0.9398)
			(stroke
				(width 0.1524)
				(type default)
			)
			(layer "B.SilkS")
		)
		(fp_rect
			(start 0.508 0.9398)
			(end -0.508 -0.9398)
			(stroke
				(width 0)
				(type default)
			)
			(fill no)
			(layer "B.CrtYd")
		)
		(fp_rect
			(start 0.508 0.9398)
			(end -0.508 -0.9398)
			(stroke
				(width 0)
				(type default)
			)
			(fill no)
			(layer "B.Fab")
		)
		(pad "1" smd custom
			(at 0 -0.4445 90)
			(size 0.1397 0.1397)
			(layers "B.Cu" "B.Mask" "B.Paste")
			(net "COMP_SPARE_0")
			(options
				(clearance outline)
				(anchor circle)
			)
			(primitives
				(gr_poly
					(pts
						(arc
							(start -0.1778 0.2794)
							(mid -0.249642 0.249642)
							(end -0.2794 0.1778)
						)
						(arc
							(start -0.2794 -0.1778)
							(mid -0.249642 -0.249642)
							(end -0.1778 -0.2794)
						)
						(arc
							(start 0.1778 -0.2794)
							(mid 0.249642 -0.249642)
							(end 0.2794 -0.1778)
						)
						(arc
							(start 0.2794 0.1778)
							(mid 0.249642 0.249642)
							(end 0.1778 0.2794)
						)
					)
					(width 0)
					(fill yes)
				)
			)
		)
		(pad "2" smd custom
			(at 0 0.4445 90)
			(size 0.1397 0.1397)
			(layers "B.Cu" "B.Mask" "B.Paste")
			(net "COMP_SPARE_0_R")
			(options
				(clearance outline)
				(anchor circle)
			)
			(primitives
				(gr_poly
					(pts
						(arc
							(start -0.1778 0.2794)
							(mid -0.249642 0.249642)
							(end -0.2794 0.1778)
						)
						(arc
							(start -0.2794 -0.1778)
							(mid -0.249642 -0.249642)
							(end -0.1778 -0.2794)
						)
						(arc
							(start 0.1778 -0.2794)
							(mid 0.249642 -0.249642)
							(end 0.2794 -0.1778)
						)
						(arc
							(start 0.2794 0.1778)
							(mid 0.249642 0.249642)
							(end 0.1778 0.2794)
						)
					)
					(width 0)
					(fill yes)
				)
			)
		)
	)
	(footprint ""
		(layer "B.Cu")
		(at 161.036 -48.895 180)
		(property "Reference" "R747"
			(at 0 0 0)
			(layer "B.SilkS")
			(hide yes)
			(effects
				(font
					(size 1.27 1.27)
				)
				(justify mirror)
			)
		)
		(property "Value" "10KR2F-2-GP"
			(at -0.064008 -3.993896 180)
			(unlocked yes)
			(layer "B.Fab")
			(hide yes)
			(effects
				(font
					(size 1.016 1.016)
					(thickness 0.1524)
				)
				(justify mirror)
			)
		)
		(property "Device Type" "R402H16"
			(at -0.064008 -5.517896 180)
			(unlocked yes)
			(layer "B.Fab")
			(hide yes)
			(effects
				(font
					(size 1.016 1.016)
					(thickness 0.1524)
				)
				(justify mirror)
			)
		)
		(duplicate_pad_numbers_are_jumpers no)
		(fp_line
			(start 0.508 -0.9398)
			(end 0.508 0.9398)
			(stroke
				(width 0.1524)
				(type default)
			)
			(layer "B.SilkS")
		)
		(fp_line
			(start -0.508 -0.9398)
			(end 0.508 -0.9398)
			(stroke
				(width 0.1524)
				(type default)
			)
			(layer "B.SilkS")
		)
		(fp_rect
			(start 0.508 0.9398)
			(end -0.508 -0.9398)
			(stroke
				(width 0)
				(type default)
			)
			(fill no)
			(layer "B.CrtYd")
		)
		(fp_rect
			(start 0.508 0.9398)
			(end -0.508 -0.9398)
			(stroke
				(width 0)
				(type default)
			)
			(fill no)
			(layer "B.Fab")
		)
		(pad "1" smd custom
			(at 0 -0.4445)
			(size 0.1397 0.1397)
			(layers "B.Cu" "B.Mask" "B.Paste")
			(net "P1V8")
			(options
				(clearance outline)
				(anchor circle)
			)
			(primitives
				(gr_poly
					(pts
						(arc
							(start -0.1778 0.2794)
							(mid -0.249642 0.249642)
							(end -0.2794 0.1778)
						)
						(arc
							(start -0.2794 -0.1778)
							(mid -0.249642 -0.249642)
							(end -0.1778 -0.2794)
						)
						(arc
							(start 0.1778 -0.2794)
							(mid 0.249642 -0.249642)
							(end 0.2794 -0.1778)
						)
						(arc
							(start 0.2794 0.1778)
							(mid 0.249642 0.249642)
							(end 0.1778 0.2794)
						)
					)
					(width 0)
					(fill yes)
				)
			)
		)
		(pad "2" smd custom
			(at 0 0.4445)
			(size 0.1397 0.1397)
			(layers "B.Cu" "B.Mask" "B.Paste")
			(net "BYTE_N")
			(options
				(clearance outline)
				(anchor circle)
			)
			(primitives
				(gr_poly
					(pts
						(arc
							(start -0.1778 0.2794)
							(mid -0.249642 0.249642)
							(end -0.2794 0.1778)
						)
						(arc
							(start -0.2794 -0.1778)
							(mid -0.249642 -0.249642)
							(end -0.1778 -0.2794)
						)
						(arc
							(start 0.1778 -0.2794)
							(mid 0.249642 -0.249642)
							(end 0.2794 -0.1778)
						)
						(arc
							(start 0.2794 0.1778)
							(mid 0.249642 0.249642)
							(end 0.1778 0.2794)
						)
					)
					(width 0)
					(fill yes)
				)
			)
		)
	)
	(footprint ""
		(layer "B.Cu")
		(at 189.2681 -61.6204 90)
		(property "Reference" "C411"
			(at 0 0 90)
			(layer "B.SilkS")
			(hide yes)
			(effects
				(font
					(size 1.27 1.27)
				)
				(justify mirror)
			)
		)
		(property "Value" "SCD1U6D3V1KX-GP"
			(at 2.8321 -1.7399 90)
			(unlocked yes)
			(layer "B.Fab")
			(hide yes)
			(effects
				(font
					(size 1.016 1.016)
					(thickness 0.1524)
				)
				(justify mirror)
			)
		)
		(property "Device Type" "C0201H13"
			(at 2.8321 -3.2639 90)
			(unlocked yes)
			(layer "B.Fab")
			(hide yes)
			(effects
				(font
					(size 1.016 1.016)
					(thickness 0.1524)
				)
				(justify mirror)
			)
		)
		(duplicate_pad_numbers_are_jumpers no)
		(fp_rect
			(start 0.2794 0.6477)
			(end -0.2794 -0.6477)
			(stroke
				(width 0)
				(type default)
			)
			(fill no)
			(layer "B.CrtYd")
		)
		(fp_rect
			(start 0.2794 0.6477)
			(end -0.2794 -0.6477)
			(stroke
				(width 0)
				(type default)
			)
			(fill no)
			(layer "B.Fab")
		)
		(pad "1" smd custom
			(at 0 -0.2794 270)
			(size 0.0762 0.0762)
			(layers "B.Cu" "B.Mask" "B.Paste")
			(net "P0V975")
			(options
				(clearance outline)
				(anchor circle)
			)
			(primitives
				(gr_poly
					(pts
						(arc
							(start 0.1524 0.127)
							(mid 0.137521 0.162921)
							(end 0.1016 0.1778)
						)
						(arc
							(start -0.1016 0.1778)
							(mid -0.137521 0.162921)
							(end -0.1524 0.127)
						)
						(arc
							(start -0.1524 -0.127)
							(mid -0.137521 -0.162921)
							(end -0.1016 -0.1778)
						)
						(arc
							(start 0.1016 -0.1778)
							(mid 0.137521 -0.162921)
							(end 0.1524 -0.127)
						)
					)
					(width 0)
					(fill yes)
				)
			)
		)
		(pad "2" smd custom
			(at 0 0.2794 270)
			(size 0.0762 0.0762)
			(layers "B.Cu" "B.Mask" "B.Paste")
			(net "GND")
			(options
				(clearance outline)
				(anchor circle)
			)
			(primitives
				(gr_poly
					(pts
						(arc
							(start 0.1524 0.127)
							(mid 0.137521 0.162921)
							(end 0.1016 0.1778)
						)
						(arc
							(start -0.1016 0.1778)
							(mid -0.137521 0.162921)
							(end -0.1524 0.127)
						)
						(arc
							(start -0.1524 -0.127)
							(mid -0.137521 -0.162921)
							(end -0.1016 -0.1778)
						)
						(arc
							(start 0.1016 -0.1778)
							(mid 0.137521 -0.162921)
							(end 0.1524 -0.127)
						)
					)
					(width 0)
					(fill yes)
				)
			)
		)
	)
	(footprint ""
		(layer "B.Cu")
		(at 23.437342 -129.1082 180)
		(property "Reference" "R248"
			(at 0 0 0)
			(layer "B.SilkS")
			(hide yes)
			(effects
				(font
					(size 1.27 1.27)
				)
				(justify mirror)
			)
		)
		(property "Value" "120R2F-GP"
			(at -0.064008 -3.993896 180)
			(unlocked yes)
			(layer "B.Fab")
			(hide yes)
			(effects
				(font
					(size 1.016 1.016)
					(thickness 0.1524)
				)
				(justify mirror)
			)
		)
		(property "Device Type" "R402H16"
			(at -0.064008 -5.517896 180)
			(unlocked yes)
			(layer "B.Fab")
			(hide yes)
			(effects
				(font
					(size 1.016 1.016)
					(thickness 0.1524)
				)
				(justify mirror)
			)
		)
		(duplicate_pad_numbers_are_jumpers no)
		(fp_line
			(start 0.508 -0.9398)
			(end 0.508 0.9398)
			(stroke
				(width 0.1524)
				(type default)
			)
			(layer "B.SilkS")
		)
		(fp_line
			(start -0.508 -0.9398)
			(end 0.508 -0.9398)
			(stroke
				(width 0.1524)
				(type default)
			)
			(layer "B.SilkS")
		)
		(fp_rect
			(start 0.508 0.9398)
			(end -0.508 -0.9398)
			(stroke
				(width 0)
				(type default)
			)
			(fill no)
			(layer "B.CrtYd")
		)
		(fp_rect
			(start 0.508 0.9398)
			(end -0.508 -0.9398)
			(stroke
				(width 0)
				(type default)
			)
			(fill no)
			(layer "B.Fab")
		)
		(pad "1" smd custom
			(at 0 -0.4445)
			(size 0.1397 0.1397)
			(layers "B.Cu" "B.Mask" "B.Paste")
			(net "GND")
			(options
				(clearance outline)
				(anchor circle)
			)
			(primitives
				(gr_poly
					(pts
						(arc
							(start -0.1778 0.2794)
							(mid -0.249642 0.249642)
							(end -0.2794 0.1778)
						)
						(arc
							(start -0.2794 -0.1778)
							(mid -0.249642 -0.249642)
							(end -0.1778 -0.2794)
						)
						(arc
							(start 0.1778 -0.2794)
							(mid 0.249642 -0.249642)
							(end 0.2794 -0.1778)
						)
						(arc
							(start 0.2794 0.1778)
							(mid 0.249642 0.249642)
							(end 0.1778 0.2794)
						)
					)
					(width 0)
					(fill yes)
				)
			)
		)
		(pad "2" smd custom
			(at 0 0.4445)
			(size 0.1397 0.1397)
			(layers "B.Cu" "B.Mask" "B.Paste")
			(net "MEMA_7")
			(options
				(clearance outline)
				(anchor circle)
			)
			(primitives
				(gr_poly
					(pts
						(arc
							(start -0.1778 0.2794)
							(mid -0.249642 0.249642)
							(end -0.2794 0.1778)
						)
						(arc
							(start -0.2794 -0.1778)
							(mid -0.249642 -0.249642)
							(end -0.1778 -0.2794)
						)
						(arc
							(start 0.1778 -0.2794)
							(mid 0.249642 -0.249642)
							(end 0.2794 -0.1778)
						)
						(arc
							(start 0.2794 0.1778)
							(mid 0.249642 0.249642)
							(end 0.1778 0.2794)
						)
					)
					(width 0)
					(fill yes)
				)
			)
		)
	)
	(footprint ""
		(layer "B.Cu")
		(at 200.8632 -75.3364)
		(property "Reference" "C365"
			(at 0 0 0)
			(layer "B.SilkS")
			(hide yes)
			(effects
				(font
					(size 1.27 1.27)
				)
				(justify mirror)
			)
		)
		(property "Value" "SCD1U6D3V1KX-GP"
			(at 2.8321 -1.7399 0)
			(unlocked yes)
			(layer "B.Fab")
			(hide yes)
			(effects
				(font
					(size 1.016 1.016)
					(thickness 0.1524)
				)
				(justify mirror)
			)
		)
		(property "Device Type" "C0201H13"
			(at 2.8321 -3.2639 0)
			(unlocked yes)
			(layer "B.Fab")
			(hide yes)
			(effects
				(font
					(size 1.016 1.016)
					(thickness 0.1524)
				)
				(justify mirror)
			)
		)
		(duplicate_pad_numbers_are_jumpers no)
		(fp_rect
			(start 0.2794 0.6477)
			(end -0.2794 -0.6477)
			(stroke
				(width 0)
				(type default)
			)
			(fill no)
			(layer "B.CrtYd")
		)
		(fp_rect
			(start 0.2794 0.6477)
			(end -0.2794 -0.6477)
			(stroke
				(width 0)
				(type default)
			)
			(fill no)
			(layer "B.Fab")
		)
		(pad "1" smd custom
			(at 0 -0.2794 180)
			(size 0.0762 0.0762)
			(layers "B.Cu" "B.Mask" "B.Paste")
			(net "PCE_AVDD")
			(options
				(clearance outline)
				(anchor circle)
			)
			(primitives
				(gr_poly
					(pts
						(arc
							(start 0.1524 0.127)
							(mid 0.137521 0.162921)
							(end 0.1016 0.1778)
						)
						(arc
							(start -0.1016 0.1778)
							(mid -0.137521 0.162921)
							(end -0.1524 0.127)
						)
						(arc
							(start -0.1524 -0.127)
							(mid -0.137521 -0.162921)
							(end -0.1016 -0.1778)
						)
						(arc
							(start 0.1016 -0.1778)
							(mid 0.137521 -0.162921)
							(end 0.1524 -0.127)
						)
					)
					(width 0)
					(fill yes)
				)
			)
		)
		(pad "2" smd custom
			(at 0 0.2794 180)
			(size 0.0762 0.0762)
			(layers "B.Cu" "B.Mask" "B.Paste")
			(net "GND")
			(options
				(clearance outline)
				(anchor circle)
			)
			(primitives
				(gr_poly
					(pts
						(arc
							(start 0.1524 0.127)
							(mid 0.137521 0.162921)
							(end 0.1016 0.1778)
						)
						(arc
							(start -0.1016 0.1778)
							(mid -0.137521 0.162921)
							(end -0.1524 0.127)
						)
						(arc
							(start -0.1524 -0.127)
							(mid -0.137521 -0.162921)
							(end -0.1016 -0.1778)
						)
						(arc
							(start 0.1016 -0.1778)
							(mid 0.137521 -0.162921)
							(end 0.1524 -0.127)
						)
					)
					(width 0)
					(fill yes)
				)
			)
		)
	)
	(footprint ""
		(layer "B.Cu")
		(at 189.171072 -76.419456)
		(property "Reference" "TP131"
			(at 0 0 0)
			(layer "B.SilkS")
			(hide yes)
			(effects
				(font
					(size 1.27 1.27)
				)
				(justify mirror)
			)
		)
		(property "Value" "TPAD28-2-GP"
			(at 0.0127 -1.6637 0)
			(unlocked yes)
			(layer "B.Fab")
			(hide yes)
			(effects
				(font
					(size 1.016 1.016)
					(thickness 0.1524)
				)
				(justify mirror)
			)
		)
		(property "Device Type" "TPAD28"
			(at 0.0127 -3.1877 0)
			(unlocked yes)
			(layer "B.Fab")
			(hide yes)
			(effects
				(font
					(size 1.016 1.016)
					(thickness 0.1524)
				)
				(justify mirror)
			)
		)
		(duplicate_pad_numbers_are_jumpers no)
		(fp_poly
			(pts
				(arc
					(start 0.3556 0)
					(mid -0.3556 0)
					(end 0.3556 0)
				)
			)
			(stroke
				(width 0)
				(type default)
			)
			(fill no)
			(layer "B.CrtYd")
		)
		(fp_poly
			(pts
				(arc
					(start 0.6096 0)
					(mid -0.6096 0)
					(end 0.6096 0)
				)
			)
			(stroke
				(width 0)
				(type default)
			)
			(fill no)
			(layer "B.Fab")
		)
		(pad "1" smd circle
			(at 0 0 180)
			(size 0.7112 0.7112)
			(layers "B.Cu" "B.Mask" "B.Paste")
			(net "IOC_UART_1_TX")
		)
	)
	(footprint ""
		(layer "B.Cu")
		(at 60.9219 -155.15844 -90)
		(property "Reference" "R304"
			(at 0 0 90)
			(layer "B.SilkS")
			(hide yes)
			(effects
				(font
					(size 1.27 1.27)
				)
				(justify mirror)
			)
		)
		(property "Value" "47KR2F-GP"
			(at -0.064008 -3.993896 270)
			(unlocked yes)
			(layer "B.Fab")
			(hide yes)
			(effects
				(font
					(size 1.016 1.016)
					(thickness 0.1524)
				)
				(justify mirror)
			)
		)
		(property "Device Type" "R402H16"
			(at -0.064008 -5.517896 270)
			(unlocked yes)
			(layer "B.Fab")
			(hide yes)
			(effects
				(font
					(size 1.016 1.016)
					(thickness 0.1524)
				)
				(justify mirror)
			)
		)
		(duplicate_pad_numbers_are_jumpers no)
		(fp_line
			(start -0.508 -0.9398)
			(end 0.508 -0.9398)
			(stroke
				(width 0.1524)
				(type default)
			)
			(layer "B.SilkS")
		)
		(fp_line
			(start 0.508 -0.9398)
			(end 0.508 0.9398)
			(stroke
				(width 0.1524)
				(type default)
			)
			(layer "B.SilkS")
		)
		(fp_rect
			(start 0.508 0.9398)
			(end -0.508 -0.9398)
			(stroke
				(width 0)
				(type default)
			)
			(fill no)
			(layer "B.CrtYd")
		)
		(fp_rect
			(start 0.508 0.9398)
			(end -0.508 -0.9398)
			(stroke
				(width 0)
				(type default)
			)
			(fill no)
			(layer "B.Fab")
		)
		(pad "1" smd custom
			(at 0 -0.4445 90)
			(size 0.1397 0.1397)
			(layers "B.Cu" "B.Mask" "B.Paste")
			(net "GND")
			(options
				(clearance outline)
				(anchor circle)
			)
			(primitives
				(gr_poly
					(pts
						(arc
							(start -0.1778 0.2794)
							(mid -0.249642 0.249642)
							(end -0.2794 0.1778)
						)
						(arc
							(start -0.2794 -0.1778)
							(mid -0.249642 -0.249642)
							(end -0.1778 -0.2794)
						)
						(arc
							(start 0.1778 -0.2794)
							(mid 0.249642 -0.249642)
							(end 0.2794 -0.1778)
						)
						(arc
							(start 0.2794 0.1778)
							(mid 0.249642 0.249642)
							(end 0.1778 0.2794)
						)
					)
					(width 0)
					(fill yes)
				)
			)
		)
		(pad "2" smd custom
			(at 0 0.4445 90)
			(size 0.1397 0.1397)
			(layers "B.Cu" "B.Mask" "B.Paste")
			(net "BMC_RGMII_A4_D3")
			(options
				(clearance outline)
				(anchor circle)
			)
			(primitives
				(gr_poly
					(pts
						(arc
							(start -0.1778 0.2794)
							(mid -0.249642 0.249642)
							(end -0.2794 0.1778)
						)
						(arc
							(start -0.2794 -0.1778)
							(mid -0.249642 -0.249642)
							(end -0.1778 -0.2794)
						)
						(arc
							(start 0.1778 -0.2794)
							(mid 0.249642 -0.249642)
							(end 0.2794 -0.1778)
						)
						(arc
							(start 0.2794 0.1778)
							(mid 0.249642 0.249642)
							(end 0.1778 0.2794)
						)
					)
					(width 0)
					(fill yes)
				)
			)
		)
	)
	(footprint ""
		(layer "B.Cu")
		(at 184.910984 -77.139546)
		(property "Reference" "TP130"
			(at 0 0 0)
			(layer "B.SilkS")
			(hide yes)
			(effects
				(font
					(size 1.27 1.27)
				)
				(justify mirror)
			)
		)
		(property "Value" "TPAD28-2-GP"
			(at 0.0127 -1.6637 0)
			(unlocked yes)
			(layer "B.Fab")
			(hide yes)
			(effects
				(font
					(size 1.016 1.016)
					(thickness 0.1524)
				)
				(justify mirror)
			)
		)
		(property "Device Type" "TPAD28"
			(at 0.0127 -3.1877 0)
			(unlocked yes)
			(layer "B.Fab")
			(hide yes)
			(effects
				(font
					(size 1.016 1.016)
					(thickness 0.1524)
				)
				(justify mirror)
			)
		)
		(duplicate_pad_numbers_are_jumpers no)
		(fp_poly
			(pts
				(arc
					(start 0.3556 0)
					(mid -0.3556 0)
					(end 0.3556 0)
				)
			)
			(stroke
				(width 0)
				(type default)
			)
			(fill no)
			(layer "B.CrtYd")
		)
		(fp_poly
			(pts
				(arc
					(start 0.6096 0)
					(mid -0.6096 0)
					(end 0.6096 0)
				)
			)
			(stroke
				(width 0)
				(type default)
			)
			(fill no)
			(layer "B.Fab")
		)
		(pad "1" smd circle
			(at 0 0 180)
			(size 0.7112 0.7112)
			(layers "B.Cu" "B.Mask" "B.Paste")
			(net "IOC_UART_1_RX")
		)
	)
	(footprint ""
		(layer "B.Cu")
		(at 166.64559 -38.416738)
		(property "Reference" "C500"
			(at 0 0 0)
			(layer "B.SilkS")
			(hide yes)
			(effects
				(font
					(size 1.27 1.27)
				)
				(justify mirror)
			)
		)
		(property "Value" "SCD01U16V1KX-GP"
			(at 2.8321 -1.7399 0)
			(unlocked yes)
			(layer "B.Fab")
			(hide yes)
			(effects
				(font
					(size 1.016 1.016)
					(thickness 0.1524)
				)
				(justify mirror)
			)
		)
		(property "Device Type" "C0201H13"
			(at 2.8321 -3.2639 0)
			(unlocked yes)
			(layer "B.Fab")
			(hide yes)
			(effects
				(font
					(size 1.016 1.016)
					(thickness 0.1524)
				)
				(justify mirror)
			)
		)
		(duplicate_pad_numbers_are_jumpers no)
		(fp_rect
			(start 0.2794 0.6477)
			(end -0.2794 -0.6477)
			(stroke
				(width 0)
				(type default)
			)
			(fill no)
			(layer "B.CrtYd")
		)
		(fp_rect
			(start 0.2794 0.6477)
			(end -0.2794 -0.6477)
			(stroke
				(width 0)
				(type default)
			)
			(fill no)
			(layer "B.Fab")
		)
		(pad "1" smd custom
			(at 0 -0.2794 180)
			(size 0.0762 0.0762)
			(layers "B.Cu" "B.Mask" "B.Paste")
			(net "PHY_CON_B_TO_IOC_2_DP")
			(options
				(clearance outline)
				(anchor circle)
			)
			(primitives
				(gr_poly
					(pts
						(arc
							(start 0.1524 0.127)
							(mid 0.137521 0.162921)
							(end 0.1016 0.1778)
						)
						(arc
							(start -0.1016 0.1778)
							(mid -0.137521 0.162921)
							(end -0.1524 0.127)
						)
						(arc
							(start -0.1524 -0.127)
							(mid -0.137521 -0.162921)
							(end -0.1016 -0.1778)
						)
						(arc
							(start 0.1016 -0.1778)
							(mid 0.137521 -0.162921)
							(end 0.1524 -0.127)
						)
					)
					(width 0)
					(fill yes)
				)
			)
		)
		(pad "2" smd custom
			(at 0 0.2794 180)
			(size 0.0762 0.0762)
			(layers "B.Cu" "B.Mask" "B.Paste")
			(net "PHY_CON_B_TO_IOC_2_DP_C")
			(options
				(clearance outline)
				(anchor circle)
			)
			(primitives
				(gr_poly
					(pts
						(arc
							(start 0.1524 0.127)
							(mid 0.137521 0.162921)
							(end 0.1016 0.1778)
						)
						(arc
							(start -0.1016 0.1778)
							(mid -0.137521 0.162921)
							(end -0.1524 0.127)
						)
						(arc
							(start -0.1524 -0.127)
							(mid -0.137521 -0.162921)
							(end -0.1016 -0.1778)
						)
						(arc
							(start 0.1016 -0.1778)
							(mid 0.137521 -0.162921)
							(end 0.1524 -0.127)
						)
					)
					(width 0)
					(fill yes)
				)
			)
		)
	)
	(footprint ""
		(layer "B.Cu")
		(at 45.07484 -155.23972 -90)
		(property "Reference" "C103"
			(at 0 0 90)
			(layer "B.SilkS")
			(hide yes)
			(effects
				(font
					(size 1.27 1.27)
				)
				(justify mirror)
			)
		)
		(property "Value" "SCD1U16V2KX-3GP"
			(at -1.1811 -2.7051 270)
			(unlocked yes)
			(layer "B.Fab")
			(hide yes)
			(effects
				(font
					(size 1.016 1.016)
					(thickness 0.1524)
				)
				(justify mirror)
			)
		)
		(property "Device Type" "C402H22"
			(at -1.1811 -4.2291 270)
			(unlocked yes)
			(layer "B.Fab")
			(hide yes)
			(effects
				(font
					(size 1.016 1.016)
					(thickness 0.1524)
				)
				(justify mirror)
			)
		)
		(duplicate_pad_numbers_are_jumpers no)
		(fp_rect
			(start 0.4318 0.9525)
			(end -0.4318 -0.9525)
			(stroke
				(width 0)
				(type default)
			)
			(fill no)
			(layer "B.CrtYd")
		)
		(fp_rect
			(start 0.4318 0.9525)
			(end -0.4318 -0.9525)
			(stroke
				(width 0)
				(type default)
			)
			(fill no)
			(layer "B.Fab")
		)
		(pad "1" smd custom
			(at 0 -0.4445 90)
			(size 0.1524 0.1524)
			(layers "B.Cu" "B.Mask" "B.Paste")
			(net "V1PLLAV11")
			(options
				(clearance outline)
				(anchor circle)
			)
			(primitives
				(gr_poly
					(pts
						(arc
							(start 0.3048 0.2032)
							(mid 0.275042 0.275042)
							(end 0.2032 0.3048)
						)
						(arc
							(start -0.2032 0.3048)
							(mid -0.275042 0.275042)
							(end -0.3048 0.2032)
						)
						(arc
							(start -0.3048 -0.2032)
							(mid -0.275042 -0.275042)
							(end -0.2032 -0.3048)
						)
						(arc
							(start 0.2032 -0.3048)
							(mid 0.275042 -0.275042)
							(end 0.3048 -0.2032)
						)
					)
					(width 0)
					(fill yes)
				)
			)
		)
		(pad "2" smd custom
			(at 0 0.4445 90)
			(size 0.1524 0.1524)
			(layers "B.Cu" "B.Mask" "B.Paste")
			(net "GND")
			(options
				(clearance outline)
				(anchor circle)
			)
			(primitives
				(gr_poly
					(pts
						(arc
							(start 0.3048 0.2032)
							(mid 0.275042 0.275042)
							(end 0.2032 0.3048)
						)
						(arc
							(start -0.2032 0.3048)
							(mid -0.275042 0.275042)
							(end -0.3048 0.2032)
						)
						(arc
							(start -0.3048 -0.2032)
							(mid -0.275042 -0.275042)
							(end -0.2032 -0.3048)
						)
						(arc
							(start 0.2032 -0.3048)
							(mid 0.275042 -0.275042)
							(end 0.3048 -0.2032)
						)
					)
					(width 0)
					(fill yes)
				)
			)
		)
	)
	(footprint ""
		(layer "B.Cu")
		(at 195.5292 -64.8081 90)
		(property "Reference" "C402"
			(at 0 0 90)
			(layer "B.SilkS")
			(hide yes)
			(effects
				(font
					(size 1.27 1.27)
				)
				(justify mirror)
			)
		)
		(property "Value" "SCD1U6D3V1KX-GP"
			(at 2.8321 -1.7399 90)
			(unlocked yes)
			(layer "B.Fab")
			(hide yes)
			(effects
				(font
					(size 1.016 1.016)
					(thickness 0.1524)
				)
				(justify mirror)
			)
		)
		(property "Device Type" "C0201H13"
			(at 2.8321 -3.2639 90)
			(unlocked yes)
			(layer "B.Fab")
			(hide yes)
			(effects
				(font
					(size 1.016 1.016)
					(thickness 0.1524)
				)
				(justify mirror)
			)
		)
		(duplicate_pad_numbers_are_jumpers no)
		(fp_rect
			(start 0.2794 0.6477)
			(end -0.2794 -0.6477)
			(stroke
				(width 0)
				(type default)
			)
			(fill no)
			(layer "B.CrtYd")
		)
		(fp_rect
			(start 0.2794 0.6477)
			(end -0.2794 -0.6477)
			(stroke
				(width 0)
				(type default)
			)
			(fill no)
			(layer "B.Fab")
		)
		(pad "1" smd custom
			(at 0 -0.2794 270)
			(size 0.0762 0.0762)
			(layers "B.Cu" "B.Mask" "B.Paste")
			(net "P0V975")
			(options
				(clearance outline)
				(anchor circle)
			)
			(primitives
				(gr_poly
					(pts
						(arc
							(start 0.1524 0.127)
							(mid 0.137521 0.162921)
							(end 0.1016 0.1778)
						)
						(arc
							(start -0.1016 0.1778)
							(mid -0.137521 0.162921)
							(end -0.1524 0.127)
						)
						(arc
							(start -0.1524 -0.127)
							(mid -0.137521 -0.162921)
							(end -0.1016 -0.1778)
						)
						(arc
							(start 0.1016 -0.1778)
							(mid 0.137521 -0.162921)
							(end 0.1524 -0.127)
						)
					)
					(width 0)
					(fill yes)
				)
			)
		)
		(pad "2" smd custom
			(at 0 0.2794 270)
			(size 0.0762 0.0762)
			(layers "B.Cu" "B.Mask" "B.Paste")
			(net "GND")
			(options
				(clearance outline)
				(anchor circle)
			)
			(primitives
				(gr_poly
					(pts
						(arc
							(start 0.1524 0.127)
							(mid 0.137521 0.162921)
							(end 0.1016 0.1778)
						)
						(arc
							(start -0.1016 0.1778)
							(mid -0.137521 0.162921)
							(end -0.1524 0.127)
						)
						(arc
							(start -0.1524 -0.127)
							(mid -0.137521 -0.162921)
							(end -0.1016 -0.1778)
						)
						(arc
							(start 0.1016 -0.1778)
							(mid 0.137521 -0.162921)
							(end 0.1524 -0.127)
						)
					)
					(width 0)
					(fill yes)
				)
			)
		)
	)
	(footprint ""
		(layer "B.Cu")
		(at 197.5612 -51.435 -90)
		(property "Reference" "C346"
			(at 0 0 90)
			(layer "B.SilkS")
			(hide yes)
			(effects
				(font
					(size 1.27 1.27)
				)
				(justify mirror)
			)
		)
		(property "Value" "SC22U6D3V3MX-9-GP-U"
			(at 0 -2.8194 270)
			(unlocked yes)
			(layer "B.Fab")
			(hide yes)
			(effects
				(font
					(size 1.016 1.016)
					(thickness 0.1524)
				)
				(justify mirror)
			)
		)
		(property "Device Type" "C603H40"
			(at 0 -4.3434 270)
			(unlocked yes)
			(layer "B.Fab")
			(hide yes)
			(effects
				(font
					(size 1.016 1.016)
					(thickness 0.1524)
				)
				(justify mirror)
			)
		)
		(duplicate_pad_numbers_are_jumpers no)
		(fp_line
			(start -0.508 0)
			(end 0.508 0)
			(stroke
				(width 0.2032)
				(type default)
			)
			(layer "B.SilkS")
		)
		(fp_rect
			(start 0.5842 1.3335)
			(end -0.5842 -1.3335)
			(stroke
				(width 0)
				(type default)
			)
			(fill no)
			(layer "B.CrtYd")
		)
		(fp_rect
			(start 0.5842 1.3335)
			(end -0.5842 -1.3335)
			(stroke
				(width 0)
				(type default)
			)
			(fill no)
			(layer "B.Fab")
		)
		(pad "1" smd custom
			(at 0 -0.762 90)
			(size 0.2159 0.2159)
			(layers "B.Cu" "B.Mask" "B.Paste")
			(net "VDDA_SAS_REF_CLK")
			(options
				(clearance outline)
				(anchor circle)
			)
			(primitives
				(gr_poly
					(pts
						(arc
							(start -0.3302 0.4318)
							(mid -0.402042 0.402042)
							(end -0.4318 0.3302)
						)
						(arc
							(start -0.4318 -0.3302)
							(mid -0.402042 -0.402042)
							(end -0.3302 -0.4318)
						)
						(arc
							(start 0.3302 -0.4318)
							(mid 0.402042 -0.402042)
							(end 0.4318 -0.3302)
						)
						(arc
							(start 0.4318 0.3302)
							(mid 0.402042 0.402042)
							(end 0.3302 0.4318)
						)
					)
					(width 0)
					(fill yes)
				)
			)
		)
		(pad "2" smd custom
			(at 0 0.762 90)
			(size 0.2159 0.2159)
			(layers "B.Cu" "B.Mask" "B.Paste")
			(net "GND")
			(options
				(clearance outline)
				(anchor circle)
			)
			(primitives
				(gr_poly
					(pts
						(arc
							(start -0.3302 0.4318)
							(mid -0.402042 0.402042)
							(end -0.4318 0.3302)
						)
						(arc
							(start -0.4318 -0.3302)
							(mid -0.402042 -0.402042)
							(end -0.3302 -0.4318)
						)
						(arc
							(start 0.3302 -0.4318)
							(mid 0.402042 -0.402042)
							(end 0.4318 -0.3302)
						)
						(arc
							(start 0.4318 0.3302)
							(mid 0.402042 0.402042)
							(end 0.3302 0.4318)
						)
					)
					(width 0)
					(fill yes)
				)
			)
		)
	)
	(footprint ""
		(layer "B.Cu")
		(at 49.082452 -118.36019)
		(property "Reference" "TP19"
			(at 0 0 0)
			(layer "B.SilkS")
			(hide yes)
			(effects
				(font
					(size 1.27 1.27)
				)
				(justify mirror)
			)
		)
		(property "Value" "TPAD32-GP"
			(at 0.0508 -1.6764 0)
			(unlocked yes)
			(layer "B.Fab")
			(hide yes)
			(effects
				(font
					(size 1.016 1.016)
					(thickness 0.1524)
				)
				(justify mirror)
			)
		)
		(property "Device Type" "TPAD32"
			(at 0.0508 -3.2004 0)
			(unlocked yes)
			(layer "B.Fab")
			(hide yes)
			(effects
				(font
					(size 1.016 1.016)
					(thickness 0.1524)
				)
				(justify mirror)
			)
		)
		(duplicate_pad_numbers_are_jumpers no)
		(fp_poly
			(pts
				(arc
					(start 0.4064 0)
					(mid -0.4064 0)
					(end 0.4064 0)
				)
			)
			(stroke
				(width 0)
				(type default)
			)
			(fill no)
			(layer "B.CrtYd")
		)
		(fp_poly
			(pts
				(arc
					(start 0.7112 0)
					(mid -0.7112 0)
					(end 0.7112 0)
				)
			)
			(stroke
				(width 0)
				(type default)
			)
			(fill no)
			(layer "B.Fab")
		)
		(pad "1" smd circle
			(at 0 0 180)
			(size 0.8128 0.8128)
			(layers "B.Cu" "B.Mask" "B.Paste")
			(net "TEMP_3_ALERT")
		)
	)
	(footprint ""
		(layer "B.Cu")
		(at 191.5795 -68.3006 -90)
		(property "Reference" "C423"
			(at 0 0 90)
			(layer "B.SilkS")
			(hide yes)
			(effects
				(font
					(size 1.27 1.27)
				)
				(justify mirror)
			)
		)
		(property "Value" "SC1KP50V2KX-1GP"
			(at -1.1811 -2.7051 270)
			(unlocked yes)
			(layer "B.Fab")
			(hide yes)
			(effects
				(font
					(size 1.016 1.016)
					(thickness 0.1524)
				)
				(justify mirror)
			)
		)
		(property "Device Type" "C402H22"
			(at -1.1811 -4.2291 270)
			(unlocked yes)
			(layer "B.Fab")
			(hide yes)
			(effects
				(font
					(size 1.016 1.016)
					(thickness 0.1524)
				)
				(justify mirror)
			)
		)
		(duplicate_pad_numbers_are_jumpers no)
		(fp_rect
			(start 0.4318 0.9525)
			(end -0.4318 -0.9525)
			(stroke
				(width 0)
				(type default)
			)
			(fill no)
			(layer "B.CrtYd")
		)
		(fp_rect
			(start 0.4318 0.9525)
			(end -0.4318 -0.9525)
			(stroke
				(width 0)
				(type default)
			)
			(fill no)
			(layer "B.Fab")
		)
		(pad "1" smd custom
			(at 0 -0.4445 90)
			(size 0.1524 0.1524)
			(layers "B.Cu" "B.Mask" "B.Paste")
			(net "P0V975")
			(options
				(clearance outline)
				(anchor circle)
			)
			(primitives
				(gr_poly
					(pts
						(arc
							(start 0.3048 0.2032)
							(mid 0.275042 0.275042)
							(end 0.2032 0.3048)
						)
						(arc
							(start -0.2032 0.3048)
							(mid -0.275042 0.275042)
							(end -0.3048 0.2032)
						)
						(arc
							(start -0.3048 -0.2032)
							(mid -0.275042 -0.275042)
							(end -0.2032 -0.3048)
						)
						(arc
							(start 0.2032 -0.3048)
							(mid 0.275042 -0.275042)
							(end 0.3048 -0.2032)
						)
					)
					(width 0)
					(fill yes)
				)
			)
		)
		(pad "2" smd custom
			(at 0 0.4445 90)
			(size 0.1524 0.1524)
			(layers "B.Cu" "B.Mask" "B.Paste")
			(net "GND")
			(options
				(clearance outline)
				(anchor circle)
			)
			(primitives
				(gr_poly
					(pts
						(arc
							(start 0.3048 0.2032)
							(mid 0.275042 0.275042)
							(end 0.2032 0.3048)
						)
						(arc
							(start -0.2032 0.3048)
							(mid -0.275042 0.275042)
							(end -0.3048 0.2032)
						)
						(arc
							(start -0.3048 -0.2032)
							(mid -0.275042 -0.275042)
							(end -0.2032 -0.3048)
						)
						(arc
							(start 0.2032 -0.3048)
							(mid 0.275042 -0.275042)
							(end 0.3048 -0.2032)
						)
					)
					(width 0)
					(fill yes)
				)
			)
		)
	)
	(footprint ""
		(layer "B.Cu")
		(at 39.53764 -152.18156 -90)
		(property "Reference" "TP65"
			(at 0 0 90)
			(layer "B.SilkS")
			(hide yes)
			(effects
				(font
					(size 1.27 1.27)
				)
				(justify mirror)
			)
		)
		(property "Value" "TPAD28-2-GP"
			(at 0.0127 -1.6637 270)
			(unlocked yes)
			(layer "B.Fab")
			(hide yes)
			(effects
				(font
					(size 1.016 1.016)
					(thickness 0.1524)
				)
				(justify mirror)
			)
		)
		(property "Device Type" "TPAD28"
			(at 0.0127 -3.1877 270)
			(unlocked yes)
			(layer "B.Fab")
			(hide yes)
			(effects
				(font
					(size 1.016 1.016)
					(thickness 0.1524)
				)
				(justify mirror)
			)
		)
		(duplicate_pad_numbers_are_jumpers no)
		(fp_poly
			(pts
				(arc
					(start 0 -0.3556)
					(mid 0 0.3556)
					(end 0 -0.3556)
				)
			)
			(stroke
				(width 0)
				(type default)
			)
			(fill no)
			(layer "B.CrtYd")
		)
		(fp_poly
			(pts
				(arc
					(start 0 -0.6096)
					(mid 0 0.6096)
					(end 0 -0.6096)
				)
			)
			(stroke
				(width 0)
				(type default)
			)
			(fill no)
			(layer "B.Fab")
		)
		(pad "1" smd circle
			(at 0 0 90)
			(size 0.7112 0.7112)
			(layers "B.Cu" "B.Mask" "B.Paste")
			(net "TP_BMC_GPION6")
		)
	)
	(footprint ""
		(layer "B.Cu")
		(at 192.915032 -72.380856 -90)
		(property "Reference" "C367"
			(at 0 0 90)
			(layer "B.SilkS")
			(hide yes)
			(effects
				(font
					(size 1.27 1.27)
				)
				(justify mirror)
			)
		)
		(property "Value" "SCD1U6D3V1KX-GP"
			(at 2.8321 -1.7399 270)
			(unlocked yes)
			(layer "B.Fab")
			(hide yes)
			(effects
				(font
					(size 1.016 1.016)
					(thickness 0.1524)
				)
				(justify mirror)
			)
		)
		(property "Device Type" "C0201H13"
			(at 2.8321 -3.2639 270)
			(unlocked yes)
			(layer "B.Fab")
			(hide yes)
			(effects
				(font
					(size 1.016 1.016)
					(thickness 0.1524)
				)
				(justify mirror)
			)
		)
		(duplicate_pad_numbers_are_jumpers no)
		(fp_rect
			(start 0.2794 0.6477)
			(end -0.2794 -0.6477)
			(stroke
				(width 0)
				(type default)
			)
			(fill no)
			(layer "B.CrtYd")
		)
		(fp_rect
			(start 0.2794 0.6477)
			(end -0.2794 -0.6477)
			(stroke
				(width 0)
				(type default)
			)
			(fill no)
			(layer "B.Fab")
		)
		(pad "1" smd custom
			(at 0 -0.2794 90)
			(size 0.0762 0.0762)
			(layers "B.Cu" "B.Mask" "B.Paste")
			(net "PCE_AVDD")
			(options
				(clearance outline)
				(anchor circle)
			)
			(primitives
				(gr_poly
					(pts
						(arc
							(start 0.1524 0.127)
							(mid 0.137521 0.162921)
							(end 0.1016 0.1778)
						)
						(arc
							(start -0.1016 0.1778)
							(mid -0.137521 0.162921)
							(end -0.1524 0.127)
						)
						(arc
							(start -0.1524 -0.127)
							(mid -0.137521 -0.162921)
							(end -0.1016 -0.1778)
						)
						(arc
							(start 0.1016 -0.1778)
							(mid 0.137521 -0.162921)
							(end 0.1524 -0.127)
						)
					)
					(width 0)
					(fill yes)
				)
			)
		)
		(pad "2" smd custom
			(at 0 0.2794 90)
			(size 0.0762 0.0762)
			(layers "B.Cu" "B.Mask" "B.Paste")
			(net "GND")
			(options
				(clearance outline)
				(anchor circle)
			)
			(primitives
				(gr_poly
					(pts
						(arc
							(start 0.1524 0.127)
							(mid 0.137521 0.162921)
							(end 0.1016 0.1778)
						)
						(arc
							(start -0.1016 0.1778)
							(mid -0.137521 0.162921)
							(end -0.1524 0.127)
						)
						(arc
							(start -0.1524 -0.127)
							(mid -0.137521 -0.162921)
							(end -0.1016 -0.1778)
						)
						(arc
							(start 0.1016 -0.1778)
							(mid 0.137521 -0.162921)
							(end 0.1524 -0.127)
						)
					)
					(width 0)
					(fill yes)
				)
			)
		)
	)
	(footprint ""
		(layer "B.Cu")
		(at 67.771264 -142.960598)
		(property "Reference" "R161"
			(at 0 0 0)
			(layer "B.SilkS")
			(hide yes)
			(effects
				(font
					(size 1.27 1.27)
				)
				(justify mirror)
			)
		)
		(property "Value" "0R2J-2-GP"
			(at -0.064008 -3.993896 0)
			(unlocked yes)
			(layer "B.Fab")
			(hide yes)
			(effects
				(font
					(size 1.016 1.016)
					(thickness 0.1524)
				)
				(justify mirror)
			)
		)
		(property "Device Type" "R402H16"
			(at -0.064008 -5.517896 0)
			(unlocked yes)
			(layer "B.Fab")
			(hide yes)
			(effects
				(font
					(size 1.016 1.016)
					(thickness 0.1524)
				)
				(justify mirror)
			)
		)
		(duplicate_pad_numbers_are_jumpers no)
		(fp_line
			(start -0.508 -0.9398)
			(end 0.508 -0.9398)
			(stroke
				(width 0.1524)
				(type default)
			)
			(layer "B.SilkS")
		)
		(fp_line
			(start 0.508 -0.9398)
			(end 0.508 0.9398)
			(stroke
				(width 0.1524)
				(type default)
			)
			(layer "B.SilkS")
		)
		(fp_rect
			(start 0.508 0.9398)
			(end -0.508 -0.9398)
			(stroke
				(width 0)
				(type default)
			)
			(fill no)
			(layer "B.CrtYd")
		)
		(fp_rect
			(start 0.508 0.9398)
			(end -0.508 -0.9398)
			(stroke
				(width 0)
				(type default)
			)
			(fill no)
			(layer "B.Fab")
		)
		(pad "1" smd custom
			(at 0 -0.4445 180)
			(size 0.1397 0.1397)
			(layers "B.Cu" "B.Mask" "B.Paste")
			(net "BMC_SMB12_DAT")
			(options
				(clearance outline)
				(anchor circle)
			)
			(primitives
				(gr_poly
					(pts
						(arc
							(start -0.1778 0.2794)
							(mid -0.249642 0.249642)
							(end -0.2794 0.1778)
						)
						(arc
							(start -0.2794 -0.1778)
							(mid -0.249642 -0.249642)
							(end -0.1778 -0.2794)
						)
						(arc
							(start 0.1778 -0.2794)
							(mid 0.249642 -0.249642)
							(end 0.2794 -0.1778)
						)
						(arc
							(start 0.2794 0.1778)
							(mid 0.249642 0.249642)
							(end 0.1778 0.2794)
						)
					)
					(width 0)
					(fill yes)
				)
			)
		)
		(pad "2" smd custom
			(at 0 0.4445 180)
			(size 0.1397 0.1397)
			(layers "B.Cu" "B.Mask" "B.Paste")
			(net "I2C_DEBUG_SDA_L")
			(options
				(clearance outline)
				(anchor circle)
			)
			(primitives
				(gr_poly
					(pts
						(arc
							(start -0.1778 0.2794)
							(mid -0.249642 0.249642)
							(end -0.2794 0.1778)
						)
						(arc
							(start -0.2794 -0.1778)
							(mid -0.249642 -0.249642)
							(end -0.1778 -0.2794)
						)
						(arc
							(start 0.1778 -0.2794)
							(mid 0.249642 -0.249642)
							(end 0.2794 -0.1778)
						)
						(arc
							(start 0.2794 0.1778)
							(mid 0.249642 0.249642)
							(end 0.1778 0.2794)
						)
					)
					(width 0)
					(fill yes)
				)
			)
		)
	)
	(footprint ""
		(layer "B.Cu")
		(at 201.177398 -51.439572 -90)
		(property "Reference" "C334"
			(at 0 0 90)
			(layer "B.SilkS")
			(hide yes)
			(effects
				(font
					(size 1.27 1.27)
				)
				(justify mirror)
			)
		)
		(property "Value" "SC22U6D3V3MX-9-GP-U"
			(at 0 -2.8194 270)
			(unlocked yes)
			(layer "B.Fab")
			(hide yes)
			(effects
				(font
					(size 1.016 1.016)
					(thickness 0.1524)
				)
				(justify mirror)
			)
		)
		(property "Device Type" "C603H40"
			(at 0 -4.3434 270)
			(unlocked yes)
			(layer "B.Fab")
			(hide yes)
			(effects
				(font
					(size 1.016 1.016)
					(thickness 0.1524)
				)
				(justify mirror)
			)
		)
		(duplicate_pad_numbers_are_jumpers no)
		(fp_line
			(start -0.508 0)
			(end 0.508 0)
			(stroke
				(width 0.2032)
				(type default)
			)
			(layer "B.SilkS")
		)
		(fp_rect
			(start 0.5842 1.3335)
			(end -0.5842 -1.3335)
			(stroke
				(width 0)
				(type default)
			)
			(fill no)
			(layer "B.CrtYd")
		)
		(fp_rect
			(start 0.5842 1.3335)
			(end -0.5842 -1.3335)
			(stroke
				(width 0)
				(type default)
			)
			(fill no)
			(layer "B.Fab")
		)
		(pad "1" smd custom
			(at 0 -0.762 90)
			(size 0.2159 0.2159)
			(layers "B.Cu" "B.Mask" "B.Paste")
			(net "SYS_PLL_VDD")
			(options
				(clearance outline)
				(anchor circle)
			)
			(primitives
				(gr_poly
					(pts
						(arc
							(start -0.3302 0.4318)
							(mid -0.402042 0.402042)
							(end -0.4318 0.3302)
						)
						(arc
							(start -0.4318 -0.3302)
							(mid -0.402042 -0.402042)
							(end -0.3302 -0.4318)
						)
						(arc
							(start 0.3302 -0.4318)
							(mid 0.402042 -0.402042)
							(end 0.4318 -0.3302)
						)
						(arc
							(start 0.4318 0.3302)
							(mid 0.402042 0.402042)
							(end 0.3302 0.4318)
						)
					)
					(width 0)
					(fill yes)
				)
			)
		)
		(pad "2" smd custom
			(at 0 0.762 90)
			(size 0.2159 0.2159)
			(layers "B.Cu" "B.Mask" "B.Paste")
			(net "GND")
			(options
				(clearance outline)
				(anchor circle)
			)
			(primitives
				(gr_poly
					(pts
						(arc
							(start -0.3302 0.4318)
							(mid -0.402042 0.402042)
							(end -0.4318 0.3302)
						)
						(arc
							(start -0.4318 -0.3302)
							(mid -0.402042 -0.402042)
							(end -0.3302 -0.4318)
						)
						(arc
							(start 0.3302 -0.4318)
							(mid 0.402042 -0.402042)
							(end 0.4318 -0.3302)
						)
						(arc
							(start 0.4318 0.3302)
							(mid 0.402042 0.402042)
							(end 0.3302 0.4318)
						)
					)
					(width 0)
					(fill yes)
				)
			)
		)
	)
	(footprint ""
		(layer "B.Cu")
		(at 209.042 -61.0108 -90)
		(property "Reference" "R588"
			(at 0 0 90)
			(layer "B.SilkS")
			(hide yes)
			(effects
				(font
					(size 1.27 1.27)
				)
				(justify mirror)
			)
		)
		(property "Value" "2K2R2F-GP"
			(at -0.064008 -3.993896 270)
			(unlocked yes)
			(layer "B.Fab")
			(hide yes)
			(effects
				(font
					(size 1.016 1.016)
					(thickness 0.1524)
				)
				(justify mirror)
			)
		)
		(property "Device Type" "R402H16"
			(at -0.064008 -5.517896 270)
			(unlocked yes)
			(layer "B.Fab")
			(hide yes)
			(effects
				(font
					(size 1.016 1.016)
					(thickness 0.1524)
				)
				(justify mirror)
			)
		)
		(duplicate_pad_numbers_are_jumpers no)
		(fp_line
			(start -0.508 -0.9398)
			(end 0.508 -0.9398)
			(stroke
				(width 0.1524)
				(type default)
			)
			(layer "B.SilkS")
		)
		(fp_line
			(start 0.508 -0.9398)
			(end 0.508 0.9398)
			(stroke
				(width 0.1524)
				(type default)
			)
			(layer "B.SilkS")
		)
		(fp_rect
			(start 0.508 0.9398)
			(end -0.508 -0.9398)
			(stroke
				(width 0)
				(type default)
			)
			(fill no)
			(layer "B.CrtYd")
		)
		(fp_rect
			(start 0.508 0.9398)
			(end -0.508 -0.9398)
			(stroke
				(width 0)
				(type default)
			)
			(fill no)
			(layer "B.Fab")
		)
		(pad "1" smd custom
			(at 0 -0.4445 90)
			(size 0.1397 0.1397)
			(layers "B.Cu" "B.Mask" "B.Paste")
			(net "P1V8")
			(options
				(clearance outline)
				(anchor circle)
			)
			(primitives
				(gr_poly
					(pts
						(arc
							(start -0.1778 0.2794)
							(mid -0.249642 0.249642)
							(end -0.2794 0.1778)
						)
						(arc
							(start -0.2794 -0.1778)
							(mid -0.249642 -0.249642)
							(end -0.1778 -0.2794)
						)
						(arc
							(start 0.1778 -0.2794)
							(mid 0.249642 -0.249642)
							(end 0.2794 -0.1778)
						)
						(arc
							(start 0.2794 0.1778)
							(mid 0.249642 0.249642)
							(end 0.1778 0.2794)
						)
					)
					(width 0)
					(fill yes)
				)
			)
		)
		(pad "2" smd custom
			(at 0 0.4445 90)
			(size 0.1397 0.1397)
			(layers "B.Cu" "B.Mask" "B.Paste")
			(net "SIO_CLK_0")
			(options
				(clearance outline)
				(anchor circle)
			)
			(primitives
				(gr_poly
					(pts
						(arc
							(start -0.1778 0.2794)
							(mid -0.249642 0.249642)
							(end -0.2794 0.1778)
						)
						(arc
							(start -0.2794 -0.1778)
							(mid -0.249642 -0.249642)
							(end -0.1778 -0.2794)
						)
						(arc
							(start 0.1778 -0.2794)
							(mid 0.249642 -0.249642)
							(end 0.2794 -0.1778)
						)
						(arc
							(start 0.2794 0.1778)
							(mid 0.249642 0.249642)
							(end 0.1778 0.2794)
						)
					)
					(width 0)
					(fill yes)
				)
			)
		)
	)
	(footprint ""
		(layer "B.Cu")
		(at 49.0855 -142.0495 -90)
		(property "Reference" "C83"
			(at 0 0 90)
			(layer "B.SilkS")
			(hide yes)
			(effects
				(font
					(size 1.27 1.27)
				)
				(justify mirror)
			)
		)
		(property "Value" "SC1U16V3KX-5GP"
			(at 0 -2.8194 270)
			(unlocked yes)
			(layer "B.Fab")
			(hide yes)
			(effects
				(font
					(size 1.016 1.016)
					(thickness 0.1524)
				)
				(justify mirror)
			)
		)
		(property "Device Type" "C603H36"
			(at 0 -4.3434 270)
			(unlocked yes)
			(layer "B.Fab")
			(hide yes)
			(effects
				(font
					(size 1.016 1.016)
					(thickness 0.1524)
				)
				(justify mirror)
			)
		)
		(duplicate_pad_numbers_are_jumpers no)
		(fp_line
			(start -0.508 0)
			(end 0.508 0)
			(stroke
				(width 0.2032)
				(type default)
			)
			(layer "B.SilkS")
		)
		(fp_rect
			(start 0.5842 1.3335)
			(end -0.5842 -1.3335)
			(stroke
				(width 0)
				(type default)
			)
			(fill no)
			(layer "B.CrtYd")
		)
		(fp_rect
			(start 0.5842 1.3335)
			(end -0.5842 -1.3335)
			(stroke
				(width 0)
				(type default)
			)
			(fill no)
			(layer "B.Fab")
		)
		(pad "1" smd custom
			(at 0 -0.762 90)
			(size 0.2159 0.2159)
			(layers "B.Cu" "B.Mask" "B.Paste")
			(net "JTAG_BMC_TRST_N")
			(options
				(clearance outline)
				(anchor circle)
			)
			(primitives
				(gr_poly
					(pts
						(arc
							(start -0.3302 0.4318)
							(mid -0.402042 0.402042)
							(end -0.4318 0.3302)
						)
						(arc
							(start -0.4318 -0.3302)
							(mid -0.402042 -0.402042)
							(end -0.3302 -0.4318)
						)
						(arc
							(start 0.3302 -0.4318)
							(mid 0.402042 -0.402042)
							(end 0.4318 -0.3302)
						)
						(arc
							(start 0.4318 0.3302)
							(mid 0.402042 0.402042)
							(end 0.3302 0.4318)
						)
					)
					(width 0)
					(fill yes)
				)
			)
		)
		(pad "2" smd custom
			(at 0 0.762 90)
			(size 0.2159 0.2159)
			(layers "B.Cu" "B.Mask" "B.Paste")
			(net "GND")
			(options
				(clearance outline)
				(anchor circle)
			)
			(primitives
				(gr_poly
					(pts
						(arc
							(start -0.3302 0.4318)
							(mid -0.402042 0.402042)
							(end -0.4318 0.3302)
						)
						(arc
							(start -0.4318 -0.3302)
							(mid -0.402042 -0.402042)
							(end -0.3302 -0.4318)
						)
						(arc
							(start 0.3302 -0.4318)
							(mid 0.402042 -0.402042)
							(end 0.4318 -0.3302)
						)
						(arc
							(start 0.4318 0.3302)
							(mid 0.402042 0.402042)
							(end 0.3302 0.4318)
						)
					)
					(width 0)
					(fill yes)
				)
			)
		)
	)
	(footprint ""
		(layer "B.Cu")
		(at 43.31843 -137.103866)
		(property "Reference" "TP27"
			(at 0 0 0)
			(layer "B.SilkS")
			(hide yes)
			(effects
				(font
					(size 1.27 1.27)
				)
				(justify mirror)
			)
		)
		(property "Value" "TPAD28-2-GP"
			(at 0.0127 -1.6637 0)
			(unlocked yes)
			(layer "B.Fab")
			(hide yes)
			(effects
				(font
					(size 1.016 1.016)
					(thickness 0.1524)
				)
				(justify mirror)
			)
		)
		(property "Device Type" "TPAD28"
			(at 0.0127 -3.1877 0)
			(unlocked yes)
			(layer "B.Fab")
			(hide yes)
			(effects
				(font
					(size 1.016 1.016)
					(thickness 0.1524)
				)
				(justify mirror)
			)
		)
		(duplicate_pad_numbers_are_jumpers no)
		(fp_poly
			(pts
				(arc
					(start 0.3556 0)
					(mid -0.3556 0)
					(end 0.3556 0)
				)
			)
			(stroke
				(width 0)
				(type default)
			)
			(fill no)
			(layer "B.CrtYd")
		)
		(fp_poly
			(pts
				(arc
					(start 0.6096 0)
					(mid -0.6096 0)
					(end 0.6096 0)
				)
			)
			(stroke
				(width 0)
				(type default)
			)
			(fill no)
			(layer "B.Fab")
		)
		(pad "1" smd circle
			(at 0 0 180)
			(size 0.7112 0.7112)
			(layers "B.Cu" "B.Mask" "B.Paste")
			(net "TP_BMC_GPIOR1")
		)
	)
	(footprint ""
		(layer "B.Cu")
		(at 47.4726 -135.7376 180)
		(property "Reference" "R140"
			(at 0 0 0)
			(layer "B.SilkS")
			(hide yes)
			(effects
				(font
					(size 1.27 1.27)
				)
				(justify mirror)
			)
		)
		(property "Value" "100KR2F-L1-GP"
			(at -0.064008 -3.993896 180)
			(unlocked yes)
			(layer "B.Fab")
			(hide yes)
			(effects
				(font
					(size 1.016 1.016)
					(thickness 0.1524)
				)
				(justify mirror)
			)
		)
		(property "Device Type" "R402H16"
			(at -0.064008 -5.517896 180)
			(unlocked yes)
			(layer "B.Fab")
			(hide yes)
			(effects
				(font
					(size 1.016 1.016)
					(thickness 0.1524)
				)
				(justify mirror)
			)
		)
		(duplicate_pad_numbers_are_jumpers no)
		(fp_line
			(start 0.508 -0.9398)
			(end 0.508 0.9398)
			(stroke
				(width 0.1524)
				(type default)
			)
			(layer "B.SilkS")
		)
		(fp_line
			(start -0.508 -0.9398)
			(end 0.508 -0.9398)
			(stroke
				(width 0.1524)
				(type default)
			)
			(layer "B.SilkS")
		)
		(fp_rect
			(start 0.508 0.9398)
			(end -0.508 -0.9398)
			(stroke
				(width 0)
				(type default)
			)
			(fill no)
			(layer "B.CrtYd")
		)
		(fp_rect
			(start 0.508 0.9398)
			(end -0.508 -0.9398)
			(stroke
				(width 0)
				(type default)
			)
			(fill no)
			(layer "B.Fab")
		)
		(pad "1" smd custom
			(at 0 -0.4445)
			(size 0.1397 0.1397)
			(layers "B.Cu" "B.Mask" "B.Paste")
			(net "GND")
			(options
				(clearance outline)
				(anchor circle)
			)
			(primitives
				(gr_poly
					(pts
						(arc
							(start -0.1778 0.2794)
							(mid -0.249642 0.249642)
							(end -0.2794 0.1778)
						)
						(arc
							(start -0.2794 -0.1778)
							(mid -0.249642 -0.249642)
							(end -0.1778 -0.2794)
						)
						(arc
							(start 0.1778 -0.2794)
							(mid 0.249642 -0.249642)
							(end 0.2794 -0.1778)
						)
						(arc
							(start 0.2794 0.1778)
							(mid 0.249642 0.249642)
							(end 0.1778 0.2794)
						)
					)
					(width 0)
					(fill yes)
				)
			)
		)
		(pad "2" smd custom
			(at 0 0.4445)
			(size 0.1397 0.1397)
			(layers "B.Cu" "B.Mask" "B.Paste")
			(net "PD_PERST_N")
			(options
				(clearance outline)
				(anchor circle)
			)
			(primitives
				(gr_poly
					(pts
						(arc
							(start -0.1778 0.2794)
							(mid -0.249642 0.249642)
							(end -0.2794 0.1778)
						)
						(arc
							(start -0.2794 -0.1778)
							(mid -0.249642 -0.249642)
							(end -0.1778 -0.2794)
						)
						(arc
							(start 0.1778 -0.2794)
							(mid 0.249642 -0.249642)
							(end 0.2794 -0.1778)
						)
						(arc
							(start 0.2794 0.1778)
							(mid 0.249642 0.249642)
							(end 0.1778 0.2794)
						)
					)
					(width 0)
					(fill yes)
				)
			)
		)
	)
	(footprint ""
		(layer "B.Cu")
		(at 12.091924 -136.715246 90)
		(property "Reference" "R251"
			(at 0 0 90)
			(layer "B.SilkS")
			(hide yes)
			(effects
				(font
					(size 1.27 1.27)
				)
				(justify mirror)
			)
		)
		(property "Value" "120R2F-GP"
			(at -0.064008 -3.993896 90)
			(unlocked yes)
			(layer "B.Fab")
			(hide yes)
			(effects
				(font
					(size 1.016 1.016)
					(thickness 0.1524)
				)
				(justify mirror)
			)
		)
		(property "Device Type" "R402H16"
			(at -0.064008 -5.517896 90)
			(unlocked yes)
			(layer "B.Fab")
			(hide yes)
			(effects
				(font
					(size 1.016 1.016)
					(thickness 0.1524)
				)
				(justify mirror)
			)
		)
		(duplicate_pad_numbers_are_jumpers no)
		(fp_line
			(start 0.508 -0.9398)
			(end 0.508 0.9398)
			(stroke
				(width 0.1524)
				(type default)
			)
			(layer "B.SilkS")
		)
		(fp_line
			(start -0.508 -0.9398)
			(end 0.508 -0.9398)
			(stroke
				(width 0.1524)
				(type default)
			)
			(layer "B.SilkS")
		)
		(fp_rect
			(start 0.508 0.9398)
			(end -0.508 -0.9398)
			(stroke
				(width 0)
				(type default)
			)
			(fill no)
			(layer "B.CrtYd")
		)
		(fp_rect
			(start 0.508 0.9398)
			(end -0.508 -0.9398)
			(stroke
				(width 0)
				(type default)
			)
			(fill no)
			(layer "B.Fab")
		)
		(pad "1" smd custom
			(at 0 -0.4445 270)
			(size 0.1397 0.1397)
			(layers "B.Cu" "B.Mask" "B.Paste")
			(net "MEMA_8")
			(options
				(clearance outline)
				(anchor circle)
			)
			(primitives
				(gr_poly
					(pts
						(arc
							(start -0.1778 0.2794)
							(mid -0.249642 0.249642)
							(end -0.2794 0.1778)
						)
						(arc
							(start -0.2794 -0.1778)
							(mid -0.249642 -0.249642)
							(end -0.1778 -0.2794)
						)
						(arc
							(start 0.1778 -0.2794)
							(mid 0.249642 -0.249642)
							(end 0.2794 -0.1778)
						)
						(arc
							(start 0.2794 0.1778)
							(mid 0.249642 0.249642)
							(end 0.1778 0.2794)
						)
					)
					(width 0)
					(fill yes)
				)
			)
		)
		(pad "2" smd custom
			(at 0 0.4445 270)
			(size 0.1397 0.1397)
			(layers "B.Cu" "B.Mask" "B.Paste")
			(net "P1V2_STBY")
			(options
				(clearance outline)
				(anchor circle)
			)
			(primitives
				(gr_poly
					(pts
						(arc
							(start -0.1778 0.2794)
							(mid -0.249642 0.249642)
							(end -0.2794 0.1778)
						)
						(arc
							(start -0.2794 -0.1778)
							(mid -0.249642 -0.249642)
							(end -0.1778 -0.2794)
						)
						(arc
							(start 0.1778 -0.2794)
							(mid 0.249642 -0.249642)
							(end 0.2794 -0.1778)
						)
						(arc
							(start 0.2794 0.1778)
							(mid 0.249642 0.249642)
							(end 0.1778 0.2794)
						)
					)
					(width 0)
					(fill yes)
				)
			)
		)
	)
	(footprint ""
		(layer "B.Cu")
		(at 69.46646 -148.869908)
		(property "Reference" "R381"
			(at 0 0 0)
			(layer "B.SilkS")
			(hide yes)
			(effects
				(font
					(size 1.27 1.27)
				)
				(justify mirror)
			)
		)
		(property "Value" "4K7R2F-GP"
			(at -0.064008 -3.993896 0)
			(unlocked yes)
			(layer "B.Fab")
			(hide yes)
			(effects
				(font
					(size 1.016 1.016)
					(thickness 0.1524)
				)
				(justify mirror)
			)
		)
		(property "Device Type" "R402H16"
			(at -0.064008 -5.517896 0)
			(unlocked yes)
			(layer "B.Fab")
			(hide yes)
			(effects
				(font
					(size 1.016 1.016)
					(thickness 0.1524)
				)
				(justify mirror)
			)
		)
		(duplicate_pad_numbers_are_jumpers no)
		(fp_line
			(start -0.508 -0.9398)
			(end 0.508 -0.9398)
			(stroke
				(width 0.1524)
				(type default)
			)
			(layer "B.SilkS")
		)
		(fp_line
			(start 0.508 -0.9398)
			(end 0.508 0.9398)
			(stroke
				(width 0.1524)
				(type default)
			)
			(layer "B.SilkS")
		)
		(fp_rect
			(start 0.508 0.9398)
			(end -0.508 -0.9398)
			(stroke
				(width 0)
				(type default)
			)
			(fill no)
			(layer "B.CrtYd")
		)
		(fp_rect
			(start 0.508 0.9398)
			(end -0.508 -0.9398)
			(stroke
				(width 0)
				(type default)
			)
			(fill no)
			(layer "B.Fab")
		)
		(pad "1" smd custom
			(at 0 -0.4445 180)
			(size 0.1397 0.1397)
			(layers "B.Cu" "B.Mask" "B.Paste")
			(net "P3V3_STBY")
			(options
				(clearance outline)
				(anchor circle)
			)
			(primitives
				(gr_poly
					(pts
						(arc
							(start -0.1778 0.2794)
							(mid -0.249642 0.249642)
							(end -0.2794 0.1778)
						)
						(arc
							(start -0.2794 -0.1778)
							(mid -0.249642 -0.249642)
							(end -0.1778 -0.2794)
						)
						(arc
							(start 0.1778 -0.2794)
							(mid 0.249642 -0.249642)
							(end 0.2794 -0.1778)
						)
						(arc
							(start 0.2794 0.1778)
							(mid 0.249642 0.249642)
							(end 0.1778 0.2794)
						)
					)
					(width 0)
					(fill yes)
				)
			)
		)
		(pad "2" smd custom
			(at 0 0.4445 180)
			(size 0.1397 0.1397)
			(layers "B.Cu" "B.Mask" "B.Paste")
			(net "NCSI_TXD0")
			(options
				(clearance outline)
				(anchor circle)
			)
			(primitives
				(gr_poly
					(pts
						(arc
							(start -0.1778 0.2794)
							(mid -0.249642 0.249642)
							(end -0.2794 0.1778)
						)
						(arc
							(start -0.2794 -0.1778)
							(mid -0.249642 -0.249642)
							(end -0.1778 -0.2794)
						)
						(arc
							(start 0.1778 -0.2794)
							(mid 0.249642 -0.249642)
							(end 0.2794 -0.1778)
						)
						(arc
							(start 0.2794 0.1778)
							(mid 0.249642 0.249642)
							(end 0.1778 0.2794)
						)
					)
					(width 0)
					(fill yes)
				)
			)
		)
	)
	(footprint ""
		(layer "B.Cu")
		(at 44.4246 -128.2192 180)
		(property "Reference" "R371"
			(at 0 0 0)
			(layer "B.SilkS")
			(hide yes)
			(effects
				(font
					(size 1.27 1.27)
				)
				(justify mirror)
			)
		)
		(property "Value" "4K7R2F-GP"
			(at -0.064008 -3.993896 180)
			(unlocked yes)
			(layer "B.Fab")
			(hide yes)
			(effects
				(font
					(size 1.016 1.016)
					(thickness 0.1524)
				)
				(justify mirror)
			)
		)
		(property "Device Type" "R402H16"
			(at -0.064008 -5.517896 180)
			(unlocked yes)
			(layer "B.Fab")
			(hide yes)
			(effects
				(font
					(size 1.016 1.016)
					(thickness 0.1524)
				)
				(justify mirror)
			)
		)
		(duplicate_pad_numbers_are_jumpers no)
		(fp_line
			(start 0.508 -0.9398)
			(end 0.508 0.9398)
			(stroke
				(width 0.1524)
				(type default)
			)
			(layer "B.SilkS")
		)
		(fp_line
			(start -0.508 -0.9398)
			(end 0.508 -0.9398)
			(stroke
				(width 0.1524)
				(type default)
			)
			(layer "B.SilkS")
		)
		(fp_rect
			(start 0.508 0.9398)
			(end -0.508 -0.9398)
			(stroke
				(width 0)
				(type default)
			)
			(fill no)
			(layer "B.CrtYd")
		)
		(fp_rect
			(start 0.508 0.9398)
			(end -0.508 -0.9398)
			(stroke
				(width 0)
				(type default)
			)
			(fill no)
			(layer "B.Fab")
		)
		(pad "1" smd custom
			(at 0 -0.4445)
			(size 0.1397 0.1397)
			(layers "B.Cu" "B.Mask" "B.Paste")
			(net "P3V3_STBY")
			(options
				(clearance outline)
				(anchor circle)
			)
			(primitives
				(gr_poly
					(pts
						(arc
							(start -0.1778 0.2794)
							(mid -0.249642 0.249642)
							(end -0.2794 0.1778)
						)
						(arc
							(start -0.2794 -0.1778)
							(mid -0.249642 -0.249642)
							(end -0.1778 -0.2794)
						)
						(arc
							(start 0.1778 -0.2794)
							(mid 0.249642 -0.249642)
							(end 0.2794 -0.1778)
						)
						(arc
							(start 0.2794 0.1778)
							(mid 0.249642 0.249642)
							(end 0.1778 0.2794)
						)
					)
					(width 0)
					(fill yes)
				)
			)
		)
		(pad "2" smd custom
			(at 0 0.4445)
			(size 0.1397 0.1397)
			(layers "B.Cu" "B.Mask" "B.Paste")
			(net "BMC_SPI_MISO")
			(options
				(clearance outline)
				(anchor circle)
			)
			(primitives
				(gr_poly
					(pts
						(arc
							(start -0.1778 0.2794)
							(mid -0.249642 0.249642)
							(end -0.2794 0.1778)
						)
						(arc
							(start -0.2794 -0.1778)
							(mid -0.249642 -0.249642)
							(end -0.1778 -0.2794)
						)
						(arc
							(start 0.1778 -0.2794)
							(mid 0.249642 -0.249642)
							(end 0.2794 -0.1778)
						)
						(arc
							(start 0.2794 0.1778)
							(mid 0.249642 0.249642)
							(end 0.1778 0.2794)
						)
					)
					(width 0)
					(fill yes)
				)
			)
		)
	)
	(footprint ""
		(layer "B.Cu")
		(at 189.2554 -65.3796 90)
		(property "Reference" "C399"
			(at 0 0 90)
			(layer "B.SilkS")
			(hide yes)
			(effects
				(font
					(size 1.27 1.27)
				)
				(justify mirror)
			)
		)
		(property "Value" "SCD1U6D3V1KX-GP"
			(at 2.8321 -1.7399 90)
			(unlocked yes)
			(layer "B.Fab")
			(hide yes)
			(effects
				(font
					(size 1.016 1.016)
					(thickness 0.1524)
				)
				(justify mirror)
			)
		)
		(property "Device Type" "C0201H13"
			(at 2.8321 -3.2639 90)
			(unlocked yes)
			(layer "B.Fab")
			(hide yes)
			(effects
				(font
					(size 1.016 1.016)
					(thickness 0.1524)
				)
				(justify mirror)
			)
		)
		(duplicate_pad_numbers_are_jumpers no)
		(fp_rect
			(start 0.2794 0.6477)
			(end -0.2794 -0.6477)
			(stroke
				(width 0)
				(type default)
			)
			(fill no)
			(layer "B.CrtYd")
		)
		(fp_rect
			(start 0.2794 0.6477)
			(end -0.2794 -0.6477)
			(stroke
				(width 0)
				(type default)
			)
			(fill no)
			(layer "B.Fab")
		)
		(pad "1" smd custom
			(at 0 -0.2794 270)
			(size 0.0762 0.0762)
			(layers "B.Cu" "B.Mask" "B.Paste")
			(net "P0V975")
			(options
				(clearance outline)
				(anchor circle)
			)
			(primitives
				(gr_poly
					(pts
						(arc
							(start 0.1524 0.127)
							(mid 0.137521 0.162921)
							(end 0.1016 0.1778)
						)
						(arc
							(start -0.1016 0.1778)
							(mid -0.137521 0.162921)
							(end -0.1524 0.127)
						)
						(arc
							(start -0.1524 -0.127)
							(mid -0.137521 -0.162921)
							(end -0.1016 -0.1778)
						)
						(arc
							(start 0.1016 -0.1778)
							(mid 0.137521 -0.162921)
							(end 0.1524 -0.127)
						)
					)
					(width 0)
					(fill yes)
				)
			)
		)
		(pad "2" smd custom
			(at 0 0.2794 270)
			(size 0.0762 0.0762)
			(layers "B.Cu" "B.Mask" "B.Paste")
			(net "GND")
			(options
				(clearance outline)
				(anchor circle)
			)
			(primitives
				(gr_poly
					(pts
						(arc
							(start 0.1524 0.127)
							(mid 0.137521 0.162921)
							(end 0.1016 0.1778)
						)
						(arc
							(start -0.1016 0.1778)
							(mid -0.137521 0.162921)
							(end -0.1524 0.127)
						)
						(arc
							(start -0.1524 -0.127)
							(mid -0.137521 -0.162921)
							(end -0.1016 -0.1778)
						)
						(arc
							(start 0.1016 -0.1778)
							(mid 0.137521 -0.162921)
							(end 0.1524 -0.127)
						)
					)
					(width 0)
					(fill yes)
				)
			)
		)
	)
	(footprint ""
		(layer "B.Cu")
		(at 56.850026 -161.083752 90)
		(property "Reference" "C123"
			(at 0 0 90)
			(layer "B.SilkS")
			(hide yes)
			(effects
				(font
					(size 1.27 1.27)
				)
				(justify mirror)
			)
		)
		(property "Value" "SCD1U25V2KX-2-GP"
			(at -1.1811 -2.7051 90)
			(unlocked yes)
			(layer "B.Fab")
			(hide yes)
			(effects
				(font
					(size 1.016 1.016)
					(thickness 0.1524)
				)
				(justify mirror)
			)
		)
		(property "Device Type" "C402H22"
			(at -1.1811 -4.2291 90)
			(unlocked yes)
			(layer "B.Fab")
			(hide yes)
			(effects
				(font
					(size 1.016 1.016)
					(thickness 0.1524)
				)
				(justify mirror)
			)
		)
		(duplicate_pad_numbers_are_jumpers no)
		(fp_rect
			(start 0.4318 0.9525)
			(end -0.4318 -0.9525)
			(stroke
				(width 0)
				(type default)
			)
			(fill no)
			(layer "B.CrtYd")
		)
		(fp_rect
			(start 0.4318 0.9525)
			(end -0.4318 -0.9525)
			(stroke
				(width 0)
				(type default)
			)
			(fill no)
			(layer "B.Fab")
		)
		(pad "1" smd custom
			(at 0 -0.4445 270)
			(size 0.1524 0.1524)
			(layers "B.Cu" "B.Mask" "B.Paste")
			(net "ADC_P5V_STBY")
			(options
				(clearance outline)
				(anchor circle)
			)
			(primitives
				(gr_poly
					(pts
						(arc
							(start 0.3048 0.2032)
							(mid 0.275042 0.275042)
							(end 0.2032 0.3048)
						)
						(arc
							(start -0.2032 0.3048)
							(mid -0.275042 0.275042)
							(end -0.3048 0.2032)
						)
						(arc
							(start -0.3048 -0.2032)
							(mid -0.275042 -0.275042)
							(end -0.2032 -0.3048)
						)
						(arc
							(start 0.2032 -0.3048)
							(mid 0.275042 -0.275042)
							(end 0.3048 -0.2032)
						)
					)
					(width 0)
					(fill yes)
				)
			)
		)
		(pad "2" smd custom
			(at 0 0.4445 270)
			(size 0.1524 0.1524)
			(layers "B.Cu" "B.Mask" "B.Paste")
			(net "GND")
			(options
				(clearance outline)
				(anchor circle)
			)
			(primitives
				(gr_poly
					(pts
						(arc
							(start 0.3048 0.2032)
							(mid 0.275042 0.275042)
							(end 0.2032 0.3048)
						)
						(arc
							(start -0.2032 0.3048)
							(mid -0.275042 0.275042)
							(end -0.3048 0.2032)
						)
						(arc
							(start -0.3048 -0.2032)
							(mid -0.275042 -0.275042)
							(end -0.2032 -0.3048)
						)
						(arc
							(start 0.2032 -0.3048)
							(mid 0.275042 -0.275042)
							(end 0.3048 -0.2032)
						)
					)
					(width 0)
					(fill yes)
				)
			)
		)
	)
	(footprint ""
		(layer "B.Cu")
		(at 179.9082 -114.554)
		(property "Reference" "R567"
			(at 0 0 0)
			(layer "B.SilkS")
			(hide yes)
			(effects
				(font
					(size 1.27 1.27)
				)
				(justify mirror)
			)
		)
		(property "Value" "4K7R2F-GP"
			(at -0.064008 -3.993896 0)
			(unlocked yes)
			(layer "B.Fab")
			(hide yes)
			(effects
				(font
					(size 1.016 1.016)
					(thickness 0.1524)
				)
				(justify mirror)
			)
		)
		(property "Device Type" "R402H16"
			(at -0.064008 -5.517896 0)
			(unlocked yes)
			(layer "B.Fab")
			(hide yes)
			(effects
				(font
					(size 1.016 1.016)
					(thickness 0.1524)
				)
				(justify mirror)
			)
		)
		(duplicate_pad_numbers_are_jumpers no)
		(fp_line
			(start -0.508 -0.9398)
			(end 0.508 -0.9398)
			(stroke
				(width 0.1524)
				(type default)
			)
			(layer "B.SilkS")
		)
		(fp_line
			(start 0.508 -0.9398)
			(end 0.508 0.9398)
			(stroke
				(width 0.1524)
				(type default)
			)
			(layer "B.SilkS")
		)
		(fp_rect
			(start 0.508 0.9398)
			(end -0.508 -0.9398)
			(stroke
				(width 0)
				(type default)
			)
			(fill no)
			(layer "B.CrtYd")
		)
		(fp_rect
			(start 0.508 0.9398)
			(end -0.508 -0.9398)
			(stroke
				(width 0)
				(type default)
			)
			(fill no)
			(layer "B.Fab")
		)
		(pad "1" smd custom
			(at 0 -0.4445 180)
			(size 0.1397 0.1397)
			(layers "B.Cu" "B.Mask" "B.Paste")
			(net "IOM_FULL_PGOOD")
			(options
				(clearance outline)
				(anchor circle)
			)
			(primitives
				(gr_poly
					(pts
						(arc
							(start -0.1778 0.2794)
							(mid -0.249642 0.249642)
							(end -0.2794 0.1778)
						)
						(arc
							(start -0.2794 -0.1778)
							(mid -0.249642 -0.249642)
							(end -0.1778 -0.2794)
						)
						(arc
							(start 0.1778 -0.2794)
							(mid 0.249642 -0.249642)
							(end 0.2794 -0.1778)
						)
						(arc
							(start 0.2794 0.1778)
							(mid 0.249642 0.249642)
							(end 0.1778 0.2794)
						)
					)
					(width 0)
					(fill yes)
				)
			)
		)
		(pad "2" smd custom
			(at 0 0.4445 180)
			(size 0.1397 0.1397)
			(layers "B.Cu" "B.Mask" "B.Paste")
			(net "P3V3_STBY")
			(options
				(clearance outline)
				(anchor circle)
			)
			(primitives
				(gr_poly
					(pts
						(arc
							(start -0.1778 0.2794)
							(mid -0.249642 0.249642)
							(end -0.2794 0.1778)
						)
						(arc
							(start -0.2794 -0.1778)
							(mid -0.249642 -0.249642)
							(end -0.1778 -0.2794)
						)
						(arc
							(start 0.1778 -0.2794)
							(mid 0.249642 -0.249642)
							(end 0.2794 -0.1778)
						)
						(arc
							(start 0.2794 0.1778)
							(mid 0.249642 0.249642)
							(end 0.1778 0.2794)
						)
					)
					(width 0)
					(fill yes)
				)
			)
		)
	)
	(footprint ""
		(layer "B.Cu")
		(at 55.8165 -154.7241 90)
		(property "Reference" "C87"
			(at 0 0 90)
			(layer "B.SilkS")
			(hide yes)
			(effects
				(font
					(size 1.27 1.27)
				)
				(justify mirror)
			)
		)
		(property "Value" "SC1U16V3KX-5GP"
			(at 0 -2.8194 90)
			(unlocked yes)
			(layer "B.Fab")
			(hide yes)
			(effects
				(font
					(size 1.016 1.016)
					(thickness 0.1524)
				)
				(justify mirror)
			)
		)
		(property "Device Type" "C603H36"
			(at 0 -4.3434 90)
			(unlocked yes)
			(layer "B.Fab")
			(hide yes)
			(effects
				(font
					(size 1.016 1.016)
					(thickness 0.1524)
				)
				(justify mirror)
			)
		)
		(duplicate_pad_numbers_are_jumpers no)
		(fp_line
			(start -0.508 0)
			(end 0.508 0)
			(stroke
				(width 0.2032)
				(type default)
			)
			(layer "B.SilkS")
		)
		(fp_rect
			(start 0.5842 1.3335)
			(end -0.5842 -1.3335)
			(stroke
				(width 0)
				(type default)
			)
			(fill no)
			(layer "B.CrtYd")
		)
		(fp_rect
			(start 0.5842 1.3335)
			(end -0.5842 -1.3335)
			(stroke
				(width 0)
				(type default)
			)
			(fill no)
			(layer "B.Fab")
		)
		(pad "1" smd custom
			(at 0 -0.762 270)
			(size 0.2159 0.2159)
			(layers "B.Cu" "B.Mask" "B.Paste")
			(net "ADCAV33")
			(options
				(clearance outline)
				(anchor circle)
			)
			(primitives
				(gr_poly
					(pts
						(arc
							(start -0.3302 0.4318)
							(mid -0.402042 0.402042)
							(end -0.4318 0.3302)
						)
						(arc
							(start -0.4318 -0.3302)
							(mid -0.402042 -0.402042)
							(end -0.3302 -0.4318)
						)
						(arc
							(start 0.3302 -0.4318)
							(mid 0.402042 -0.402042)
							(end 0.4318 -0.3302)
						)
						(arc
							(start 0.4318 0.3302)
							(mid 0.402042 0.402042)
							(end 0.3302 0.4318)
						)
					)
					(width 0)
					(fill yes)
				)
			)
		)
		(pad "2" smd custom
			(at 0 0.762 270)
			(size 0.2159 0.2159)
			(layers "B.Cu" "B.Mask" "B.Paste")
			(net "GND")
			(options
				(clearance outline)
				(anchor circle)
			)
			(primitives
				(gr_poly
					(pts
						(arc
							(start -0.3302 0.4318)
							(mid -0.402042 0.402042)
							(end -0.4318 0.3302)
						)
						(arc
							(start -0.4318 -0.3302)
							(mid -0.402042 -0.402042)
							(end -0.3302 -0.4318)
						)
						(arc
							(start 0.3302 -0.4318)
							(mid 0.402042 -0.402042)
							(end 0.4318 -0.3302)
						)
						(arc
							(start 0.4318 0.3302)
							(mid 0.402042 0.402042)
							(end 0.3302 0.4318)
						)
					)
					(width 0)
					(fill yes)
				)
			)
		)
	)
	(footprint ""
		(layer "B.Cu")
		(at 181.3814 -60.6552)
		(property "Reference" "TP163"
			(at 0 0 0)
			(layer "B.SilkS")
			(hide yes)
			(effects
				(font
					(size 1.27 1.27)
				)
				(justify mirror)
			)
		)
		(property "Value" "TPAD28-2-GP"
			(at 0.0127 -1.6637 0)
			(unlocked yes)
			(layer "B.Fab")
			(hide yes)
			(effects
				(font
					(size 1.016 1.016)
					(thickness 0.1524)
				)
				(justify mirror)
			)
		)
		(property "Device Type" "TPAD28"
			(at 0.0127 -3.1877 0)
			(unlocked yes)
			(layer "B.Fab")
			(hide yes)
			(effects
				(font
					(size 1.016 1.016)
					(thickness 0.1524)
				)
				(justify mirror)
			)
		)
		(duplicate_pad_numbers_are_jumpers no)
		(fp_poly
			(pts
				(arc
					(start 0.3556 0)
					(mid -0.3556 0)
					(end 0.3556 0)
				)
			)
			(stroke
				(width 0)
				(type default)
			)
			(fill no)
			(layer "B.CrtYd")
		)
		(fp_poly
			(pts
				(arc
					(start 0.6096 0)
					(mid -0.6096 0)
					(end 0.6096 0)
				)
			)
			(stroke
				(width 0)
				(type default)
			)
			(fill no)
			(layer "B.Fab")
		)
		(pad "1" smd circle
			(at 0 0 180)
			(size 0.7112 0.7112)
			(layers "B.Cu" "B.Mask" "B.Paste")
			(net "XM_ADDR_24")
		)
	)
	(footprint ""
		(layer "B.Cu")
		(at 83.213448 -59.830716 180)
		(property "Reference" "C512"
			(at 0 0 0)
			(layer "B.SilkS")
			(hide yes)
			(effects
				(font
					(size 1.27 1.27)
				)
				(justify mirror)
			)
		)
		(property "Value" "SC10U16V5KX-7-GP-U"
			(at 0.0762 -6.1214 180)
			(unlocked yes)
			(layer "B.Fab")
			(hide yes)
			(effects
				(font
					(size 1.016 1.016)
					(thickness 0.1524)
				)
				(justify mirror)
			)
		)
		(property "Device Type" "C805H58"
			(at 0.0762 -8.1534 180)
			(unlocked yes)
			(layer "B.Fab")
			(hide yes)
			(effects
				(font
					(size 1.016 1.016)
					(thickness 0.1524)
				)
				(justify mirror)
			)
		)
		(duplicate_pad_numbers_are_jumpers no)
		(fp_line
			(start -0.635 0)
			(end 0.635 0)
			(stroke
				(width 0.508)
				(type default)
			)
			(layer "B.SilkS")
		)
		(fp_rect
			(start 0.9652 1.778)
			(end -0.9652 -1.778)
			(stroke
				(width 0)
				(type default)
			)
			(fill no)
			(layer "B.CrtYd")
		)
		(fp_poly
			(pts
				(xy 0.9652 -1.778) (xy -0.9652 -1.778) (xy -0.9652 1.778) (xy 0.9652 1.778)
			)
			(stroke
				(width 0)
				(type default)
			)
			(fill no)
			(layer "B.Fab")
		)
		(pad "1" smd rect
			(at 0 -0.9652)
			(size 1.397 1.143)
			(layers "B.Cu" "B.Mask" "B.Paste")
			(net "P3V3_STBY")
		)
		(pad "2" smd rect
			(at 0 0.9652)
			(size 1.397 1.143)
			(layers "B.Cu" "B.Mask" "B.Paste")
			(net "GND")
		)
	)
	(footprint ""
		(layer "B.Cu")
		(at 199.826626 -55.390796 90)
		(property "Reference" "C436"
			(at 0 0 90)
			(layer "B.SilkS")
			(hide yes)
			(effects
				(font
					(size 1.27 1.27)
				)
				(justify mirror)
			)
		)
		(property "Value" "SCD1U16V2KX-3GP"
			(at -1.1811 -2.7051 90)
			(unlocked yes)
			(layer "B.Fab")
			(hide yes)
			(effects
				(font
					(size 1.016 1.016)
					(thickness 0.1524)
				)
				(justify mirror)
			)
		)
		(property "Device Type" "C402H22"
			(at -1.1811 -4.2291 90)
			(unlocked yes)
			(layer "B.Fab")
			(hide yes)
			(effects
				(font
					(size 1.016 1.016)
					(thickness 0.1524)
				)
				(justify mirror)
			)
		)
		(duplicate_pad_numbers_are_jumpers no)
		(fp_rect
			(start 0.4318 0.9525)
			(end -0.4318 -0.9525)
			(stroke
				(width 0)
				(type default)
			)
			(fill no)
			(layer "B.CrtYd")
		)
		(fp_rect
			(start 0.4318 0.9525)
			(end -0.4318 -0.9525)
			(stroke
				(width 0)
				(type default)
			)
			(fill no)
			(layer "B.Fab")
		)
		(pad "1" smd custom
			(at 0 -0.4445 270)
			(size 0.1524 0.1524)
			(layers "B.Cu" "B.Mask" "B.Paste")
			(net "P1V8")
			(options
				(clearance outline)
				(anchor circle)
			)
			(primitives
				(gr_poly
					(pts
						(arc
							(start 0.3048 0.2032)
							(mid 0.275042 0.275042)
							(end 0.2032 0.3048)
						)
						(arc
							(start -0.2032 0.3048)
							(mid -0.275042 0.275042)
							(end -0.3048 0.2032)
						)
						(arc
							(start -0.3048 -0.2032)
							(mid -0.275042 -0.275042)
							(end -0.2032 -0.3048)
						)
						(arc
							(start 0.2032 -0.3048)
							(mid 0.275042 -0.275042)
							(end 0.3048 -0.2032)
						)
					)
					(width 0)
					(fill yes)
				)
			)
		)
		(pad "2" smd custom
			(at 0 0.4445 270)
			(size 0.1524 0.1524)
			(layers "B.Cu" "B.Mask" "B.Paste")
			(net "GND")
			(options
				(clearance outline)
				(anchor circle)
			)
			(primitives
				(gr_poly
					(pts
						(arc
							(start 0.3048 0.2032)
							(mid 0.275042 0.275042)
							(end 0.2032 0.3048)
						)
						(arc
							(start -0.2032 0.3048)
							(mid -0.275042 0.275042)
							(end -0.3048 0.2032)
						)
						(arc
							(start -0.3048 -0.2032)
							(mid -0.275042 -0.275042)
							(end -0.2032 -0.3048)
						)
						(arc
							(start 0.2032 -0.3048)
							(mid 0.275042 -0.275042)
							(end 0.3048 -0.2032)
						)
					)
					(width 0)
					(fill yes)
				)
			)
		)
	)
	(footprint ""
		(layer "B.Cu")
		(at 10.211562 -139.575032 90)
		(property "Reference" "R233"
			(at 0 0 90)
			(layer "B.SilkS")
			(hide yes)
			(effects
				(font
					(size 1.27 1.27)
				)
				(justify mirror)
			)
		)
		(property "Value" "120R2F-GP"
			(at -0.064008 -3.993896 90)
			(unlocked yes)
			(layer "B.Fab")
			(hide yes)
			(effects
				(font
					(size 1.016 1.016)
					(thickness 0.1524)
				)
				(justify mirror)
			)
		)
		(property "Device Type" "R402H16"
			(at -0.064008 -5.517896 90)
			(unlocked yes)
			(layer "B.Fab")
			(hide yes)
			(effects
				(font
					(size 1.016 1.016)
					(thickness 0.1524)
				)
				(justify mirror)
			)
		)
		(duplicate_pad_numbers_are_jumpers no)
		(fp_line
			(start 0.508 -0.9398)
			(end 0.508 0.9398)
			(stroke
				(width 0.1524)
				(type default)
			)
			(layer "B.SilkS")
		)
		(fp_line
			(start -0.508 -0.9398)
			(end 0.508 -0.9398)
			(stroke
				(width 0.1524)
				(type default)
			)
			(layer "B.SilkS")
		)
		(fp_rect
			(start 0.508 0.9398)
			(end -0.508 -0.9398)
			(stroke
				(width 0)
				(type default)
			)
			(fill no)
			(layer "B.CrtYd")
		)
		(fp_rect
			(start 0.508 0.9398)
			(end -0.508 -0.9398)
			(stroke
				(width 0)
				(type default)
			)
			(fill no)
			(layer "B.Fab")
		)
		(pad "1" smd custom
			(at 0 -0.4445 270)
			(size 0.1397 0.1397)
			(layers "B.Cu" "B.Mask" "B.Paste")
			(net "GND")
			(options
				(clearance outline)
				(anchor circle)
			)
			(primitives
				(gr_poly
					(pts
						(arc
							(start -0.1778 0.2794)
							(mid -0.249642 0.249642)
							(end -0.2794 0.1778)
						)
						(arc
							(start -0.2794 -0.1778)
							(mid -0.249642 -0.249642)
							(end -0.1778 -0.2794)
						)
						(arc
							(start 0.1778 -0.2794)
							(mid 0.249642 -0.249642)
							(end 0.2794 -0.1778)
						)
						(arc
							(start 0.2794 0.1778)
							(mid 0.249642 0.249642)
							(end 0.1778 0.2794)
						)
					)
					(width 0)
					(fill yes)
				)
			)
		)
		(pad "2" smd custom
			(at 0 0.4445 270)
			(size 0.1397 0.1397)
			(layers "B.Cu" "B.Mask" "B.Paste")
			(net "MEMA_0")
			(options
				(clearance outline)
				(anchor circle)
			)
			(primitives
				(gr_poly
					(pts
						(arc
							(start -0.1778 0.2794)
							(mid -0.249642 0.249642)
							(end -0.2794 0.1778)
						)
						(arc
							(start -0.2794 -0.1778)
							(mid -0.249642 -0.249642)
							(end -0.1778 -0.2794)
						)
						(arc
							(start 0.1778 -0.2794)
							(mid 0.249642 -0.249642)
							(end 0.2794 -0.1778)
						)
						(arc
							(start 0.2794 0.1778)
							(mid 0.249642 0.249642)
							(end 0.1778 0.2794)
						)
					)
					(width 0)
					(fill yes)
				)
			)
		)
	)
	(footprint ""
		(layer "B.Cu")
		(at 197.819518 -81.153 180)
		(property "Reference" "C295"
			(at 0 0 0)
			(layer "B.SilkS")
			(hide yes)
			(effects
				(font
					(size 1.27 1.27)
				)
				(justify mirror)
			)
		)
		(property "Value" "SCD22U10V1KX-GP"
			(at 2.8321 -1.7399 180)
			(unlocked yes)
			(layer "B.Fab")
			(hide yes)
			(effects
				(font
					(size 1.016 1.016)
					(thickness 0.1524)
				)
				(justify mirror)
			)
		)
		(property "Device Type" "C0201H13"
			(at 2.8321 -3.2639 180)
			(unlocked yes)
			(layer "B.Fab")
			(hide yes)
			(effects
				(font
					(size 1.016 1.016)
					(thickness 0.1524)
				)
				(justify mirror)
			)
		)
		(duplicate_pad_numbers_are_jumpers no)
		(fp_rect
			(start 0.2794 0.6477)
			(end -0.2794 -0.6477)
			(stroke
				(width 0)
				(type default)
			)
			(fill no)
			(layer "B.CrtYd")
		)
		(fp_rect
			(start 0.2794 0.6477)
			(end -0.2794 -0.6477)
			(stroke
				(width 0)
				(type default)
			)
			(fill no)
			(layer "B.Fab")
		)
		(pad "1" smd custom
			(at 0 -0.2794)
			(size 0.0762 0.0762)
			(layers "B.Cu" "B.Mask" "B.Paste")
			(net "PCIE_IOM_TO_COMP_11_DP_C")
			(options
				(clearance outline)
				(anchor circle)
			)
			(primitives
				(gr_poly
					(pts
						(arc
							(start 0.1524 0.127)
							(mid 0.137521 0.162921)
							(end 0.1016 0.1778)
						)
						(arc
							(start -0.1016 0.1778)
							(mid -0.137521 0.162921)
							(end -0.1524 0.127)
						)
						(arc
							(start -0.1524 -0.127)
							(mid -0.137521 -0.162921)
							(end -0.1016 -0.1778)
						)
						(arc
							(start 0.1016 -0.1778)
							(mid 0.137521 -0.162921)
							(end 0.1524 -0.127)
						)
					)
					(width 0)
					(fill yes)
				)
			)
		)
		(pad "2" smd custom
			(at 0 0.2794)
			(size 0.0762 0.0762)
			(layers "B.Cu" "B.Mask" "B.Paste")
			(net "PCIE_IOM_TO_COMP_11_DP")
			(options
				(clearance outline)
				(anchor circle)
			)
			(primitives
				(gr_poly
					(pts
						(arc
							(start 0.1524 0.127)
							(mid 0.137521 0.162921)
							(end 0.1016 0.1778)
						)
						(arc
							(start -0.1016 0.1778)
							(mid -0.137521 0.162921)
							(end -0.1524 0.127)
						)
						(arc
							(start -0.1524 -0.127)
							(mid -0.137521 -0.162921)
							(end -0.1016 -0.1778)
						)
						(arc
							(start 0.1016 -0.1778)
							(mid 0.137521 -0.162921)
							(end 0.1524 -0.127)
						)
					)
					(width 0)
					(fill yes)
				)
			)
		)
	)
	(footprint ""
		(layer "B.Cu")
		(at 182.52186 -81.49844)
		(property "Reference" "C394"
			(at 0 0 0)
			(layer "B.SilkS")
			(hide yes)
			(effects
				(font
					(size 1.27 1.27)
				)
				(justify mirror)
			)
		)
		(property "Value" "SC1U16V2KX-7-GP"
			(at -1.7526 -1.6002 0)
			(unlocked yes)
			(layer "B.Fab")
			(hide yes)
			(effects
				(font
					(size 1.016 1.016)
					(thickness 0.1524)
				)
				(justify mirror)
			)
		)
		(property "Device Type" "C402-TO0D2H24"
			(at -1.7526 -3.1242 0)
			(unlocked yes)
			(layer "B.Fab")
			(hide yes)
			(effects
				(font
					(size 1.016 1.016)
					(thickness 0.1524)
				)
				(justify mirror)
			)
		)
		(duplicate_pad_numbers_are_jumpers no)
		(fp_rect
			(start 0.4826 0.889)
			(end -0.4826 -0.889)
			(stroke
				(width 0)
				(type default)
			)
			(fill no)
			(layer "B.CrtYd")
		)
		(fp_rect
			(start 0.4826 0.889)
			(end -0.4826 -0.889)
			(stroke
				(width 0)
				(type default)
			)
			(fill no)
			(layer "B.Fab")
		)
		(pad "1" smd custom
			(at 0 -0.4572 180)
			(size 0.1524 0.1524)
			(layers "B.Cu" "B.Mask" "B.Paste")
			(net "P0V975")
			(options
				(clearance outline)
				(anchor circle)
			)
			(primitives
				(gr_poly
					(pts
						(arc
							(start -0.254 -0.3048)
							(mid -0.325842 -0.275042)
							(end -0.3556 -0.2032)
						)
						(arc
							(start -0.3556 0.2032)
							(mid -0.325842 0.275042)
							(end -0.254 0.3048)
						)
						(arc
							(start 0.254 0.3048)
							(mid 0.325842 0.275042)
							(end 0.3556 0.2032)
						)
						(arc
							(start 0.3556 -0.2032)
							(mid 0.325842 -0.275042)
							(end 0.254 -0.3048)
						)
					)
					(width 0)
					(fill yes)
				)
			)
		)
		(pad "2" smd custom
			(at 0 0.4572 180)
			(size 0.1524 0.1524)
			(layers "B.Cu" "B.Mask" "B.Paste")
			(net "GND")
			(options
				(clearance outline)
				(anchor circle)
			)
			(primitives
				(gr_poly
					(pts
						(arc
							(start -0.254 -0.3048)
							(mid -0.325842 -0.275042)
							(end -0.3556 -0.2032)
						)
						(arc
							(start -0.3556 0.2032)
							(mid -0.325842 0.275042)
							(end -0.254 0.3048)
						)
						(arc
							(start 0.254 0.3048)
							(mid 0.325842 0.275042)
							(end 0.3556 0.2032)
						)
						(arc
							(start 0.3556 -0.2032)
							(mid 0.325842 -0.275042)
							(end 0.254 -0.3048)
						)
					)
					(width 0)
					(fill yes)
				)
			)
		)
	)
	(footprint ""
		(layer "B.Cu")
		(at 48.734726 -128.216406 180)
		(property "Reference" "R286"
			(at 0 0 0)
			(layer "B.SilkS")
			(hide yes)
			(effects
				(font
					(size 1.27 1.27)
				)
				(justify mirror)
			)
		)
		(property "Value" "0R2J-2-GP"
			(at -0.064008 -3.993896 180)
			(unlocked yes)
			(layer "B.Fab")
			(hide yes)
			(effects
				(font
					(size 1.016 1.016)
					(thickness 0.1524)
				)
				(justify mirror)
			)
		)
		(property "Device Type" "R402H16"
			(at -0.064008 -5.517896 180)
			(unlocked yes)
			(layer "B.Fab")
			(hide yes)
			(effects
				(font
					(size 1.016 1.016)
					(thickness 0.1524)
				)
				(justify mirror)
			)
		)
		(duplicate_pad_numbers_are_jumpers no)
		(fp_line
			(start 0.508 -0.9398)
			(end 0.508 0.9398)
			(stroke
				(width 0.1524)
				(type default)
			)
			(layer "B.SilkS")
		)
		(fp_line
			(start -0.508 -0.9398)
			(end 0.508 -0.9398)
			(stroke
				(width 0.1524)
				(type default)
			)
			(layer "B.SilkS")
		)
		(fp_rect
			(start 0.508 0.9398)
			(end -0.508 -0.9398)
			(stroke
				(width 0)
				(type default)
			)
			(fill no)
			(layer "B.CrtYd")
		)
		(fp_rect
			(start 0.508 0.9398)
			(end -0.508 -0.9398)
			(stroke
				(width 0)
				(type default)
			)
			(fill no)
			(layer "B.Fab")
		)
		(pad "1" smd custom
			(at 0 -0.4445)
			(size 0.1397 0.1397)
			(layers "B.Cu" "B.Mask" "B.Paste")
			(net "SCC_LOC_FULL_PWR_EN")
			(options
				(clearance outline)
				(anchor circle)
			)
			(primitives
				(gr_poly
					(pts
						(arc
							(start -0.1778 0.2794)
							(mid -0.249642 0.249642)
							(end -0.2794 0.1778)
						)
						(arc
							(start -0.2794 -0.1778)
							(mid -0.249642 -0.249642)
							(end -0.1778 -0.2794)
						)
						(arc
							(start 0.1778 -0.2794)
							(mid 0.249642 -0.249642)
							(end 0.2794 -0.1778)
						)
						(arc
							(start 0.2794 0.1778)
							(mid 0.249642 0.249642)
							(end 0.1778 0.2794)
						)
					)
					(width 0)
					(fill yes)
				)
			)
		)
		(pad "2" smd custom
			(at 0 0.4445)
			(size 0.1397 0.1397)
			(layers "B.Cu" "B.Mask" "B.Paste")
			(net "SCC_LOC_FULLPWR_EN")
			(options
				(clearance outline)
				(anchor circle)
			)
			(primitives
				(gr_poly
					(pts
						(arc
							(start -0.1778 0.2794)
							(mid -0.249642 0.249642)
							(end -0.2794 0.1778)
						)
						(arc
							(start -0.2794 -0.1778)
							(mid -0.249642 -0.249642)
							(end -0.1778 -0.2794)
						)
						(arc
							(start 0.1778 -0.2794)
							(mid 0.249642 -0.249642)
							(end 0.2794 -0.1778)
						)
						(arc
							(start 0.2794 0.1778)
							(mid 0.249642 0.249642)
							(end 0.1778 0.2794)
						)
					)
					(width 0)
					(fill yes)
				)
			)
		)
	)
	(footprint ""
		(layer "B.Cu")
		(at 40.4876 -126.5682)
		(property "Reference" "TP84"
			(at 0 0 0)
			(layer "B.SilkS")
			(hide yes)
			(effects
				(font
					(size 1.27 1.27)
				)
				(justify mirror)
			)
		)
		(property "Value" "TPAD28-2-GP"
			(at 0.0127 -1.6637 0)
			(unlocked yes)
			(layer "B.Fab")
			(hide yes)
			(effects
				(font
					(size 1.016 1.016)
					(thickness 0.1524)
				)
				(justify mirror)
			)
		)
		(property "Device Type" "TPAD28"
			(at 0.0127 -3.1877 0)
			(unlocked yes)
			(layer "B.Fab")
			(hide yes)
			(effects
				(font
					(size 1.016 1.016)
					(thickness 0.1524)
				)
				(justify mirror)
			)
		)
		(duplicate_pad_numbers_are_jumpers no)
		(fp_poly
			(pts
				(arc
					(start 0.3556 0)
					(mid -0.3556 0)
					(end 0.3556 0)
				)
			)
			(stroke
				(width 0)
				(type default)
			)
			(fill no)
			(layer "B.CrtYd")
		)
		(fp_poly
			(pts
				(arc
					(start 0.6096 0)
					(mid -0.6096 0)
					(end 0.6096 0)
				)
			)
			(stroke
				(width 0)
				(type default)
			)
			(fill no)
			(layer "B.Fab")
		)
		(pad "1" smd circle
			(at 0 0 180)
			(size 0.7112 0.7112)
			(layers "B.Cu" "B.Mask" "B.Paste")
			(net "FM_BMC_RESET_N")
		)
	)
	(footprint ""
		(layer "B.Cu")
		(at 181.487826 -69.878956)
		(property "Reference" "TP127"
			(at 0 0 0)
			(layer "B.SilkS")
			(hide yes)
			(effects
				(font
					(size 1.27 1.27)
				)
				(justify mirror)
			)
		)
		(property "Value" "TPAD28-2-GP"
			(at 0.0127 -1.6637 0)
			(unlocked yes)
			(layer "B.Fab")
			(hide yes)
			(effects
				(font
					(size 1.016 1.016)
					(thickness 0.1524)
				)
				(justify mirror)
			)
		)
		(property "Device Type" "TPAD28"
			(at 0.0127 -3.1877 0)
			(unlocked yes)
			(layer "B.Fab")
			(hide yes)
			(effects
				(font
					(size 1.016 1.016)
					(thickness 0.1524)
				)
				(justify mirror)
			)
		)
		(duplicate_pad_numbers_are_jumpers no)
		(fp_poly
			(pts
				(arc
					(start 0.3556 0)
					(mid -0.3556 0)
					(end 0.3556 0)
				)
			)
			(stroke
				(width 0)
				(type default)
			)
			(fill no)
			(layer "B.CrtYd")
		)
		(fp_poly
			(pts
				(arc
					(start 0.6096 0)
					(mid -0.6096 0)
					(end 0.6096 0)
				)
			)
			(stroke
				(width 0)
				(type default)
			)
			(fill no)
			(layer "B.Fab")
		)
		(pad "1" smd circle
			(at 0 0 180)
			(size 0.7112 0.7112)
			(layers "B.Cu" "B.Mask" "B.Paste")
			(net "IOC_GPIO_34")
		)
	)
	(footprint ""
		(layer "B.Cu")
		(at 197.20814 -61.4553 90)
		(property "Reference" "C385"
			(at 0 0 90)
			(layer "B.SilkS")
			(hide yes)
			(effects
				(font
					(size 1.27 1.27)
				)
				(justify mirror)
			)
		)
		(property "Value" "SC10U6D3V5KX-4GP"
			(at 0.0762 -6.1214 90)
			(unlocked yes)
			(layer "B.Fab")
			(hide yes)
			(effects
				(font
					(size 1.016 1.016)
					(thickness 0.1524)
				)
				(justify mirror)
			)
		)
		(property "Device Type" "C805H58"
			(at 0.0762 -8.1534 90)
			(unlocked yes)
			(layer "B.Fab")
			(hide yes)
			(effects
				(font
					(size 1.016 1.016)
					(thickness 0.1524)
				)
				(justify mirror)
			)
		)
		(duplicate_pad_numbers_are_jumpers no)
		(fp_line
			(start -0.635 0)
			(end 0.635 0)
			(stroke
				(width 0.508)
				(type default)
			)
			(layer "B.SilkS")
		)
		(fp_rect
			(start 0.9652 1.778)
			(end -0.9652 -1.778)
			(stroke
				(width 0)
				(type default)
			)
			(fill no)
			(layer "B.CrtYd")
		)
		(fp_poly
			(pts
				(xy 0.9652 -1.778) (xy -0.9652 -1.778) (xy -0.9652 1.778) (xy 0.9652 1.778)
			)
			(stroke
				(width 0)
				(type default)
			)
			(fill no)
			(layer "B.Fab")
		)
		(pad "1" smd rect
			(at 0 -0.9652 270)
			(size 1.397 1.143)
			(layers "B.Cu" "B.Mask" "B.Paste")
			(net "P0V975")
		)
		(pad "2" smd rect
			(at 0 0.9652 270)
			(size 1.397 1.143)
			(layers "B.Cu" "B.Mask" "B.Paste")
			(net "GND")
		)
	)
	(footprint ""
		(layer "B.Cu")
		(at 180.2384 -76.0476)
		(property "Reference" "TP88"
			(at 0 0 0)
			(layer "B.SilkS")
			(hide yes)
			(effects
				(font
					(size 1.27 1.27)
				)
				(justify mirror)
			)
		)
		(property "Value" "TPAD28-2-GP"
			(at 0.0127 -1.6637 0)
			(unlocked yes)
			(layer "B.Fab")
			(hide yes)
			(effects
				(font
					(size 1.016 1.016)
					(thickness 0.1524)
				)
				(justify mirror)
			)
		)
		(property "Device Type" "TPAD28"
			(at 0.0127 -3.1877 0)
			(unlocked yes)
			(layer "B.Fab")
			(hide yes)
			(effects
				(font
					(size 1.016 1.016)
					(thickness 0.1524)
				)
				(justify mirror)
			)
		)
		(duplicate_pad_numbers_are_jumpers no)
		(fp_poly
			(pts
				(arc
					(start 0.3556 0)
					(mid -0.3556 0)
					(end 0.3556 0)
				)
			)
			(stroke
				(width 0)
				(type default)
			)
			(fill no)
			(layer "B.CrtYd")
		)
		(fp_poly
			(pts
				(arc
					(start 0.6096 0)
					(mid -0.6096 0)
					(end 0.6096 0)
				)
			)
			(stroke
				(width 0)
				(type default)
			)
			(fill no)
			(layer "B.Fab")
		)
		(pad "1" smd circle
			(at 0 0 180)
			(size 0.7112 0.7112)
			(layers "B.Cu" "B.Mask" "B.Paste")
			(net "IOC_GPIO_0")
		)
	)
	(footprint ""
		(layer "B.Cu")
		(at 203.327 -78.613 90)
		(property "Reference" "C376"
			(at 0 0 90)
			(layer "B.SilkS")
			(hide yes)
			(effects
				(font
					(size 1.27 1.27)
				)
				(justify mirror)
			)
		)
		(property "Value" "SCD1U6D3V1KX-GP"
			(at 2.8321 -1.7399 90)
			(unlocked yes)
			(layer "B.Fab")
			(hide yes)
			(effects
				(font
					(size 1.016 1.016)
					(thickness 0.1524)
				)
				(justify mirror)
			)
		)
		(property "Device Type" "C0201H13"
			(at 2.8321 -3.2639 90)
			(unlocked yes)
			(layer "B.Fab")
			(hide yes)
			(effects
				(font
					(size 1.016 1.016)
					(thickness 0.1524)
				)
				(justify mirror)
			)
		)
		(duplicate_pad_numbers_are_jumpers no)
		(fp_rect
			(start 0.2794 0.6477)
			(end -0.2794 -0.6477)
			(stroke
				(width 0)
				(type default)
			)
			(fill no)
			(layer "B.CrtYd")
		)
		(fp_rect
			(start 0.2794 0.6477)
			(end -0.2794 -0.6477)
			(stroke
				(width 0)
				(type default)
			)
			(fill no)
			(layer "B.Fab")
		)
		(pad "1" smd custom
			(at 0 -0.2794 270)
			(size 0.0762 0.0762)
			(layers "B.Cu" "B.Mask" "B.Paste")
			(net "SAS0_AVDD")
			(options
				(clearance outline)
				(anchor circle)
			)
			(primitives
				(gr_poly
					(pts
						(arc
							(start 0.1524 0.127)
							(mid 0.137521 0.162921)
							(end 0.1016 0.1778)
						)
						(arc
							(start -0.1016 0.1778)
							(mid -0.137521 0.162921)
							(end -0.1524 0.127)
						)
						(arc
							(start -0.1524 -0.127)
							(mid -0.137521 -0.162921)
							(end -0.1016 -0.1778)
						)
						(arc
							(start 0.1016 -0.1778)
							(mid 0.137521 -0.162921)
							(end 0.1524 -0.127)
						)
					)
					(width 0)
					(fill yes)
				)
			)
		)
		(pad "2" smd custom
			(at 0 0.2794 270)
			(size 0.0762 0.0762)
			(layers "B.Cu" "B.Mask" "B.Paste")
			(net "GND")
			(options
				(clearance outline)
				(anchor circle)
			)
			(primitives
				(gr_poly
					(pts
						(arc
							(start 0.1524 0.127)
							(mid 0.137521 0.162921)
							(end 0.1016 0.1778)
						)
						(arc
							(start -0.1016 0.1778)
							(mid -0.137521 0.162921)
							(end -0.1524 0.127)
						)
						(arc
							(start -0.1524 -0.127)
							(mid -0.137521 -0.162921)
							(end -0.1016 -0.1778)
						)
						(arc
							(start 0.1016 -0.1778)
							(mid 0.137521 -0.162921)
							(end 0.1524 -0.127)
						)
					)
					(width 0)
					(fill yes)
				)
			)
		)
	)
	(footprint ""
		(layer "B.Cu")
		(at 60.22594 -152.94864 -90)
		(property "Reference" "R399"
			(at 0 0 90)
			(layer "B.SilkS")
			(hide yes)
			(effects
				(font
					(size 1.27 1.27)
				)
				(justify mirror)
			)
		)
		(property "Value" "4K7R2F-GP"
			(at -0.064008 -3.993896 270)
			(unlocked yes)
			(layer "B.Fab")
			(hide yes)
			(effects
				(font
					(size 1.016 1.016)
					(thickness 0.1524)
				)
				(justify mirror)
			)
		)
		(property "Device Type" "R402H16"
			(at -0.064008 -5.517896 270)
			(unlocked yes)
			(layer "B.Fab")
			(hide yes)
			(effects
				(font
					(size 1.016 1.016)
					(thickness 0.1524)
				)
				(justify mirror)
			)
		)
		(duplicate_pad_numbers_are_jumpers no)
		(fp_line
			(start -0.508 -0.9398)
			(end 0.508 -0.9398)
			(stroke
				(width 0.1524)
				(type default)
			)
			(layer "B.SilkS")
		)
		(fp_line
			(start 0.508 -0.9398)
			(end 0.508 0.9398)
			(stroke
				(width 0.1524)
				(type default)
			)
			(layer "B.SilkS")
		)
		(fp_rect
			(start 0.508 0.9398)
			(end -0.508 -0.9398)
			(stroke
				(width 0)
				(type default)
			)
			(fill no)
			(layer "B.CrtYd")
		)
		(fp_rect
			(start 0.508 0.9398)
			(end -0.508 -0.9398)
			(stroke
				(width 0)
				(type default)
			)
			(fill no)
			(layer "B.Fab")
		)
		(pad "1" smd custom
			(at 0 -0.4445 90)
			(size 0.1397 0.1397)
			(layers "B.Cu" "B.Mask" "B.Paste")
			(net "GND")
			(options
				(clearance outline)
				(anchor circle)
			)
			(primitives
				(gr_poly
					(pts
						(arc
							(start -0.1778 0.2794)
							(mid -0.249642 0.249642)
							(end -0.2794 0.1778)
						)
						(arc
							(start -0.2794 -0.1778)
							(mid -0.249642 -0.249642)
							(end -0.1778 -0.2794)
						)
						(arc
							(start 0.1778 -0.2794)
							(mid 0.249642 -0.249642)
							(end 0.2794 -0.1778)
						)
						(arc
							(start 0.2794 0.1778)
							(mid 0.249642 0.249642)
							(end 0.1778 0.2794)
						)
					)
					(width 0)
					(fill yes)
				)
			)
		)
		(pad "2" smd custom
			(at 0 0.4445 90)
			(size 0.1397 0.1397)
			(layers "B.Cu" "B.Mask" "B.Paste")
			(net "MAC2_TXD3")
			(options
				(clearance outline)
				(anchor circle)
			)
			(primitives
				(gr_poly
					(pts
						(arc
							(start -0.1778 0.2794)
							(mid -0.249642 0.249642)
							(end -0.2794 0.1778)
						)
						(arc
							(start -0.2794 -0.1778)
							(mid -0.249642 -0.249642)
							(end -0.1778 -0.2794)
						)
						(arc
							(start 0.1778 -0.2794)
							(mid 0.249642 -0.249642)
							(end 0.2794 -0.1778)
						)
						(arc
							(start 0.2794 0.1778)
							(mid 0.249642 0.249642)
							(end 0.1778 0.2794)
						)
					)
					(width 0)
					(fill yes)
				)
			)
		)
	)
	(footprint ""
		(layer "B.Cu")
		(at 201.860404 -92.851224 180)
		(property "Reference" "C356"
			(at 0 0 0)
			(layer "B.SilkS")
			(hide yes)
			(effects
				(font
					(size 1.27 1.27)
				)
				(justify mirror)
			)
		)
		(property "Value" "SC22U6D3V3MX-9-GP-U"
			(at 0 -2.8194 180)
			(unlocked yes)
			(layer "B.Fab")
			(hide yes)
			(effects
				(font
					(size 1.016 1.016)
					(thickness 0.1524)
				)
				(justify mirror)
			)
		)
		(property "Device Type" "C603H40"
			(at 0 -4.3434 180)
			(unlocked yes)
			(layer "B.Fab")
			(hide yes)
			(effects
				(font
					(size 1.016 1.016)
					(thickness 0.1524)
				)
				(justify mirror)
			)
		)
		(duplicate_pad_numbers_are_jumpers no)
		(fp_line
			(start -0.508 0)
			(end 0.508 0)
			(stroke
				(width 0.2032)
				(type default)
			)
			(layer "B.SilkS")
		)
		(fp_rect
			(start 0.5842 1.3335)
			(end -0.5842 -1.3335)
			(stroke
				(width 0)
				(type default)
			)
			(fill no)
			(layer "B.CrtYd")
		)
		(fp_rect
			(start 0.5842 1.3335)
			(end -0.5842 -1.3335)
			(stroke
				(width 0)
				(type default)
			)
			(fill no)
			(layer "B.Fab")
		)
		(pad "1" smd custom
			(at 0 -0.762)
			(size 0.2159 0.2159)
			(layers "B.Cu" "B.Mask" "B.Paste")
			(net "PCE_VDDH")
			(options
				(clearance outline)
				(anchor circle)
			)
			(primitives
				(gr_poly
					(pts
						(arc
							(start -0.3302 0.4318)
							(mid -0.402042 0.402042)
							(end -0.4318 0.3302)
						)
						(arc
							(start -0.4318 -0.3302)
							(mid -0.402042 -0.402042)
							(end -0.3302 -0.4318)
						)
						(arc
							(start 0.3302 -0.4318)
							(mid 0.402042 -0.402042)
							(end 0.4318 -0.3302)
						)
						(arc
							(start 0.4318 0.3302)
							(mid 0.402042 0.402042)
							(end 0.3302 0.4318)
						)
					)
					(width 0)
					(fill yes)
				)
			)
		)
		(pad "2" smd custom
			(at 0 0.762)
			(size 0.2159 0.2159)
			(layers "B.Cu" "B.Mask" "B.Paste")
			(net "GND")
			(options
				(clearance outline)
				(anchor circle)
			)
			(primitives
				(gr_poly
					(pts
						(arc
							(start -0.3302 0.4318)
							(mid -0.402042 0.402042)
							(end -0.4318 0.3302)
						)
						(arc
							(start -0.4318 -0.3302)
							(mid -0.402042 -0.402042)
							(end -0.3302 -0.4318)
						)
						(arc
							(start 0.3302 -0.4318)
							(mid 0.402042 -0.402042)
							(end 0.4318 -0.3302)
						)
						(arc
							(start 0.4318 0.3302)
							(mid 0.402042 0.402042)
							(end 0.3302 0.4318)
						)
					)
					(width 0)
					(fill yes)
				)
			)
		)
	)
	(footprint ""
		(layer "B.Cu")
		(at 165.959536 -38.416738)
		(property "Reference" "C499"
			(at 0 0 0)
			(layer "B.SilkS")
			(hide yes)
			(effects
				(font
					(size 1.27 1.27)
				)
				(justify mirror)
			)
		)
		(property "Value" "SCD01U16V1KX-GP"
			(at 2.8321 -1.7399 0)
			(unlocked yes)
			(layer "B.Fab")
			(hide yes)
			(effects
				(font
					(size 1.016 1.016)
					(thickness 0.1524)
				)
				(justify mirror)
			)
		)
		(property "Device Type" "C0201H13"
			(at 2.8321 -3.2639 0)
			(unlocked yes)
			(layer "B.Fab")
			(hide yes)
			(effects
				(font
					(size 1.016 1.016)
					(thickness 0.1524)
				)
				(justify mirror)
			)
		)
		(duplicate_pad_numbers_are_jumpers no)
		(fp_rect
			(start 0.2794 0.6477)
			(end -0.2794 -0.6477)
			(stroke
				(width 0)
				(type default)
			)
			(fill no)
			(layer "B.CrtYd")
		)
		(fp_rect
			(start 0.2794 0.6477)
			(end -0.2794 -0.6477)
			(stroke
				(width 0)
				(type default)
			)
			(fill no)
			(layer "B.Fab")
		)
		(pad "1" smd custom
			(at 0 -0.2794 180)
			(size 0.0762 0.0762)
			(layers "B.Cu" "B.Mask" "B.Paste")
			(net "PHY_CON_B_TO_IOC_3_DN")
			(options
				(clearance outline)
				(anchor circle)
			)
			(primitives
				(gr_poly
					(pts
						(arc
							(start 0.1524 0.127)
							(mid 0.137521 0.162921)
							(end 0.1016 0.1778)
						)
						(arc
							(start -0.1016 0.1778)
							(mid -0.137521 0.162921)
							(end -0.1524 0.127)
						)
						(arc
							(start -0.1524 -0.127)
							(mid -0.137521 -0.162921)
							(end -0.1016 -0.1778)
						)
						(arc
							(start 0.1016 -0.1778)
							(mid 0.137521 -0.162921)
							(end 0.1524 -0.127)
						)
					)
					(width 0)
					(fill yes)
				)
			)
		)
		(pad "2" smd custom
			(at 0 0.2794 180)
			(size 0.0762 0.0762)
			(layers "B.Cu" "B.Mask" "B.Paste")
			(net "PHY_CON_B_TO_IOC_3_DN_C")
			(options
				(clearance outline)
				(anchor circle)
			)
			(primitives
				(gr_poly
					(pts
						(arc
							(start 0.1524 0.127)
							(mid 0.137521 0.162921)
							(end 0.1016 0.1778)
						)
						(arc
							(start -0.1016 0.1778)
							(mid -0.137521 0.162921)
							(end -0.1524 0.127)
						)
						(arc
							(start -0.1524 -0.127)
							(mid -0.137521 -0.162921)
							(end -0.1016 -0.1778)
						)
						(arc
							(start 0.1016 -0.1778)
							(mid 0.137521 -0.162921)
							(end 0.1524 -0.127)
						)
					)
					(width 0)
					(fill yes)
				)
			)
		)
	)
	(footprint ""
		(layer "B.Cu")
		(at 52.705 -126.33452 180)
		(property "Reference" "C505"
			(at 0 0 0)
			(layer "B.SilkS")
			(hide yes)
			(effects
				(font
					(size 1.27 1.27)
				)
				(justify mirror)
			)
		)
		(property "Value" "SCD1U16V2KX-3GP"
			(at -1.1811 -2.7051 180)
			(unlocked yes)
			(layer "B.Fab")
			(hide yes)
			(effects
				(font
					(size 1.016 1.016)
					(thickness 0.1524)
				)
				(justify mirror)
			)
		)
		(property "Device Type" "C402H22"
			(at -1.1811 -4.2291 180)
			(unlocked yes)
			(layer "B.Fab")
			(hide yes)
			(effects
				(font
					(size 1.016 1.016)
					(thickness 0.1524)
				)
				(justify mirror)
			)
		)
		(duplicate_pad_numbers_are_jumpers no)
		(fp_rect
			(start 0.4318 0.9525)
			(end -0.4318 -0.9525)
			(stroke
				(width 0)
				(type default)
			)
			(fill no)
			(layer "B.CrtYd")
		)
		(fp_rect
			(start 0.4318 0.9525)
			(end -0.4318 -0.9525)
			(stroke
				(width 0)
				(type default)
			)
			(fill no)
			(layer "B.Fab")
		)
		(pad "1" smd custom
			(at 0 -0.4445)
			(size 0.1524 0.1524)
			(layers "B.Cu" "B.Mask" "B.Paste")
			(net "P3V3_STBY")
			(options
				(clearance outline)
				(anchor circle)
			)
			(primitives
				(gr_poly
					(pts
						(arc
							(start 0.3048 0.2032)
							(mid 0.275042 0.275042)
							(end 0.2032 0.3048)
						)
						(arc
							(start -0.2032 0.3048)
							(mid -0.275042 0.275042)
							(end -0.3048 0.2032)
						)
						(arc
							(start -0.3048 -0.2032)
							(mid -0.275042 -0.275042)
							(end -0.2032 -0.3048)
						)
						(arc
							(start 0.2032 -0.3048)
							(mid 0.275042 -0.275042)
							(end 0.3048 -0.2032)
						)
					)
					(width 0)
					(fill yes)
				)
			)
		)
		(pad "2" smd custom
			(at 0 0.4445)
			(size 0.1524 0.1524)
			(layers "B.Cu" "B.Mask" "B.Paste")
			(net "GND")
			(options
				(clearance outline)
				(anchor circle)
			)
			(primitives
				(gr_poly
					(pts
						(arc
							(start 0.3048 0.2032)
							(mid 0.275042 0.275042)
							(end 0.2032 0.3048)
						)
						(arc
							(start -0.2032 0.3048)
							(mid -0.275042 0.275042)
							(end -0.3048 0.2032)
						)
						(arc
							(start -0.3048 -0.2032)
							(mid -0.275042 -0.275042)
							(end -0.2032 -0.3048)
						)
						(arc
							(start 0.2032 -0.3048)
							(mid 0.275042 -0.275042)
							(end 0.3048 -0.2032)
						)
					)
					(width 0)
					(fill yes)
				)
			)
		)
	)
	(footprint ""
		(layer "B.Cu")
		(at 28.4734 -126.3142 -90)
		(property "Reference" "C508"
			(at 0 0 90)
			(layer "B.SilkS")
			(hide yes)
			(effects
				(font
					(size 1.27 1.27)
				)
				(justify mirror)
			)
		)
		(property "Value" "SCD1U16V2KX-3GP"
			(at -1.1811 -2.7051 270)
			(unlocked yes)
			(layer "B.Fab")
			(hide yes)
			(effects
				(font
					(size 1.016 1.016)
					(thickness 0.1524)
				)
				(justify mirror)
			)
		)
		(property "Device Type" "C402H22"
			(at -1.1811 -4.2291 270)
			(unlocked yes)
			(layer "B.Fab")
			(hide yes)
			(effects
				(font
					(size 1.016 1.016)
					(thickness 0.1524)
				)
				(justify mirror)
			)
		)
		(duplicate_pad_numbers_are_jumpers no)
		(fp_rect
			(start 0.4318 0.9525)
			(end -0.4318 -0.9525)
			(stroke
				(width 0)
				(type default)
			)
			(fill no)
			(layer "B.CrtYd")
		)
		(fp_rect
			(start 0.4318 0.9525)
			(end -0.4318 -0.9525)
			(stroke
				(width 0)
				(type default)
			)
			(fill no)
			(layer "B.Fab")
		)
		(pad "1" smd custom
			(at 0 -0.4445 90)
			(size 0.1524 0.1524)
			(layers "B.Cu" "B.Mask" "B.Paste")
			(net "P3V3_STBY")
			(options
				(clearance outline)
				(anchor circle)
			)
			(primitives
				(gr_poly
					(pts
						(arc
							(start 0.3048 0.2032)
							(mid 0.275042 0.275042)
							(end 0.2032 0.3048)
						)
						(arc
							(start -0.2032 0.3048)
							(mid -0.275042 0.275042)
							(end -0.3048 0.2032)
						)
						(arc
							(start -0.3048 -0.2032)
							(mid -0.275042 -0.275042)
							(end -0.2032 -0.3048)
						)
						(arc
							(start 0.2032 -0.3048)
							(mid 0.275042 -0.275042)
							(end 0.3048 -0.2032)
						)
					)
					(width 0)
					(fill yes)
				)
			)
		)
		(pad "2" smd custom
			(at 0 0.4445 90)
			(size 0.1524 0.1524)
			(layers "B.Cu" "B.Mask" "B.Paste")
			(net "GND")
			(options
				(clearance outline)
				(anchor circle)
			)
			(primitives
				(gr_poly
					(pts
						(arc
							(start 0.3048 0.2032)
							(mid 0.275042 0.275042)
							(end 0.2032 0.3048)
						)
						(arc
							(start -0.2032 0.3048)
							(mid -0.275042 0.275042)
							(end -0.3048 0.2032)
						)
						(arc
							(start -0.3048 -0.2032)
							(mid -0.275042 -0.275042)
							(end -0.2032 -0.3048)
						)
						(arc
							(start 0.2032 -0.3048)
							(mid 0.275042 -0.275042)
							(end 0.3048 -0.2032)
						)
					)
					(width 0)
					(fill yes)
				)
			)
		)
	)
	(footprint ""
		(layer "B.Cu")
		(at 34.404046 -142.938246 180)
		(property "Reference" "C57"
			(at 0 0 0)
			(layer "B.SilkS")
			(hide yes)
			(effects
				(font
					(size 1.27 1.27)
				)
				(justify mirror)
			)
		)
		(property "Value" "SC10U6D3V5KX-4GP"
			(at 0.0762 -6.1214 180)
			(unlocked yes)
			(layer "B.Fab")
			(hide yes)
			(effects
				(font
					(size 1.016 1.016)
					(thickness 0.1524)
				)
				(justify mirror)
			)
		)
		(property "Device Type" "C805H58"
			(at 0.0762 -8.1534 180)
			(unlocked yes)
			(layer "B.Fab")
			(hide yes)
			(effects
				(font
					(size 1.016 1.016)
					(thickness 0.1524)
				)
				(justify mirror)
			)
		)
		(duplicate_pad_numbers_are_jumpers no)
		(fp_line
			(start -0.635 0)
			(end 0.635 0)
			(stroke
				(width 0.508)
				(type default)
			)
			(layer "B.SilkS")
		)
		(fp_rect
			(start 0.9652 1.778)
			(end -0.9652 -1.778)
			(stroke
				(width 0)
				(type default)
			)
			(fill no)
			(layer "B.CrtYd")
		)
		(fp_poly
			(pts
				(xy 0.9652 -1.778) (xy -0.9652 -1.778) (xy -0.9652 1.778) (xy 0.9652 1.778)
			)
			(stroke
				(width 0)
				(type default)
			)
			(fill no)
			(layer "B.Fab")
		)
		(pad "1" smd rect
			(at 0 -0.9652)
			(size 1.397 1.143)
			(layers "B.Cu" "B.Mask" "B.Paste")
			(net "GND")
		)
		(pad "2" smd rect
			(at 0 0.9652)
			(size 1.397 1.143)
			(layers "B.Cu" "B.Mask" "B.Paste")
			(net "P1V2_STBY")
		)
	)
	(footprint ""
		(layer "B.Cu")
		(at 140.843 -18.415 90)
		(property "Reference" "U51"
			(at 0 0 90)
			(layer "B.SilkS")
			(hide yes)
			(effects
				(font
					(size 1.27 1.27)
				)
				(justify mirror)
			)
		)
		(property "Value" "SN74LVC1G08DCKR-GP"
			(at 2.3368 -8.6868 90)
			(unlocked yes)
			(layer "B.Fab")
			(hide yes)
			(effects
				(font
					(size 1.016 1.016)
					(thickness 0.1524)
				)
				(justify mirror)
			)
		)
		(property "Device Type" "SC70-5H44"
			(at 2.3114 -10.414 90)
			(unlocked yes)
			(layer "B.Fab")
			(hide yes)
			(effects
				(font
					(size 1.016 1.016)
					(thickness 0.1524)
				)
				(justify mirror)
			)
		)
		(duplicate_pad_numbers_are_jumpers no)
		(fp_line
			(start -0.6604 -1.8034)
			(end -1.3843 -1.8034)
			(stroke
				(width 0.3302)
				(type default)
			)
			(layer "B.SilkS")
		)
		(fp_line
			(start -1.3843 -1.8034)
			(end -1.3843 -1.1176)
			(stroke
				(width 0.3302)
				(type default)
			)
			(layer "B.SilkS")
		)
		(fp_line
			(start 1.27 -1.7018)
			(end -1.27 -1.7018)
			(stroke
				(width 0.1524)
				(type default)
			)
			(layer "B.SilkS")
		)
		(fp_line
			(start -1.27 -1.7018)
			(end -1.27 1.7018)
			(stroke
				(width 0.1524)
				(type default)
			)
			(layer "B.SilkS")
		)
		(fp_line
			(start 1.27 1.7018)
			(end 1.27 -1.7018)
			(stroke
				(width 0.1524)
				(type default)
			)
			(layer "B.SilkS")
		)
		(fp_line
			(start -1.27 1.7018)
			(end 1.27 1.7018)
			(stroke
				(width 0.1524)
				(type default)
			)
			(layer "B.SilkS")
		)
		(fp_rect
			(start 1.524 1.9558)
			(end -1.524 -1.9558)
			(stroke
				(width 0)
				(type default)
			)
			(fill no)
			(layer "B.CrtYd")
		)
		(fp_poly
			(pts
				(xy 1.524 -1.9558) (xy -1.524 -1.9558) (xy -1.524 1.9558) (xy 1.524 1.9558)
			)
			(stroke
				(width 0)
				(type default)
			)
			(fill no)
			(layer "B.Fab")
		)
		(pad "1" smd rect
			(at -0.65024 -0.8255 270)
			(size 0.4064 1.2192)
			(layers "B.Cu" "B.Mask" "B.Paste")
			(net "BMC_EXT2_LED_Y")
		)
		(pad "2" smd rect
			(at 0 -0.8255 270)
			(size 0.4064 1.2192)
			(layers "B.Cu" "B.Mask" "B.Paste")
			(net "IOC_EXT2_LED_B")
		)
		(pad "3" smd rect
			(at 0.65024 -0.8255 270)
			(size 0.4064 1.2192)
			(layers "B.Cu" "B.Mask" "B.Paste")
			(net "GND")
		)
		(pad "4" smd rect
			(at 0.65024 0.8255 270)
			(size 0.4064 1.2192)
			(layers "B.Cu" "B.Mask" "B.Paste")
			(net "EXT2_LED_BLUE_G_Q27")
		)
		(pad "5" smd rect
			(at -0.65024 0.8255 270)
			(size 0.4064 1.2192)
			(layers "B.Cu" "B.Mask" "B.Paste")
			(net "P1V8")
		)
	)
	(footprint ""
		(layer "B.Cu")
		(at 90.88628 -178.9684 90)
		(property "Reference" "U15"
			(at 0 0 90)
			(layer "B.SilkS")
			(hide yes)
			(effects
				(font
					(size 1.27 1.27)
				)
				(justify mirror)
			)
		)
		(property "Value" "NX3L1G66GW-GP"
			(at 2.3368 -8.6868 90)
			(unlocked yes)
			(layer "B.Fab")
			(hide yes)
			(effects
				(font
					(size 1.016 1.016)
					(thickness 0.1524)
				)
				(justify mirror)
			)
		)
		(property "Device Type" "SC70-5H44"
			(at 2.3114 -10.414 90)
			(unlocked yes)
			(layer "B.Fab")
			(hide yes)
			(effects
				(font
					(size 1.016 1.016)
					(thickness 0.1524)
				)
				(justify mirror)
			)
		)
		(duplicate_pad_numbers_are_jumpers no)
		(fp_line
			(start -0.6604 -1.8034)
			(end -1.3843 -1.8034)
			(stroke
				(width 0.3302)
				(type default)
			)
			(layer "B.SilkS")
		)
		(fp_line
			(start -1.3843 -1.8034)
			(end -1.3843 -1.1176)
			(stroke
				(width 0.3302)
				(type default)
			)
			(layer "B.SilkS")
		)
		(fp_line
			(start 1.27 -1.7018)
			(end -1.27 -1.7018)
			(stroke
				(width 0.1524)
				(type default)
			)
			(layer "B.SilkS")
		)
		(fp_line
			(start -1.27 -1.7018)
			(end -1.27 1.7018)
			(stroke
				(width 0.1524)
				(type default)
			)
			(layer "B.SilkS")
		)
		(fp_line
			(start 1.27 1.7018)
			(end 1.27 -1.7018)
			(stroke
				(width 0.1524)
				(type default)
			)
			(layer "B.SilkS")
		)
		(fp_line
			(start -1.27 1.7018)
			(end 1.27 1.7018)
			(stroke
				(width 0.1524)
				(type default)
			)
			(layer "B.SilkS")
		)
		(fp_rect
			(start 1.524 1.9558)
			(end -1.524 -1.9558)
			(stroke
				(width 0)
				(type default)
			)
			(fill no)
			(layer "B.CrtYd")
		)
		(fp_poly
			(pts
				(xy 1.524 -1.9558) (xy -1.524 -1.9558) (xy -1.524 1.9558) (xy 1.524 1.9558)
			)
			(stroke
				(width 0)
				(type default)
			)
			(fill no)
			(layer "B.Fab")
		)
		(pad "1" smd rect
			(at -0.65024 -0.8255 270)
			(size 0.4064 1.2192)
			(layers "B.Cu" "B.Mask" "B.Paste")
			(net "I2C_BMC_COMP_SDA_R")
		)
		(pad "2" smd rect
			(at 0 -0.8255 270)
			(size 0.4064 1.2192)
			(layers "B.Cu" "B.Mask" "B.Paste")
			(net "I2C_BMC_COMP_SDA_OUT")
		)
		(pad "3" smd rect
			(at 0.65024 -0.8255 270)
			(size 0.4064 1.2192)
			(layers "B.Cu" "B.Mask" "B.Paste")
			(net "GND")
		)
		(pad "4" smd rect
			(at 0.65024 0.8255 270)
			(size 0.4064 1.2192)
			(layers "B.Cu" "B.Mask" "B.Paste")
			(net "COMP_PWR_EN")
		)
		(pad "5" smd rect
			(at -0.65024 0.8255 270)
			(size 0.4064 1.2192)
			(layers "B.Cu" "B.Mask" "B.Paste")
			(net "P3V3_STBY")
		)
	)
	(footprint ""
		(layer "B.Cu")
		(at 46.6344 -161.3662 90)
		(property "Reference" "R324"
			(at 0 0 90)
			(layer "B.SilkS")
			(hide yes)
			(effects
				(font
					(size 1.27 1.27)
				)
				(justify mirror)
			)
		)
		(property "Value" "4K7R2F-GP"
			(at -0.064008 -3.993896 90)
			(unlocked yes)
			(layer "B.Fab")
			(hide yes)
			(effects
				(font
					(size 1.016 1.016)
					(thickness 0.1524)
				)
				(justify mirror)
			)
		)
		(property "Device Type" "R402H16"
			(at -0.064008 -5.517896 90)
			(unlocked yes)
			(layer "B.Fab")
			(hide yes)
			(effects
				(font
					(size 1.016 1.016)
					(thickness 0.1524)
				)
				(justify mirror)
			)
		)
		(duplicate_pad_numbers_are_jumpers no)
		(fp_line
			(start 0.508 -0.9398)
			(end 0.508 0.9398)
			(stroke
				(width 0.1524)
				(type default)
			)
			(layer "B.SilkS")
		)
		(fp_line
			(start -0.508 -0.9398)
			(end 0.508 -0.9398)
			(stroke
				(width 0.1524)
				(type default)
			)
			(layer "B.SilkS")
		)
		(fp_rect
			(start 0.508 0.9398)
			(end -0.508 -0.9398)
			(stroke
				(width 0)
				(type default)
			)
			(fill no)
			(layer "B.CrtYd")
		)
		(fp_rect
			(start 0.508 0.9398)
			(end -0.508 -0.9398)
			(stroke
				(width 0)
				(type default)
			)
			(fill no)
			(layer "B.Fab")
		)
		(pad "1" smd custom
			(at 0 -0.4445 270)
			(size 0.1397 0.1397)
			(layers "B.Cu" "B.Mask" "B.Paste")
			(net "BOARD_REV_2")
			(options
				(clearance outline)
				(anchor circle)
			)
			(primitives
				(gr_poly
					(pts
						(arc
							(start -0.1778 0.2794)
							(mid -0.249642 0.249642)
							(end -0.2794 0.1778)
						)
						(arc
							(start -0.2794 -0.1778)
							(mid -0.249642 -0.249642)
							(end -0.1778 -0.2794)
						)
						(arc
							(start 0.1778 -0.2794)
							(mid 0.249642 -0.249642)
							(end 0.2794 -0.1778)
						)
						(arc
							(start 0.2794 0.1778)
							(mid 0.249642 0.249642)
							(end 0.1778 0.2794)
						)
					)
					(width 0)
					(fill yes)
				)
			)
		)
		(pad "2" smd custom
			(at 0 0.4445 270)
			(size 0.1397 0.1397)
			(layers "B.Cu" "B.Mask" "B.Paste")
			(net "GND")
			(options
				(clearance outline)
				(anchor circle)
			)
			(primitives
				(gr_poly
					(pts
						(arc
							(start -0.1778 0.2794)
							(mid -0.249642 0.249642)
							(end -0.2794 0.1778)
						)
						(arc
							(start -0.2794 -0.1778)
							(mid -0.249642 -0.249642)
							(end -0.1778 -0.2794)
						)
						(arc
							(start 0.1778 -0.2794)
							(mid 0.249642 -0.249642)
							(end 0.2794 -0.1778)
						)
						(arc
							(start 0.2794 0.1778)
							(mid 0.249642 0.249642)
							(end 0.1778 0.2794)
						)
					)
					(width 0)
					(fill yes)
				)
			)
		)
	)
	(footprint ""
		(layer "B.Cu")
		(at 35.862006 -150.758398 180)
		(property "Reference" "C54"
			(at 0 0 0)
			(layer "B.SilkS")
			(hide yes)
			(effects
				(font
					(size 1.27 1.27)
				)
				(justify mirror)
			)
		)
		(property "Value" "SC1U16V3KX-5GP"
			(at 0 -2.8194 180)
			(unlocked yes)
			(layer "B.Fab")
			(hide yes)
			(effects
				(font
					(size 1.016 1.016)
					(thickness 0.1524)
				)
				(justify mirror)
			)
		)
		(property "Device Type" "C603H36"
			(at 0 -4.3434 180)
			(unlocked yes)
			(layer "B.Fab")
			(hide yes)
			(effects
				(font
					(size 1.016 1.016)
					(thickness 0.1524)
				)
				(justify mirror)
			)
		)
		(duplicate_pad_numbers_are_jumpers no)
		(fp_line
			(start -0.508 0)
			(end 0.508 0)
			(stroke
				(width 0.2032)
				(type default)
			)
			(layer "B.SilkS")
		)
		(fp_rect
			(start 0.5842 1.3335)
			(end -0.5842 -1.3335)
			(stroke
				(width 0)
				(type default)
			)
			(fill no)
			(layer "B.CrtYd")
		)
		(fp_rect
			(start 0.5842 1.3335)
			(end -0.5842 -1.3335)
			(stroke
				(width 0)
				(type default)
			)
			(fill no)
			(layer "B.Fab")
		)
		(pad "1" smd custom
			(at 0 -0.762)
			(size 0.2159 0.2159)
			(layers "B.Cu" "B.Mask" "B.Paste")
			(net "DDR_VREF")
			(options
				(clearance outline)
				(anchor circle)
			)
			(primitives
				(gr_poly
					(pts
						(arc
							(start -0.3302 0.4318)
							(mid -0.402042 0.402042)
							(end -0.4318 0.3302)
						)
						(arc
							(start -0.4318 -0.3302)
							(mid -0.402042 -0.402042)
							(end -0.3302 -0.4318)
						)
						(arc
							(start 0.3302 -0.4318)
							(mid 0.402042 -0.402042)
							(end 0.4318 -0.3302)
						)
						(arc
							(start 0.4318 0.3302)
							(mid 0.402042 0.402042)
							(end 0.3302 0.4318)
						)
					)
					(width 0)
					(fill yes)
				)
			)
		)
		(pad "2" smd custom
			(at 0 0.762)
			(size 0.2159 0.2159)
			(layers "B.Cu" "B.Mask" "B.Paste")
			(net "GND")
			(options
				(clearance outline)
				(anchor circle)
			)
			(primitives
				(gr_poly
					(pts
						(arc
							(start -0.3302 0.4318)
							(mid -0.402042 0.402042)
							(end -0.4318 0.3302)
						)
						(arc
							(start -0.4318 -0.3302)
							(mid -0.402042 -0.402042)
							(end -0.3302 -0.4318)
						)
						(arc
							(start 0.3302 -0.4318)
							(mid 0.402042 -0.402042)
							(end 0.4318 -0.3302)
						)
						(arc
							(start 0.4318 0.3302)
							(mid 0.402042 0.402042)
							(end 0.3302 0.4318)
						)
					)
					(width 0)
					(fill yes)
				)
			)
		)
	)
	(footprint ""
		(layer "B.Cu")
		(at 207.3148 -78.8416 -90)
		(property "Reference" "R615"
			(at 0 0 90)
			(layer "B.SilkS")
			(hide yes)
			(effects
				(font
					(size 1.27 1.27)
				)
				(justify mirror)
			)
		)
		(property "Value" "0R2J-2-GP"
			(at -0.064008 -3.993896 270)
			(unlocked yes)
			(layer "B.Fab")
			(hide yes)
			(effects
				(font
					(size 1.016 1.016)
					(thickness 0.1524)
				)
				(justify mirror)
			)
		)
		(property "Device Type" "R402H16"
			(at -0.064008 -5.517896 270)
			(unlocked yes)
			(layer "B.Fab")
			(hide yes)
			(effects
				(font
					(size 1.016 1.016)
					(thickness 0.1524)
				)
				(justify mirror)
			)
		)
		(duplicate_pad_numbers_are_jumpers no)
		(fp_line
			(start -0.508 -0.9398)
			(end 0.508 -0.9398)
			(stroke
				(width 0.1524)
				(type default)
			)
			(layer "B.SilkS")
		)
		(fp_line
			(start 0.508 -0.9398)
			(end 0.508 0.9398)
			(stroke
				(width 0.1524)
				(type default)
			)
			(layer "B.SilkS")
		)
		(fp_rect
			(start 0.508 0.9398)
			(end -0.508 -0.9398)
			(stroke
				(width 0)
				(type default)
			)
			(fill no)
			(layer "B.CrtYd")
		)
		(fp_rect
			(start 0.508 0.9398)
			(end -0.508 -0.9398)
			(stroke
				(width 0)
				(type default)
			)
			(fill no)
			(layer "B.Fab")
		)
		(pad "1" smd custom
			(at 0 -0.4445 90)
			(size 0.1397 0.1397)
			(layers "B.Cu" "B.Mask" "B.Paste")
			(net "GND_SEN")
			(options
				(clearance outline)
				(anchor circle)
			)
			(primitives
				(gr_poly
					(pts
						(arc
							(start -0.1778 0.2794)
							(mid -0.249642 0.249642)
							(end -0.2794 0.1778)
						)
						(arc
							(start -0.2794 -0.1778)
							(mid -0.249642 -0.249642)
							(end -0.1778 -0.2794)
						)
						(arc
							(start 0.1778 -0.2794)
							(mid 0.249642 -0.249642)
							(end 0.2794 -0.1778)
						)
						(arc
							(start 0.2794 0.1778)
							(mid 0.249642 0.249642)
							(end 0.1778 0.2794)
						)
					)
					(width 0)
					(fill yes)
				)
			)
		)
		(pad "2" smd custom
			(at 0 0.4445 90)
			(size 0.1397 0.1397)
			(layers "B.Cu" "B.Mask" "B.Paste")
			(net "GND")
			(options
				(clearance outline)
				(anchor circle)
			)
			(primitives
				(gr_poly
					(pts
						(arc
							(start -0.1778 0.2794)
							(mid -0.249642 0.249642)
							(end -0.2794 0.1778)
						)
						(arc
							(start -0.2794 -0.1778)
							(mid -0.249642 -0.249642)
							(end -0.1778 -0.2794)
						)
						(arc
							(start 0.1778 -0.2794)
							(mid 0.249642 -0.249642)
							(end 0.2794 -0.1778)
						)
						(arc
							(start 0.2794 0.1778)
							(mid 0.249642 0.249642)
							(end 0.1778 0.2794)
						)
					)
					(width 0)
					(fill yes)
				)
			)
		)
	)
	(footprint ""
		(layer "B.Cu")
		(at 192.405 -61.6204 90)
		(property "Reference" "C408"
			(at 0 0 90)
			(layer "B.SilkS")
			(hide yes)
			(effects
				(font
					(size 1.27 1.27)
				)
				(justify mirror)
			)
		)
		(property "Value" "SCD1U6D3V1KX-GP"
			(at 2.8321 -1.7399 90)
			(unlocked yes)
			(layer "B.Fab")
			(hide yes)
			(effects
				(font
					(size 1.016 1.016)
					(thickness 0.1524)
				)
				(justify mirror)
			)
		)
		(property "Device Type" "C0201H13"
			(at 2.8321 -3.2639 90)
			(unlocked yes)
			(layer "B.Fab")
			(hide yes)
			(effects
				(font
					(size 1.016 1.016)
					(thickness 0.1524)
				)
				(justify mirror)
			)
		)
		(duplicate_pad_numbers_are_jumpers no)
		(fp_rect
			(start 0.2794 0.6477)
			(end -0.2794 -0.6477)
			(stroke
				(width 0)
				(type default)
			)
			(fill no)
			(layer "B.CrtYd")
		)
		(fp_rect
			(start 0.2794 0.6477)
			(end -0.2794 -0.6477)
			(stroke
				(width 0)
				(type default)
			)
			(fill no)
			(layer "B.Fab")
		)
		(pad "1" smd custom
			(at 0 -0.2794 270)
			(size 0.0762 0.0762)
			(layers "B.Cu" "B.Mask" "B.Paste")
			(net "P0V975")
			(options
				(clearance outline)
				(anchor circle)
			)
			(primitives
				(gr_poly
					(pts
						(arc
							(start 0.1524 0.127)
							(mid 0.137521 0.162921)
							(end 0.1016 0.1778)
						)
						(arc
							(start -0.1016 0.1778)
							(mid -0.137521 0.162921)
							(end -0.1524 0.127)
						)
						(arc
							(start -0.1524 -0.127)
							(mid -0.137521 -0.162921)
							(end -0.1016 -0.1778)
						)
						(arc
							(start 0.1016 -0.1778)
							(mid 0.137521 -0.162921)
							(end 0.1524 -0.127)
						)
					)
					(width 0)
					(fill yes)
				)
			)
		)
		(pad "2" smd custom
			(at 0 0.2794 270)
			(size 0.0762 0.0762)
			(layers "B.Cu" "B.Mask" "B.Paste")
			(net "GND")
			(options
				(clearance outline)
				(anchor circle)
			)
			(primitives
				(gr_poly
					(pts
						(arc
							(start 0.1524 0.127)
							(mid 0.137521 0.162921)
							(end 0.1016 0.1778)
						)
						(arc
							(start -0.1016 0.1778)
							(mid -0.137521 0.162921)
							(end -0.1524 0.127)
						)
						(arc
							(start -0.1524 -0.127)
							(mid -0.137521 -0.162921)
							(end -0.1016 -0.1778)
						)
						(arc
							(start 0.1016 -0.1778)
							(mid 0.137521 -0.162921)
							(end 0.1524 -0.127)
						)
					)
					(width 0)
					(fill yes)
				)
			)
		)
	)
	(footprint ""
		(layer "B.Cu")
		(at 46.5074 -128.2192)
		(property "Reference" "R183"
			(at 0 0 0)
			(layer "B.SilkS")
			(hide yes)
			(effects
				(font
					(size 1.27 1.27)
				)
				(justify mirror)
			)
		)
		(property "Value" "2K2R2F-GP"
			(at -0.064008 -3.993896 0)
			(unlocked yes)
			(layer "B.Fab")
			(hide yes)
			(effects
				(font
					(size 1.016 1.016)
					(thickness 0.1524)
				)
				(justify mirror)
			)
		)
		(property "Device Type" "R402H16"
			(at -0.064008 -5.517896 0)
			(unlocked yes)
			(layer "B.Fab")
			(hide yes)
			(effects
				(font
					(size 1.016 1.016)
					(thickness 0.1524)
				)
				(justify mirror)
			)
		)
		(duplicate_pad_numbers_are_jumpers no)
		(fp_line
			(start -0.508 -0.9398)
			(end 0.508 -0.9398)
			(stroke
				(width 0.1524)
				(type default)
			)
			(layer "B.SilkS")
		)
		(fp_line
			(start 0.508 -0.9398)
			(end 0.508 0.9398)
			(stroke
				(width 0.1524)
				(type default)
			)
			(layer "B.SilkS")
		)
		(fp_rect
			(start 0.508 0.9398)
			(end -0.508 -0.9398)
			(stroke
				(width 0)
				(type default)
			)
			(fill no)
			(layer "B.CrtYd")
		)
		(fp_rect
			(start 0.508 0.9398)
			(end -0.508 -0.9398)
			(stroke
				(width 0)
				(type default)
			)
			(fill no)
			(layer "B.Fab")
		)
		(pad "1" smd custom
			(at 0 -0.4445 180)
			(size 0.1397 0.1397)
			(layers "B.Cu" "B.Mask" "B.Paste")
			(net "I2C_IOM_SCL")
			(options
				(clearance outline)
				(anchor circle)
			)
			(primitives
				(gr_poly
					(pts
						(arc
							(start -0.1778 0.2794)
							(mid -0.249642 0.249642)
							(end -0.2794 0.1778)
						)
						(arc
							(start -0.2794 -0.1778)
							(mid -0.249642 -0.249642)
							(end -0.1778 -0.2794)
						)
						(arc
							(start 0.1778 -0.2794)
							(mid 0.249642 -0.249642)
							(end 0.2794 -0.1778)
						)
						(arc
							(start 0.2794 0.1778)
							(mid 0.249642 0.249642)
							(end 0.1778 0.2794)
						)
					)
					(width 0)
					(fill yes)
				)
			)
		)
		(pad "2" smd custom
			(at 0 0.4445 180)
			(size 0.1397 0.1397)
			(layers "B.Cu" "B.Mask" "B.Paste")
			(net "P3V3_STBY")
			(options
				(clearance outline)
				(anchor circle)
			)
			(primitives
				(gr_poly
					(pts
						(arc
							(start -0.1778 0.2794)
							(mid -0.249642 0.249642)
							(end -0.2794 0.1778)
						)
						(arc
							(start -0.2794 -0.1778)
							(mid -0.249642 -0.249642)
							(end -0.1778 -0.2794)
						)
						(arc
							(start 0.1778 -0.2794)
							(mid 0.249642 -0.249642)
							(end 0.2794 -0.1778)
						)
						(arc
							(start 0.2794 0.1778)
							(mid 0.249642 0.249642)
							(end 0.1778 0.2794)
						)
					)
					(width 0)
					(fill yes)
				)
			)
		)
	)
	(footprint ""
		(layer "B.Cu")
		(at 148.0312 -19.6596 -90)
		(property "Reference" "C523"
			(at 0 0 90)
			(layer "B.SilkS")
			(hide yes)
			(effects
				(font
					(size 1.27 1.27)
				)
				(justify mirror)
			)
		)
		(property "Value" "SCD1U16V2KX-3GP"
			(at -1.1811 -2.7051 270)
			(unlocked yes)
			(layer "B.Fab")
			(hide yes)
			(effects
				(font
					(size 1.016 1.016)
					(thickness 0.1524)
				)
				(justify mirror)
			)
		)
		(property "Device Type" "C402H22"
			(at -1.1811 -4.2291 270)
			(unlocked yes)
			(layer "B.Fab")
			(hide yes)
			(effects
				(font
					(size 1.016 1.016)
					(thickness 0.1524)
				)
				(justify mirror)
			)
		)
		(duplicate_pad_numbers_are_jumpers no)
		(fp_rect
			(start 0.4318 0.9525)
			(end -0.4318 -0.9525)
			(stroke
				(width 0)
				(type default)
			)
			(fill no)
			(layer "B.CrtYd")
		)
		(fp_rect
			(start 0.4318 0.9525)
			(end -0.4318 -0.9525)
			(stroke
				(width 0)
				(type default)
			)
			(fill no)
			(layer "B.Fab")
		)
		(pad "1" smd custom
			(at 0 -0.4445 90)
			(size 0.1524 0.1524)
			(layers "B.Cu" "B.Mask" "B.Paste")
			(net "P3V3_STBY")
			(options
				(clearance outline)
				(anchor circle)
			)
			(primitives
				(gr_poly
					(pts
						(arc
							(start 0.3048 0.2032)
							(mid 0.275042 0.275042)
							(end 0.2032 0.3048)
						)
						(arc
							(start -0.2032 0.3048)
							(mid -0.275042 0.275042)
							(end -0.3048 0.2032)
						)
						(arc
							(start -0.3048 -0.2032)
							(mid -0.275042 -0.275042)
							(end -0.2032 -0.3048)
						)
						(arc
							(start 0.2032 -0.3048)
							(mid 0.275042 -0.275042)
							(end 0.3048 -0.2032)
						)
					)
					(width 0)
					(fill yes)
				)
			)
		)
		(pad "2" smd custom
			(at 0 0.4445 90)
			(size 0.1524 0.1524)
			(layers "B.Cu" "B.Mask" "B.Paste")
			(net "GND")
			(options
				(clearance outline)
				(anchor circle)
			)
			(primitives
				(gr_poly
					(pts
						(arc
							(start 0.3048 0.2032)
							(mid 0.275042 0.275042)
							(end 0.2032 0.3048)
						)
						(arc
							(start -0.2032 0.3048)
							(mid -0.275042 0.275042)
							(end -0.3048 0.2032)
						)
						(arc
							(start -0.3048 -0.2032)
							(mid -0.275042 -0.275042)
							(end -0.2032 -0.3048)
						)
						(arc
							(start 0.2032 -0.3048)
							(mid 0.275042 -0.275042)
							(end 0.3048 -0.2032)
						)
					)
					(width 0)
					(fill yes)
				)
			)
		)
	)
	(footprint ""
		(layer "B.Cu")
		(at 44.137326 -147.30476 90)
		(property "Reference" "C53"
			(at 0 0 90)
			(layer "B.SilkS")
			(hide yes)
			(effects
				(font
					(size 1.27 1.27)
				)
				(justify mirror)
			)
		)
		(property "Value" "SCD01U25V2KX-3GP"
			(at -1.1811 -2.7051 90)
			(unlocked yes)
			(layer "B.Fab")
			(hide yes)
			(effects
				(font
					(size 1.016 1.016)
					(thickness 0.1524)
				)
				(justify mirror)
			)
		)
		(property "Device Type" "C402H22"
			(at -1.1811 -4.2291 90)
			(unlocked yes)
			(layer "B.Fab")
			(hide yes)
			(effects
				(font
					(size 1.016 1.016)
					(thickness 0.1524)
				)
				(justify mirror)
			)
		)
		(duplicate_pad_numbers_are_jumpers no)
		(fp_rect
			(start 0.4318 0.9525)
			(end -0.4318 -0.9525)
			(stroke
				(width 0)
				(type default)
			)
			(fill no)
			(layer "B.CrtYd")
		)
		(fp_rect
			(start 0.4318 0.9525)
			(end -0.4318 -0.9525)
			(stroke
				(width 0)
				(type default)
			)
			(fill no)
			(layer "B.Fab")
		)
		(pad "1" smd custom
			(at 0 -0.4445 270)
			(size 0.1524 0.1524)
			(layers "B.Cu" "B.Mask" "B.Paste")
			(net "DDR_VREF")
			(options
				(clearance outline)
				(anchor circle)
			)
			(primitives
				(gr_poly
					(pts
						(arc
							(start 0.3048 0.2032)
							(mid 0.275042 0.275042)
							(end 0.2032 0.3048)
						)
						(arc
							(start -0.2032 0.3048)
							(mid -0.275042 0.275042)
							(end -0.3048 0.2032)
						)
						(arc
							(start -0.3048 -0.2032)
							(mid -0.275042 -0.275042)
							(end -0.2032 -0.3048)
						)
						(arc
							(start 0.2032 -0.3048)
							(mid 0.275042 -0.275042)
							(end 0.3048 -0.2032)
						)
					)
					(width 0)
					(fill yes)
				)
			)
		)
		(pad "2" smd custom
			(at 0 0.4445 270)
			(size 0.1524 0.1524)
			(layers "B.Cu" "B.Mask" "B.Paste")
			(net "GND")
			(options
				(clearance outline)
				(anchor circle)
			)
			(primitives
				(gr_poly
					(pts
						(arc
							(start 0.3048 0.2032)
							(mid 0.275042 0.275042)
							(end 0.2032 0.3048)
						)
						(arc
							(start -0.2032 0.3048)
							(mid -0.275042 0.275042)
							(end -0.3048 0.2032)
						)
						(arc
							(start -0.3048 -0.2032)
							(mid -0.275042 -0.275042)
							(end -0.2032 -0.3048)
						)
						(arc
							(start 0.2032 -0.3048)
							(mid 0.275042 -0.275042)
							(end 0.3048 -0.2032)
						)
					)
					(width 0)
					(fill yes)
				)
			)
		)
	)
	(footprint ""
		(layer "B.Cu")
		(at 185.97118 -57.7596 90)
		(property "Reference" "C431"
			(at 0 0 90)
			(layer "B.SilkS")
			(hide yes)
			(effects
				(font
					(size 1.27 1.27)
				)
				(justify mirror)
			)
		)
		(property "Value" "SCD1U16V2KX-3GP"
			(at -1.1811 -2.7051 90)
			(unlocked yes)
			(layer "B.Fab")
			(hide yes)
			(effects
				(font
					(size 1.016 1.016)
					(thickness 0.1524)
				)
				(justify mirror)
			)
		)
		(property "Device Type" "C402H22"
			(at -1.1811 -4.2291 90)
			(unlocked yes)
			(layer "B.Fab")
			(hide yes)
			(effects
				(font
					(size 1.016 1.016)
					(thickness 0.1524)
				)
				(justify mirror)
			)
		)
		(duplicate_pad_numbers_are_jumpers no)
		(fp_rect
			(start 0.4318 0.9525)
			(end -0.4318 -0.9525)
			(stroke
				(width 0)
				(type default)
			)
			(fill no)
			(layer "B.CrtYd")
		)
		(fp_rect
			(start 0.4318 0.9525)
			(end -0.4318 -0.9525)
			(stroke
				(width 0)
				(type default)
			)
			(fill no)
			(layer "B.Fab")
		)
		(pad "1" smd custom
			(at 0 -0.4445 270)
			(size 0.1524 0.1524)
			(layers "B.Cu" "B.Mask" "B.Paste")
			(net "P1V8")
			(options
				(clearance outline)
				(anchor circle)
			)
			(primitives
				(gr_poly
					(pts
						(arc
							(start 0.3048 0.2032)
							(mid 0.275042 0.275042)
							(end 0.2032 0.3048)
						)
						(arc
							(start -0.2032 0.3048)
							(mid -0.275042 0.275042)
							(end -0.3048 0.2032)
						)
						(arc
							(start -0.3048 -0.2032)
							(mid -0.275042 -0.275042)
							(end -0.2032 -0.3048)
						)
						(arc
							(start 0.2032 -0.3048)
							(mid 0.275042 -0.275042)
							(end 0.3048 -0.2032)
						)
					)
					(width 0)
					(fill yes)
				)
			)
		)
		(pad "2" smd custom
			(at 0 0.4445 270)
			(size 0.1524 0.1524)
			(layers "B.Cu" "B.Mask" "B.Paste")
			(net "GND")
			(options
				(clearance outline)
				(anchor circle)
			)
			(primitives
				(gr_poly
					(pts
						(arc
							(start 0.3048 0.2032)
							(mid 0.275042 0.275042)
							(end 0.2032 0.3048)
						)
						(arc
							(start -0.2032 0.3048)
							(mid -0.275042 0.275042)
							(end -0.3048 0.2032)
						)
						(arc
							(start -0.3048 -0.2032)
							(mid -0.275042 -0.275042)
							(end -0.2032 -0.3048)
						)
						(arc
							(start 0.2032 -0.3048)
							(mid 0.275042 -0.275042)
							(end 0.3048 -0.2032)
						)
					)
					(width 0)
					(fill yes)
				)
			)
		)
	)
	(footprint ""
		(layer "B.Cu")
		(at 25.334976 -141.03096 -90)
		(property "Reference" "R223"
			(at 0 0 90)
			(layer "B.SilkS")
			(hide yes)
			(effects
				(font
					(size 1.27 1.27)
				)
				(justify mirror)
			)
		)
		(property "Value" "120R2F-GP"
			(at -0.064008 -3.993896 270)
			(unlocked yes)
			(layer "B.Fab")
			(hide yes)
			(effects
				(font
					(size 1.016 1.016)
					(thickness 0.1524)
				)
				(justify mirror)
			)
		)
		(property "Device Type" "R402H16"
			(at -0.064008 -5.517896 270)
			(unlocked yes)
			(layer "B.Fab")
			(hide yes)
			(effects
				(font
					(size 1.016 1.016)
					(thickness 0.1524)
				)
				(justify mirror)
			)
		)
		(duplicate_pad_numbers_are_jumpers no)
		(fp_line
			(start -0.508 -0.9398)
			(end 0.508 -0.9398)
			(stroke
				(width 0.1524)
				(type default)
			)
			(layer "B.SilkS")
		)
		(fp_line
			(start 0.508 -0.9398)
			(end 0.508 0.9398)
			(stroke
				(width 0.1524)
				(type default)
			)
			(layer "B.SilkS")
		)
		(fp_rect
			(start 0.508 0.9398)
			(end -0.508 -0.9398)
			(stroke
				(width 0)
				(type default)
			)
			(fill no)
			(layer "B.CrtYd")
		)
		(fp_rect
			(start 0.508 0.9398)
			(end -0.508 -0.9398)
			(stroke
				(width 0)
				(type default)
			)
			(fill no)
			(layer "B.Fab")
		)
		(pad "1" smd custom
			(at 0 -0.4445 90)
			(size 0.1397 0.1397)
			(layers "B.Cu" "B.Mask" "B.Paste")
			(net "MEMRASN")
			(options
				(clearance outline)
				(anchor circle)
			)
			(primitives
				(gr_poly
					(pts
						(arc
							(start -0.1778 0.2794)
							(mid -0.249642 0.249642)
							(end -0.2794 0.1778)
						)
						(arc
							(start -0.2794 -0.1778)
							(mid -0.249642 -0.249642)
							(end -0.1778 -0.2794)
						)
						(arc
							(start 0.1778 -0.2794)
							(mid 0.249642 -0.249642)
							(end 0.2794 -0.1778)
						)
						(arc
							(start 0.2794 0.1778)
							(mid 0.249642 0.249642)
							(end 0.1778 0.2794)
						)
					)
					(width 0)
					(fill yes)
				)
			)
		)
		(pad "2" smd custom
			(at 0 0.4445 90)
			(size 0.1397 0.1397)
			(layers "B.Cu" "B.Mask" "B.Paste")
			(net "P1V2_STBY")
			(options
				(clearance outline)
				(anchor circle)
			)
			(primitives
				(gr_poly
					(pts
						(arc
							(start -0.1778 0.2794)
							(mid -0.249642 0.249642)
							(end -0.2794 0.1778)
						)
						(arc
							(start -0.2794 -0.1778)
							(mid -0.249642 -0.249642)
							(end -0.1778 -0.2794)
						)
						(arc
							(start 0.1778 -0.2794)
							(mid 0.249642 -0.249642)
							(end 0.2794 -0.1778)
						)
						(arc
							(start 0.2794 0.1778)
							(mid 0.249642 0.249642)
							(end 0.1778 0.2794)
						)
					)
					(width 0)
					(fill yes)
				)
			)
		)
	)
	(footprint ""
		(layer "B.Cu")
		(at 89.3826 -134.7724 180)
		(property "Reference" "R688"
			(at 0 0 0)
			(layer "B.SilkS")
			(hide yes)
			(effects
				(font
					(size 1.27 1.27)
				)
				(justify mirror)
			)
		)
		(property "Value" "100KR2F-L1-GP"
			(at -0.064008 -3.993896 180)
			(unlocked yes)
			(layer "B.Fab")
			(hide yes)
			(effects
				(font
					(size 1.016 1.016)
					(thickness 0.1524)
				)
				(justify mirror)
			)
		)
		(property "Device Type" "R402H16"
			(at -0.064008 -5.517896 180)
			(unlocked yes)
			(layer "B.Fab")
			(hide yes)
			(effects
				(font
					(size 1.016 1.016)
					(thickness 0.1524)
				)
				(justify mirror)
			)
		)
		(duplicate_pad_numbers_are_jumpers no)
		(fp_line
			(start 0.508 -0.9398)
			(end 0.508 0.9398)
			(stroke
				(width 0.1524)
				(type default)
			)
			(layer "B.SilkS")
		)
		(fp_line
			(start -0.508 -0.9398)
			(end 0.508 -0.9398)
			(stroke
				(width 0.1524)
				(type default)
			)
			(layer "B.SilkS")
		)
		(fp_rect
			(start 0.508 0.9398)
			(end -0.508 -0.9398)
			(stroke
				(width 0)
				(type default)
			)
			(fill no)
			(layer "B.CrtYd")
		)
		(fp_rect
			(start 0.508 0.9398)
			(end -0.508 -0.9398)
			(stroke
				(width 0)
				(type default)
			)
			(fill no)
			(layer "B.Fab")
		)
		(pad "1" smd custom
			(at 0 -0.4445)
			(size 0.1397 0.1397)
			(layers "B.Cu" "B.Mask" "B.Paste")
			(net "P3V3_STBY")
			(options
				(clearance outline)
				(anchor circle)
			)
			(primitives
				(gr_poly
					(pts
						(arc
							(start -0.1778 0.2794)
							(mid -0.249642 0.249642)
							(end -0.2794 0.1778)
						)
						(arc
							(start -0.2794 -0.1778)
							(mid -0.249642 -0.249642)
							(end -0.1778 -0.2794)
						)
						(arc
							(start 0.1778 -0.2794)
							(mid 0.249642 -0.249642)
							(end 0.2794 -0.1778)
						)
						(arc
							(start 0.2794 0.1778)
							(mid 0.249642 0.249642)
							(end 0.1778 0.2794)
						)
					)
					(width 0)
					(fill yes)
				)
			)
		)
		(pad "2" smd custom
			(at 0 0.4445)
			(size 0.1397 0.1397)
			(layers "B.Cu" "B.Mask" "B.Paste")
			(net "DEBUG_UART_IOM_RX")
			(options
				(clearance outline)
				(anchor circle)
			)
			(primitives
				(gr_poly
					(pts
						(arc
							(start -0.1778 0.2794)
							(mid -0.249642 0.249642)
							(end -0.2794 0.1778)
						)
						(arc
							(start -0.2794 -0.1778)
							(mid -0.249642 -0.249642)
							(end -0.1778 -0.2794)
						)
						(arc
							(start 0.1778 -0.2794)
							(mid 0.249642 -0.249642)
							(end 0.2794 -0.1778)
						)
						(arc
							(start 0.2794 0.1778)
							(mid 0.249642 0.249642)
							(end 0.1778 0.2794)
						)
					)
					(width 0)
					(fill yes)
				)
			)
		)
	)
	(footprint ""
		(layer "B.Cu")
		(at 53.19903 -132.651246 180)
		(property "Reference" "C115"
			(at 0 0 0)
			(layer "B.SilkS")
			(hide yes)
			(effects
				(font
					(size 1.27 1.27)
				)
				(justify mirror)
			)
		)
		(property "Value" "SC10U6D3V3KX-1-GP"
			(at 0 -2.8194 180)
			(unlocked yes)
			(layer "B.Fab")
			(hide yes)
			(effects
				(font
					(size 1.016 1.016)
					(thickness 0.1524)
				)
				(justify mirror)
			)
		)
		(property "Device Type" "C603H40"
			(at 0 -4.3434 180)
			(unlocked yes)
			(layer "B.Fab")
			(hide yes)
			(effects
				(font
					(size 1.016 1.016)
					(thickness 0.1524)
				)
				(justify mirror)
			)
		)
		(duplicate_pad_numbers_are_jumpers no)
		(fp_line
			(start -0.508 0)
			(end 0.508 0)
			(stroke
				(width 0.2032)
				(type default)
			)
			(layer "B.SilkS")
		)
		(fp_rect
			(start 0.5842 1.3335)
			(end -0.5842 -1.3335)
			(stroke
				(width 0)
				(type default)
			)
			(fill no)
			(layer "B.CrtYd")
		)
		(fp_rect
			(start 0.5842 1.3335)
			(end -0.5842 -1.3335)
			(stroke
				(width 0)
				(type default)
			)
			(fill no)
			(layer "B.Fab")
		)
		(pad "1" smd custom
			(at 0 -0.762)
			(size 0.2159 0.2159)
			(layers "B.Cu" "B.Mask" "B.Paste")
			(net "GND")
			(options
				(clearance outline)
				(anchor circle)
			)
			(primitives
				(gr_poly
					(pts
						(arc
							(start -0.3302 0.4318)
							(mid -0.402042 0.402042)
							(end -0.4318 0.3302)
						)
						(arc
							(start -0.4318 -0.3302)
							(mid -0.402042 -0.402042)
							(end -0.3302 -0.4318)
						)
						(arc
							(start 0.3302 -0.4318)
							(mid 0.402042 -0.402042)
							(end 0.4318 -0.3302)
						)
						(arc
							(start 0.4318 0.3302)
							(mid 0.402042 0.402042)
							(end 0.3302 0.4318)
						)
					)
					(width 0)
					(fill yes)
				)
			)
		)
		(pad "2" smd custom
			(at 0 0.762)
			(size 0.2159 0.2159)
			(layers "B.Cu" "B.Mask" "B.Paste")
			(net "P1V15_STBY")
			(options
				(clearance outline)
				(anchor circle)
			)
			(primitives
				(gr_poly
					(pts
						(arc
							(start -0.3302 0.4318)
							(mid -0.402042 0.402042)
							(end -0.4318 0.3302)
						)
						(arc
							(start -0.4318 -0.3302)
							(mid -0.402042 -0.402042)
							(end -0.3302 -0.4318)
						)
						(arc
							(start 0.3302 -0.4318)
							(mid 0.402042 -0.402042)
							(end 0.4318 -0.3302)
						)
						(arc
							(start 0.4318 0.3302)
							(mid 0.402042 0.402042)
							(end 0.3302 0.4318)
						)
					)
					(width 0)
					(fill yes)
				)
			)
		)
	)
	(footprint ""
		(layer "B.Cu")
		(at 189.1284 -124.405136 180)
		(property "Reference" "R561"
			(at 0 0 0)
			(layer "B.SilkS")
			(hide yes)
			(effects
				(font
					(size 1.27 1.27)
				)
				(justify mirror)
			)
		)
		(property "Value" "10KR2F-2-GP"
			(at -0.064008 -3.993896 180)
			(unlocked yes)
			(layer "B.Fab")
			(hide yes)
			(effects
				(font
					(size 1.016 1.016)
					(thickness 0.1524)
				)
				(justify mirror)
			)
		)
		(property "Device Type" "R402H16"
			(at -0.064008 -5.517896 180)
			(unlocked yes)
			(layer "B.Fab")
			(hide yes)
			(effects
				(font
					(size 1.016 1.016)
					(thickness 0.1524)
				)
				(justify mirror)
			)
		)
		(duplicate_pad_numbers_are_jumpers no)
		(fp_line
			(start 0.508 -0.9398)
			(end 0.508 0.9398)
			(stroke
				(width 0.1524)
				(type default)
			)
			(layer "B.SilkS")
		)
		(fp_line
			(start -0.508 -0.9398)
			(end 0.508 -0.9398)
			(stroke
				(width 0.1524)
				(type default)
			)
			(layer "B.SilkS")
		)
		(fp_rect
			(start 0.508 0.9398)
			(end -0.508 -0.9398)
			(stroke
				(width 0)
				(type default)
			)
			(fill no)
			(layer "B.CrtYd")
		)
		(fp_rect
			(start 0.508 0.9398)
			(end -0.508 -0.9398)
			(stroke
				(width 0)
				(type default)
			)
			(fill no)
			(layer "B.Fab")
		)
		(pad "1" smd custom
			(at 0 -0.4445)
			(size 0.1397 0.1397)
			(layers "B.Cu" "B.Mask" "B.Paste")
			(net "AGND_P0V975")
			(options
				(clearance outline)
				(anchor circle)
			)
			(primitives
				(gr_poly
					(pts
						(arc
							(start -0.1778 0.2794)
							(mid -0.249642 0.249642)
							(end -0.2794 0.1778)
						)
						(arc
							(start -0.2794 -0.1778)
							(mid -0.249642 -0.249642)
							(end -0.1778 -0.2794)
						)
						(arc
							(start 0.1778 -0.2794)
							(mid 0.249642 -0.249642)
							(end 0.2794 -0.1778)
						)
						(arc
							(start 0.2794 0.1778)
							(mid 0.249642 0.249642)
							(end 0.1778 0.2794)
						)
					)
					(width 0)
					(fill yes)
				)
			)
		)
		(pad "2" smd custom
			(at 0 0.4445)
			(size 0.1397 0.1397)
			(layers "B.Cu" "B.Mask" "B.Paste")
			(net "VT235_BIAS")
			(options
				(clearance outline)
				(anchor circle)
			)
			(primitives
				(gr_poly
					(pts
						(arc
							(start -0.1778 0.2794)
							(mid -0.249642 0.249642)
							(end -0.2794 0.1778)
						)
						(arc
							(start -0.2794 -0.1778)
							(mid -0.249642 -0.249642)
							(end -0.1778 -0.2794)
						)
						(arc
							(start 0.1778 -0.2794)
							(mid 0.249642 -0.249642)
							(end 0.2794 -0.1778)
						)
						(arc
							(start 0.2794 0.1778)
							(mid 0.249642 0.249642)
							(end 0.1778 0.2794)
						)
					)
					(width 0)
					(fill yes)
				)
			)
		)
	)
	(footprint ""
		(layer "B.Cu")
		(at 200.4314 -68.326 90)
		(property "Reference" "C354"
			(at 0 0 90)
			(layer "B.SilkS")
			(hide yes)
			(effects
				(font
					(size 1.27 1.27)
				)
				(justify mirror)
			)
		)
		(property "Value" "SCD1U6D3V1KX-GP"
			(at 2.8321 -1.7399 90)
			(unlocked yes)
			(layer "B.Fab")
			(hide yes)
			(effects
				(font
					(size 1.016 1.016)
					(thickness 0.1524)
				)
				(justify mirror)
			)
		)
		(property "Device Type" "C0201H13"
			(at 2.8321 -3.2639 90)
			(unlocked yes)
			(layer "B.Fab")
			(hide yes)
			(effects
				(font
					(size 1.016 1.016)
					(thickness 0.1524)
				)
				(justify mirror)
			)
		)
		(duplicate_pad_numbers_are_jumpers no)
		(fp_rect
			(start 0.2794 0.6477)
			(end -0.2794 -0.6477)
			(stroke
				(width 0)
				(type default)
			)
			(fill no)
			(layer "B.CrtYd")
		)
		(fp_rect
			(start 0.2794 0.6477)
			(end -0.2794 -0.6477)
			(stroke
				(width 0)
				(type default)
			)
			(fill no)
			(layer "B.Fab")
		)
		(pad "1" smd custom
			(at 0 -0.2794 270)
			(size 0.0762 0.0762)
			(layers "B.Cu" "B.Mask" "B.Paste")
			(net "SAS0_VDDH")
			(options
				(clearance outline)
				(anchor circle)
			)
			(primitives
				(gr_poly
					(pts
						(arc
							(start 0.1524 0.127)
							(mid 0.137521 0.162921)
							(end 0.1016 0.1778)
						)
						(arc
							(start -0.1016 0.1778)
							(mid -0.137521 0.162921)
							(end -0.1524 0.127)
						)
						(arc
							(start -0.1524 -0.127)
							(mid -0.137521 -0.162921)
							(end -0.1016 -0.1778)
						)
						(arc
							(start 0.1016 -0.1778)
							(mid 0.137521 -0.162921)
							(end 0.1524 -0.127)
						)
					)
					(width 0)
					(fill yes)
				)
			)
		)
		(pad "2" smd custom
			(at 0 0.2794 270)
			(size 0.0762 0.0762)
			(layers "B.Cu" "B.Mask" "B.Paste")
			(net "GND")
			(options
				(clearance outline)
				(anchor circle)
			)
			(primitives
				(gr_poly
					(pts
						(arc
							(start 0.1524 0.127)
							(mid 0.137521 0.162921)
							(end 0.1016 0.1778)
						)
						(arc
							(start -0.1016 0.1778)
							(mid -0.137521 0.162921)
							(end -0.1524 0.127)
						)
						(arc
							(start -0.1524 -0.127)
							(mid -0.137521 -0.162921)
							(end -0.1016 -0.1778)
						)
						(arc
							(start 0.1016 -0.1778)
							(mid 0.137521 -0.162921)
							(end 0.1524 -0.127)
						)
					)
					(width 0)
					(fill yes)
				)
			)
		)
	)
	(footprint ""
		(layer "B.Cu")
		(at 38.117018 -155.560522 180)
		(property "Reference" "R316"
			(at 0 0 0)
			(layer "B.SilkS")
			(hide yes)
			(effects
				(font
					(size 1.27 1.27)
				)
				(justify mirror)
			)
		)
		(property "Value" "0R2J-2-GP"
			(at -0.064262 -3.993642 180)
			(unlocked yes)
			(layer "B.Fab")
			(hide yes)
			(effects
				(font
					(size 1.016 1.016)
					(thickness 0.1524)
				)
				(justify mirror)
			)
		)
		(property "Device Type" "R402H16"
			(at -0.064262 -5.517896 180)
			(unlocked yes)
			(layer "B.Fab")
			(hide yes)
			(effects
				(font
					(size 1.016 1.016)
					(thickness 0.1524)
				)
				(justify mirror)
			)
		)
		(duplicate_pad_numbers_are_jumpers no)
		(fp_line
			(start 0.508 -0.9398)
			(end 0.508 0.9398)
			(stroke
				(width 0.1524)
				(type default)
			)
			(layer "B.SilkS")
		)
		(fp_line
			(start -0.508 -0.9398)
			(end 0.508 -0.9398)
			(stroke
				(width 0.1524)
				(type default)
			)
			(layer "B.SilkS")
		)
		(fp_rect
			(start 0.508 0.9398)
			(end -0.508 -0.9398)
			(stroke
				(width 0)
				(type default)
			)
			(fill no)
			(layer "B.CrtYd")
		)
		(fp_rect
			(start 0.508 0.9398)
			(end -0.508 -0.9398)
			(stroke
				(width 0)
				(type default)
			)
			(fill no)
			(layer "B.Fab")
		)
		(pad "1" smd custom
			(at 0 -0.4445)
			(size 0.1397 0.1397)
			(layers "B.Cu" "B.Mask" "B.Paste")
			(net "BMC_RMT_HB")
			(options
				(clearance outline)
				(anchor circle)
			)
			(primitives
				(gr_poly
					(pts
						(arc
							(start -0.1778 0.2794)
							(mid -0.249642 0.249642)
							(end -0.2794 0.1778)
						)
						(arc
							(start -0.2794 -0.1778)
							(mid -0.249642 -0.249642)
							(end -0.1778 -0.2794)
						)
						(arc
							(start 0.1778 -0.2794)
							(mid 0.249642 -0.249642)
							(end 0.2794 -0.1778)
						)
						(arc
							(start 0.2794 0.1778)
							(mid 0.249642 0.249642)
							(end 0.1778 0.2794)
						)
					)
					(width 0)
					(fill yes)
				)
			)
		)
		(pad "2" smd custom
			(at 0 0.4445)
			(size 0.1397 0.1397)
			(layers "B.Cu" "B.Mask" "B.Paste")
			(net "BMC_RMT_HEARTBEAT")
			(options
				(clearance outline)
				(anchor circle)
			)
			(primitives
				(gr_poly
					(pts
						(arc
							(start -0.1778 0.2794)
							(mid -0.249642 0.249642)
							(end -0.2794 0.1778)
						)
						(arc
							(start -0.2794 -0.1778)
							(mid -0.249642 -0.249642)
							(end -0.1778 -0.2794)
						)
						(arc
							(start 0.1778 -0.2794)
							(mid 0.249642 -0.249642)
							(end 0.2794 -0.1778)
						)
						(arc
							(start 0.2794 0.1778)
							(mid 0.249642 0.249642)
							(end 0.1778 0.2794)
						)
					)
					(width 0)
					(fill yes)
				)
			)
		)
	)
	(footprint ""
		(layer "B.Cu")
		(at 202.463146 -61.35243)
		(property "Reference" "C454"
			(at 0 0 0)
			(layer "B.SilkS")
			(hide yes)
			(effects
				(font
					(size 1.27 1.27)
				)
				(justify mirror)
			)
		)
		(property "Value" "SCD1U16V2KX-3GP"
			(at -1.1811 -2.7051 0)
			(unlocked yes)
			(layer "B.Fab")
			(hide yes)
			(effects
				(font
					(size 1.016 1.016)
					(thickness 0.1524)
				)
				(justify mirror)
			)
		)
		(property "Device Type" "C402H22"
			(at -1.1811 -4.2291 0)
			(unlocked yes)
			(layer "B.Fab")
			(hide yes)
			(effects
				(font
					(size 1.016 1.016)
					(thickness 0.1524)
				)
				(justify mirror)
			)
		)
		(duplicate_pad_numbers_are_jumpers no)
		(fp_rect
			(start 0.4318 0.9525)
			(end -0.4318 -0.9525)
			(stroke
				(width 0)
				(type default)
			)
			(fill no)
			(layer "B.CrtYd")
		)
		(fp_rect
			(start 0.4318 0.9525)
			(end -0.4318 -0.9525)
			(stroke
				(width 0)
				(type default)
			)
			(fill no)
			(layer "B.Fab")
		)
		(pad "1" smd custom
			(at 0 -0.4445 180)
			(size 0.1524 0.1524)
			(layers "B.Cu" "B.Mask" "B.Paste")
			(net "P1V8")
			(options
				(clearance outline)
				(anchor circle)
			)
			(primitives
				(gr_poly
					(pts
						(arc
							(start 0.3048 0.2032)
							(mid 0.275042 0.275042)
							(end 0.2032 0.3048)
						)
						(arc
							(start -0.2032 0.3048)
							(mid -0.275042 0.275042)
							(end -0.3048 0.2032)
						)
						(arc
							(start -0.3048 -0.2032)
							(mid -0.275042 -0.275042)
							(end -0.2032 -0.3048)
						)
						(arc
							(start 0.2032 -0.3048)
							(mid 0.275042 -0.275042)
							(end 0.3048 -0.2032)
						)
					)
					(width 0)
					(fill yes)
				)
			)
		)
		(pad "2" smd custom
			(at 0 0.4445 180)
			(size 0.1524 0.1524)
			(layers "B.Cu" "B.Mask" "B.Paste")
			(net "GND")
			(options
				(clearance outline)
				(anchor circle)
			)
			(primitives
				(gr_poly
					(pts
						(arc
							(start 0.3048 0.2032)
							(mid 0.275042 0.275042)
							(end 0.2032 0.3048)
						)
						(arc
							(start -0.2032 0.3048)
							(mid -0.275042 0.275042)
							(end -0.3048 0.2032)
						)
						(arc
							(start -0.3048 -0.2032)
							(mid -0.275042 -0.275042)
							(end -0.2032 -0.3048)
						)
						(arc
							(start 0.2032 -0.3048)
							(mid 0.275042 -0.275042)
							(end 0.3048 -0.2032)
						)
					)
					(width 0)
					(fill yes)
				)
			)
		)
	)
	(footprint ""
		(layer "B.Cu")
		(at 94.0054 -143.087852 -90)
		(property "Reference" "Q26"
			(at 0 0 90)
			(layer "B.SilkS")
			(hide yes)
			(effects
				(font
					(size 1.27 1.27)
				)
				(justify mirror)
			)
		)
		(property "Value" "2N7002K-1-GP"
			(at -0.127 -8.9662 270)
			(unlocked yes)
			(layer "B.Fab")
			(hide yes)
			(effects
				(font
					(size 1.016 1.016)
					(thickness 0.1524)
				)
				(justify mirror)
			)
		)
		(property "Device Type" "SOT23DGS2D4H44"
			(at -0.127 -10.4902 270)
			(unlocked yes)
			(layer "B.Fab")
			(hide yes)
			(effects
				(font
					(size 1.016 1.016)
					(thickness 0.1524)
				)
				(justify mirror)
			)
		)
		(duplicate_pad_numbers_are_jumpers no)
		(fp_line
			(start -1.651 1.778)
			(end -1.651 -1.778)
			(stroke
				(width 0.1524)
				(type default)
			)
			(layer "B.SilkS")
		)
		(fp_line
			(start 1.651 1.778)
			(end -1.651 1.778)
			(stroke
				(width 0.1524)
				(type default)
			)
			(layer "B.SilkS")
		)
		(fp_line
			(start -1.651 -1.778)
			(end 1.651 -1.778)
			(stroke
				(width 0.1524)
				(type default)
			)
			(layer "B.SilkS")
		)
		(fp_line
			(start 1.651 -1.778)
			(end 1.651 1.778)
			(stroke
				(width 0.1524)
				(type default)
			)
			(layer "B.SilkS")
		)
		(fp_poly
			(pts
				(xy 1.778 1.8796) (xy 1.778 -1.8796) (xy -1.778 -1.8796) (xy -1.778 1.8796)
			)
			(stroke
				(width 0)
				(type default)
			)
			(fill no)
			(layer "B.CrtYd")
		)
		(fp_poly
			(pts
				(xy 1.778 1.8796) (xy 1.778 -1.8796) (xy -1.778 -1.8796) (xy -1.778 1.8796)
			)
			(stroke
				(width 0)
				(type default)
			)
			(fill no)
			(layer "B.Fab")
		)
		(pad "D" smd custom
			(at 0 -0.9525 90)
			(size 0.1905 0.1905)
			(layers "B.Cu" "B.Mask" "B.Paste")
			(net "DB_PRSNT_BMC_N")
			(options
				(clearance outline)
				(anchor circle)
			)
			(primitives
				(gr_poly
					(pts
						(arc
							(start -0.1778 -0.5715)
							(mid -0.321484 -0.511984)
							(end -0.381 -0.3683)
						)
						(arc
							(start -0.381 0.3683)
							(mid -0.321484 0.511984)
							(end -0.1778 0.5715)
						)
						(arc
							(start 0.1778 0.5715)
							(mid 0.321484 0.511984)
							(end 0.381 0.3683)
						)
						(arc
							(start 0.381 -0.3683)
							(mid 0.321484 -0.511984)
							(end 0.1778 -0.5715)
						)
					)
					(width 0)
					(fill yes)
				)
			)
		)
		(pad "G" smd custom
			(at 0.98425 0.9525 90)
			(size 0.1905 0.1905)
			(layers "B.Cu" "B.Mask" "B.Paste")
			(net "DEBUG_CARD_PRSNT")
			(options
				(clearance outline)
				(anchor circle)
			)
			(primitives
				(gr_poly
					(pts
						(arc
							(start -0.1778 -0.5715)
							(mid -0.321484 -0.511984)
							(end -0.381 -0.3683)
						)
						(arc
							(start -0.381 0.3683)
							(mid -0.321484 0.511984)
							(end -0.1778 0.5715)
						)
						(arc
							(start 0.1778 0.5715)
							(mid 0.321484 0.511984)
							(end 0.381 0.3683)
						)
						(arc
							(start 0.381 -0.3683)
							(mid 0.321484 -0.511984)
							(end 0.1778 -0.5715)
						)
					)
					(width 0)
					(fill yes)
				)
			)
		)
		(pad "S" smd custom
			(at -0.98425 0.9525 90)
			(size 0.1905 0.1905)
			(layers "B.Cu" "B.Mask" "B.Paste")
			(net "GND")
			(options
				(clearance outline)
				(anchor circle)
			)
			(primitives
				(gr_poly
					(pts
						(arc
							(start -0.1778 -0.5715)
							(mid -0.321484 -0.511984)
							(end -0.381 -0.3683)
						)
						(arc
							(start -0.381 0.3683)
							(mid -0.321484 0.511984)
							(end -0.1778 0.5715)
						)
						(arc
							(start 0.1778 0.5715)
							(mid 0.321484 0.511984)
							(end 0.381 0.3683)
						)
						(arc
							(start 0.381 -0.3683)
							(mid 0.321484 -0.511984)
							(end 0.1778 -0.5715)
						)
					)
					(width 0)
					(fill yes)
				)
			)
		)
	)
	(footprint ""
		(layer "B.Cu")
		(at 182.5244 -77.2922 -90)
		(property "Reference" "TP94"
			(at 0 0 90)
			(layer "B.SilkS")
			(hide yes)
			(effects
				(font
					(size 1.27 1.27)
				)
				(justify mirror)
			)
		)
		(property "Value" "TPAD28-2-GP"
			(at 0.0127 -1.6637 270)
			(unlocked yes)
			(layer "B.Fab")
			(hide yes)
			(effects
				(font
					(size 1.016 1.016)
					(thickness 0.1524)
				)
				(justify mirror)
			)
		)
		(property "Device Type" "TPAD28"
			(at 0.0127 -3.1877 270)
			(unlocked yes)
			(layer "B.Fab")
			(hide yes)
			(effects
				(font
					(size 1.016 1.016)
					(thickness 0.1524)
				)
				(justify mirror)
			)
		)
		(duplicate_pad_numbers_are_jumpers no)
		(fp_poly
			(pts
				(arc
					(start 0 -0.3556)
					(mid 0 0.3556)
					(end 0 -0.3556)
				)
			)
			(stroke
				(width 0)
				(type default)
			)
			(fill no)
			(layer "B.CrtYd")
		)
		(fp_poly
			(pts
				(arc
					(start 0 -0.6096)
					(mid 0 0.6096)
					(end 0 -0.6096)
				)
			)
			(stroke
				(width 0)
				(type default)
			)
			(fill no)
			(layer "B.Fab")
		)
		(pad "1" smd circle
			(at 0 0 90)
			(size 0.7112 0.7112)
			(layers "B.Cu" "B.Mask" "B.Paste")
			(net "IOC_GPIO_9")
		)
	)
	(footprint ""
		(layer "B.Cu")
		(at 199.089518 -81.153 180)
		(property "Reference" "C293"
			(at 0 0 0)
			(layer "B.SilkS")
			(hide yes)
			(effects
				(font
					(size 1.27 1.27)
				)
				(justify mirror)
			)
		)
		(property "Value" "SCD22U10V1KX-GP"
			(at 2.8321 -1.7399 180)
			(unlocked yes)
			(layer "B.Fab")
			(hide yes)
			(effects
				(font
					(size 1.016 1.016)
					(thickness 0.1524)
				)
				(justify mirror)
			)
		)
		(property "Device Type" "C0201H13"
			(at 2.8321 -3.2639 180)
			(unlocked yes)
			(layer "B.Fab")
			(hide yes)
			(effects
				(font
					(size 1.016 1.016)
					(thickness 0.1524)
				)
				(justify mirror)
			)
		)
		(duplicate_pad_numbers_are_jumpers no)
		(fp_rect
			(start 0.2794 0.6477)
			(end -0.2794 -0.6477)
			(stroke
				(width 0)
				(type default)
			)
			(fill no)
			(layer "B.CrtYd")
		)
		(fp_rect
			(start 0.2794 0.6477)
			(end -0.2794 -0.6477)
			(stroke
				(width 0)
				(type default)
			)
			(fill no)
			(layer "B.Fab")
		)
		(pad "1" smd custom
			(at 0 -0.2794)
			(size 0.0762 0.0762)
			(layers "B.Cu" "B.Mask" "B.Paste")
			(net "PCIE_IOM_TO_COMP_10_DP_C")
			(options
				(clearance outline)
				(anchor circle)
			)
			(primitives
				(gr_poly
					(pts
						(arc
							(start 0.1524 0.127)
							(mid 0.137521 0.162921)
							(end 0.1016 0.1778)
						)
						(arc
							(start -0.1016 0.1778)
							(mid -0.137521 0.162921)
							(end -0.1524 0.127)
						)
						(arc
							(start -0.1524 -0.127)
							(mid -0.137521 -0.162921)
							(end -0.1016 -0.1778)
						)
						(arc
							(start 0.1016 -0.1778)
							(mid 0.137521 -0.162921)
							(end 0.1524 -0.127)
						)
					)
					(width 0)
					(fill yes)
				)
			)
		)
		(pad "2" smd custom
			(at 0 0.2794)
			(size 0.0762 0.0762)
			(layers "B.Cu" "B.Mask" "B.Paste")
			(net "PCIE_IOM_TO_COMP_10_DP")
			(options
				(clearance outline)
				(anchor circle)
			)
			(primitives
				(gr_poly
					(pts
						(arc
							(start 0.1524 0.127)
							(mid 0.137521 0.162921)
							(end 0.1016 0.1778)
						)
						(arc
							(start -0.1016 0.1778)
							(mid -0.137521 0.162921)
							(end -0.1524 0.127)
						)
						(arc
							(start -0.1524 -0.127)
							(mid -0.137521 -0.162921)
							(end -0.1016 -0.1778)
						)
						(arc
							(start 0.1016 -0.1778)
							(mid 0.137521 -0.162921)
							(end 0.1524 -0.127)
						)
					)
					(width 0)
					(fill yes)
				)
			)
		)
	)
	(footprint ""
		(layer "B.Cu")
		(at 203.708 -59.055)
		(property "Reference" "TP115"
			(at 0 0 0)
			(layer "B.SilkS")
			(hide yes)
			(effects
				(font
					(size 1.27 1.27)
				)
				(justify mirror)
			)
		)
		(property "Value" "TPAD28-2-GP"
			(at 0.0127 -1.6637 0)
			(unlocked yes)
			(layer "B.Fab")
			(hide yes)
			(effects
				(font
					(size 1.016 1.016)
					(thickness 0.1524)
				)
				(justify mirror)
			)
		)
		(property "Device Type" "TPAD28"
			(at 0.0127 -3.1877 0)
			(unlocked yes)
			(layer "B.Fab")
			(hide yes)
			(effects
				(font
					(size 1.016 1.016)
					(thickness 0.1524)
				)
				(justify mirror)
			)
		)
		(duplicate_pad_numbers_are_jumpers no)
		(fp_poly
			(pts
				(arc
					(start 0.3556 0)
					(mid -0.3556 0)
					(end 0.3556 0)
				)
			)
			(stroke
				(width 0)
				(type default)
			)
			(fill no)
			(layer "B.CrtYd")
		)
		(fp_poly
			(pts
				(arc
					(start 0.6096 0)
					(mid -0.6096 0)
					(end 0.6096 0)
				)
			)
			(stroke
				(width 0)
				(type default)
			)
			(fill no)
			(layer "B.Fab")
		)
		(pad "1" smd circle
			(at 0 0 180)
			(size 0.7112 0.7112)
			(layers "B.Cu" "B.Mask" "B.Paste")
			(net "SIO_DOUT_0")
		)
	)
	(footprint ""
		(layer "B.Cu")
		(at 125.984 -13.56741)
		(property "Reference" "C144"
			(at 0 0 0)
			(layer "B.SilkS")
			(hide yes)
			(effects
				(font
					(size 1.27 1.27)
				)
				(justify mirror)
			)
		)
		(property "Value" "SC1U16V3KX-5GP"
			(at 0 -2.8194 0)
			(unlocked yes)
			(layer "B.Fab")
			(hide yes)
			(effects
				(font
					(size 1.016 1.016)
					(thickness 0.1524)
				)
				(justify mirror)
			)
		)
		(property "Device Type" "C603H36"
			(at 0 -4.3434 0)
			(unlocked yes)
			(layer "B.Fab")
			(hide yes)
			(effects
				(font
					(size 1.016 1.016)
					(thickness 0.1524)
				)
				(justify mirror)
			)
		)
		(duplicate_pad_numbers_are_jumpers no)
		(fp_line
			(start -0.508 0)
			(end 0.508 0)
			(stroke
				(width 0.2032)
				(type default)
			)
			(layer "B.SilkS")
		)
		(fp_rect
			(start 0.5842 1.3335)
			(end -0.5842 -1.3335)
			(stroke
				(width 0)
				(type default)
			)
			(fill no)
			(layer "B.CrtYd")
		)
		(fp_rect
			(start 0.5842 1.3335)
			(end -0.5842 -1.3335)
			(stroke
				(width 0)
				(type default)
			)
			(fill no)
			(layer "B.Fab")
		)
		(pad "1" smd custom
			(at 0 -0.762 180)
			(size 0.2159 0.2159)
			(layers "B.Cu" "B.Mask" "B.Paste")
			(net "MB0_CM_OV_R")
			(options
				(clearance outline)
				(anchor circle)
			)
			(primitives
				(gr_poly
					(pts
						(arc
							(start -0.3302 0.4318)
							(mid -0.402042 0.402042)
							(end -0.4318 0.3302)
						)
						(arc
							(start -0.4318 -0.3302)
							(mid -0.402042 -0.402042)
							(end -0.3302 -0.4318)
						)
						(arc
							(start 0.3302 -0.4318)
							(mid 0.402042 -0.402042)
							(end 0.4318 -0.3302)
						)
						(arc
							(start 0.4318 0.3302)
							(mid 0.402042 0.402042)
							(end 0.3302 0.4318)
						)
					)
					(width 0)
					(fill yes)
				)
			)
		)
		(pad "2" smd custom
			(at 0 0.762 180)
			(size 0.2159 0.2159)
			(layers "B.Cu" "B.Mask" "B.Paste")
			(net "AGND_CURRENT_MON")
			(options
				(clearance outline)
				(anchor circle)
			)
			(primitives
				(gr_poly
					(pts
						(arc
							(start -0.3302 0.4318)
							(mid -0.402042 0.402042)
							(end -0.4318 0.3302)
						)
						(arc
							(start -0.4318 -0.3302)
							(mid -0.402042 -0.402042)
							(end -0.3302 -0.4318)
						)
						(arc
							(start 0.3302 -0.4318)
							(mid 0.402042 -0.402042)
							(end 0.4318 -0.3302)
						)
						(arc
							(start 0.4318 0.3302)
							(mid 0.402042 0.402042)
							(end 0.3302 0.4318)
						)
					)
					(width 0)
					(fill yes)
				)
			)
		)
	)
	(footprint ""
		(layer "B.Cu")
		(at 79.819246 -56.237378 90)
		(property "Reference" "C187"
			(at 0 0 90)
			(layer "B.SilkS")
			(hide yes)
			(effects
				(font
					(size 1.27 1.27)
				)
				(justify mirror)
			)
		)
		(property "Value" "SC10U6D3V5KX-4GP"
			(at 0.0762 -6.1214 90)
			(unlocked yes)
			(layer "B.Fab")
			(hide yes)
			(effects
				(font
					(size 1.016 1.016)
					(thickness 0.1524)
				)
				(justify mirror)
			)
		)
		(property "Device Type" "C805H58"
			(at 0.0762 -8.1534 90)
			(unlocked yes)
			(layer "B.Fab")
			(hide yes)
			(effects
				(font
					(size 1.016 1.016)
					(thickness 0.1524)
				)
				(justify mirror)
			)
		)
		(duplicate_pad_numbers_are_jumpers no)
		(fp_line
			(start -0.635 0)
			(end 0.635 0)
			(stroke
				(width 0.508)
				(type default)
			)
			(layer "B.SilkS")
		)
		(fp_rect
			(start 0.9652 1.778)
			(end -0.9652 -1.778)
			(stroke
				(width 0)
				(type default)
			)
			(fill no)
			(layer "B.CrtYd")
		)
		(fp_poly
			(pts
				(xy 0.9652 -1.778) (xy -0.9652 -1.778) (xy -0.9652 1.778) (xy 0.9652 1.778)
			)
			(stroke
				(width 0)
				(type default)
			)
			(fill no)
			(layer "B.Fab")
		)
		(pad "1" smd rect
			(at 0 -0.9652 270)
			(size 1.397 1.143)
			(layers "B.Cu" "B.Mask" "B.Paste")
			(net "P3V3")
		)
		(pad "2" smd rect
			(at 0 0.9652 270)
			(size 1.397 1.143)
			(layers "B.Cu" "B.Mask" "B.Paste")
			(net "GND")
		)
	)
	(footprint ""
		(layer "B.Cu")
		(at 181.4576 -68.2244)
		(property "Reference" "TP109"
			(at 0 0 0)
			(layer "B.SilkS")
			(hide yes)
			(effects
				(font
					(size 1.27 1.27)
				)
				(justify mirror)
			)
		)
		(property "Value" "TPAD28-2-GP"
			(at 0.0127 -1.6637 0)
			(unlocked yes)
			(layer "B.Fab")
			(hide yes)
			(effects
				(font
					(size 1.016 1.016)
					(thickness 0.1524)
				)
				(justify mirror)
			)
		)
		(property "Device Type" "TPAD28"
			(at 0.0127 -3.1877 0)
			(unlocked yes)
			(layer "B.Fab")
			(hide yes)
			(effects
				(font
					(size 1.016 1.016)
					(thickness 0.1524)
				)
				(justify mirror)
			)
		)
		(duplicate_pad_numbers_are_jumpers no)
		(fp_poly
			(pts
				(arc
					(start 0.3556 0)
					(mid -0.3556 0)
					(end 0.3556 0)
				)
			)
			(stroke
				(width 0)
				(type default)
			)
			(fill no)
			(layer "B.CrtYd")
		)
		(fp_poly
			(pts
				(arc
					(start 0.6096 0)
					(mid -0.6096 0)
					(end 0.6096 0)
				)
			)
			(stroke
				(width 0)
				(type default)
			)
			(fill no)
			(layer "B.Fab")
		)
		(pad "1" smd circle
			(at 0 0 180)
			(size 0.7112 0.7112)
			(layers "B.Cu" "B.Mask" "B.Paste")
			(net "IOC_GPIO_24")
		)
	)
	(footprint ""
		(layer "B.Cu")
		(at 164.769292 -75.714606)
		(property "Reference" "C328"
			(at 0 0 0)
			(layer "B.SilkS")
			(hide yes)
			(effects
				(font
					(size 1.27 1.27)
				)
				(justify mirror)
			)
		)
		(property "Value" "SCD1U16V2KX-3GP"
			(at -1.1811 -2.7051 0)
			(unlocked yes)
			(layer "B.Fab")
			(hide yes)
			(effects
				(font
					(size 1.016 1.016)
					(thickness 0.1524)
				)
				(justify mirror)
			)
		)
		(property "Device Type" "C402H22"
			(at -1.1811 -4.2291 0)
			(unlocked yes)
			(layer "B.Fab")
			(hide yes)
			(effects
				(font
					(size 1.016 1.016)
					(thickness 0.1524)
				)
				(justify mirror)
			)
		)
		(duplicate_pad_numbers_are_jumpers no)
		(fp_rect
			(start 0.4318 0.9525)
			(end -0.4318 -0.9525)
			(stroke
				(width 0)
				(type default)
			)
			(fill no)
			(layer "B.CrtYd")
		)
		(fp_rect
			(start 0.4318 0.9525)
			(end -0.4318 -0.9525)
			(stroke
				(width 0)
				(type default)
			)
			(fill no)
			(layer "B.Fab")
		)
		(pad "1" smd custom
			(at 0 -0.4445 180)
			(size 0.1524 0.1524)
			(layers "B.Cu" "B.Mask" "B.Paste")
			(net "P1V8")
			(options
				(clearance outline)
				(anchor circle)
			)
			(primitives
				(gr_poly
					(pts
						(arc
							(start 0.3048 0.2032)
							(mid 0.275042 0.275042)
							(end 0.2032 0.3048)
						)
						(arc
							(start -0.2032 0.3048)
							(mid -0.275042 0.275042)
							(end -0.3048 0.2032)
						)
						(arc
							(start -0.3048 -0.2032)
							(mid -0.275042 -0.275042)
							(end -0.2032 -0.3048)
						)
						(arc
							(start 0.2032 -0.3048)
							(mid 0.275042 -0.275042)
							(end 0.3048 -0.2032)
						)
					)
					(width 0)
					(fill yes)
				)
			)
		)
		(pad "2" smd custom
			(at 0 0.4445 180)
			(size 0.1524 0.1524)
			(layers "B.Cu" "B.Mask" "B.Paste")
			(net "GND")
			(options
				(clearance outline)
				(anchor circle)
			)
			(primitives
				(gr_poly
					(pts
						(arc
							(start 0.3048 0.2032)
							(mid 0.275042 0.275042)
							(end 0.2032 0.3048)
						)
						(arc
							(start -0.2032 0.3048)
							(mid -0.275042 0.275042)
							(end -0.3048 0.2032)
						)
						(arc
							(start -0.3048 -0.2032)
							(mid -0.275042 -0.275042)
							(end -0.2032 -0.3048)
						)
						(arc
							(start 0.2032 -0.3048)
							(mid 0.275042 -0.275042)
							(end 0.3048 -0.2032)
						)
					)
					(width 0)
					(fill yes)
				)
			)
		)
	)
	(footprint ""
		(layer "B.Cu")
		(at 177.012346 -154.319732 -90)
		(property "Reference" "C158"
			(at 0 0 90)
			(layer "B.SilkS")
			(hide yes)
			(effects
				(font
					(size 1.27 1.27)
				)
				(justify mirror)
			)
		)
		(property "Value" "SCD1U50V3KX-GP"
			(at 0 -2.8194 270)
			(unlocked yes)
			(layer "B.Fab")
			(hide yes)
			(effects
				(font
					(size 1.016 1.016)
					(thickness 0.1524)
				)
				(justify mirror)
			)
		)
		(property "Device Type" "C603H36"
			(at 0 -4.3434 270)
			(unlocked yes)
			(layer "B.Fab")
			(hide yes)
			(effects
				(font
					(size 1.016 1.016)
					(thickness 0.1524)
				)
				(justify mirror)
			)
		)
		(duplicate_pad_numbers_are_jumpers no)
		(fp_line
			(start -0.508 0)
			(end 0.508 0)
			(stroke
				(width 0.2032)
				(type default)
			)
			(layer "B.SilkS")
		)
		(fp_rect
			(start 0.5842 1.3335)
			(end -0.5842 -1.3335)
			(stroke
				(width 0)
				(type default)
			)
			(fill no)
			(layer "B.CrtYd")
		)
		(fp_rect
			(start 0.5842 1.3335)
			(end -0.5842 -1.3335)
			(stroke
				(width 0)
				(type default)
			)
			(fill no)
			(layer "B.Fab")
		)
		(pad "1" smd custom
			(at 0 -0.762 90)
			(size 0.2159 0.2159)
			(layers "B.Cu" "B.Mask" "B.Paste")
			(net "P5V_VBST_RC")
			(options
				(clearance outline)
				(anchor circle)
			)
			(primitives
				(gr_poly
					(pts
						(arc
							(start -0.3302 0.4318)
							(mid -0.402042 0.402042)
							(end -0.4318 0.3302)
						)
						(arc
							(start -0.4318 -0.3302)
							(mid -0.402042 -0.402042)
							(end -0.3302 -0.4318)
						)
						(arc
							(start 0.3302 -0.4318)
							(mid 0.402042 -0.402042)
							(end 0.4318 -0.3302)
						)
						(arc
							(start 0.4318 0.3302)
							(mid 0.402042 0.402042)
							(end 0.3302 0.4318)
						)
					)
					(width 0)
					(fill yes)
				)
			)
		)
		(pad "2" smd custom
			(at 0 0.762 90)
			(size 0.2159 0.2159)
			(layers "B.Cu" "B.Mask" "B.Paste")
			(net "P5V_LL")
			(options
				(clearance outline)
				(anchor circle)
			)
			(primitives
				(gr_poly
					(pts
						(arc
							(start -0.3302 0.4318)
							(mid -0.402042 0.402042)
							(end -0.4318 0.3302)
						)
						(arc
							(start -0.4318 -0.3302)
							(mid -0.402042 -0.402042)
							(end -0.3302 -0.4318)
						)
						(arc
							(start 0.3302 -0.4318)
							(mid 0.402042 -0.402042)
							(end 0.4318 -0.3302)
						)
						(arc
							(start 0.4318 0.3302)
							(mid 0.402042 0.402042)
							(end 0.3302 0.4318)
						)
					)
					(width 0)
					(fill yes)
				)
			)
		)
	)
	(footprint ""
		(layer "B.Cu")
		(at 88.6968 -161.2646 180)
		(property "Reference" "C15"
			(at 0 0 0)
			(layer "B.SilkS")
			(hide yes)
			(effects
				(font
					(size 1.27 1.27)
				)
				(justify mirror)
			)
		)
		(property "Value" "SC1U16V3KX-5GP"
			(at 0 -2.8194 180)
			(unlocked yes)
			(layer "B.Fab")
			(hide yes)
			(effects
				(font
					(size 1.016 1.016)
					(thickness 0.1524)
				)
				(justify mirror)
			)
		)
		(property "Device Type" "C603H36"
			(at 0 -4.3434 180)
			(unlocked yes)
			(layer "B.Fab")
			(hide yes)
			(effects
				(font
					(size 1.016 1.016)
					(thickness 0.1524)
				)
				(justify mirror)
			)
		)
		(duplicate_pad_numbers_are_jumpers no)
		(fp_line
			(start -0.508 0)
			(end 0.508 0)
			(stroke
				(width 0.2032)
				(type default)
			)
			(layer "B.SilkS")
		)
		(fp_rect
			(start 0.5842 1.3335)
			(end -0.5842 -1.3335)
			(stroke
				(width 0)
				(type default)
			)
			(fill no)
			(layer "B.CrtYd")
		)
		(fp_rect
			(start 0.5842 1.3335)
			(end -0.5842 -1.3335)
			(stroke
				(width 0)
				(type default)
			)
			(fill no)
			(layer "B.Fab")
		)
		(pad "1" smd custom
			(at 0 -0.762)
			(size 0.2159 0.2159)
			(layers "B.Cu" "B.Mask" "B.Paste")
			(net "P3V3_STBY")
			(options
				(clearance outline)
				(anchor circle)
			)
			(primitives
				(gr_poly
					(pts
						(arc
							(start -0.3302 0.4318)
							(mid -0.402042 0.402042)
							(end -0.4318 0.3302)
						)
						(arc
							(start -0.4318 -0.3302)
							(mid -0.402042 -0.402042)
							(end -0.3302 -0.4318)
						)
						(arc
							(start 0.3302 -0.4318)
							(mid 0.402042 -0.402042)
							(end 0.4318 -0.3302)
						)
						(arc
							(start 0.4318 0.3302)
							(mid 0.402042 0.402042)
							(end 0.3302 0.4318)
						)
					)
					(width 0)
					(fill yes)
				)
			)
		)
		(pad "2" smd custom
			(at 0 0.762)
			(size 0.2159 0.2159)
			(layers "B.Cu" "B.Mask" "B.Paste")
			(net "GND")
			(options
				(clearance outline)
				(anchor circle)
			)
			(primitives
				(gr_poly
					(pts
						(arc
							(start -0.3302 0.4318)
							(mid -0.402042 0.402042)
							(end -0.4318 0.3302)
						)
						(arc
							(start -0.4318 -0.3302)
							(mid -0.402042 -0.402042)
							(end -0.3302 -0.4318)
						)
						(arc
							(start 0.3302 -0.4318)
							(mid 0.402042 -0.402042)
							(end 0.4318 -0.3302)
						)
						(arc
							(start 0.4318 0.3302)
							(mid 0.402042 0.402042)
							(end 0.3302 0.4318)
						)
					)
					(width 0)
					(fill yes)
				)
			)
		)
	)
	(footprint ""
		(layer "B.Cu")
		(at 67.7672 -145.6436 180)
		(property "Reference" "R159"
			(at 0 0 0)
			(layer "B.SilkS")
			(hide yes)
			(effects
				(font
					(size 1.27 1.27)
				)
				(justify mirror)
			)
		)
		(property "Value" "0R2J-2-GP"
			(at -0.064008 -3.993896 180)
			(unlocked yes)
			(layer "B.Fab")
			(hide yes)
			(effects
				(font
					(size 1.016 1.016)
					(thickness 0.1524)
				)
				(justify mirror)
			)
		)
		(property "Device Type" "R402H16"
			(at -0.064008 -5.517896 180)
			(unlocked yes)
			(layer "B.Fab")
			(hide yes)
			(effects
				(font
					(size 1.016 1.016)
					(thickness 0.1524)
				)
				(justify mirror)
			)
		)
		(duplicate_pad_numbers_are_jumpers no)
		(fp_line
			(start 0.508 -0.9398)
			(end 0.508 0.9398)
			(stroke
				(width 0.1524)
				(type default)
			)
			(layer "B.SilkS")
		)
		(fp_line
			(start -0.508 -0.9398)
			(end 0.508 -0.9398)
			(stroke
				(width 0.1524)
				(type default)
			)
			(layer "B.SilkS")
		)
		(fp_rect
			(start 0.508 0.9398)
			(end -0.508 -0.9398)
			(stroke
				(width 0)
				(type default)
			)
			(fill no)
			(layer "B.CrtYd")
		)
		(fp_rect
			(start 0.508 0.9398)
			(end -0.508 -0.9398)
			(stroke
				(width 0)
				(type default)
			)
			(fill no)
			(layer "B.Fab")
		)
		(pad "1" smd custom
			(at 0 -0.4445)
			(size 0.1397 0.1397)
			(layers "B.Cu" "B.Mask" "B.Paste")
			(net "BMC_SMB12_CLK")
			(options
				(clearance outline)
				(anchor circle)
			)
			(primitives
				(gr_poly
					(pts
						(arc
							(start -0.1778 0.2794)
							(mid -0.249642 0.249642)
							(end -0.2794 0.1778)
						)
						(arc
							(start -0.2794 -0.1778)
							(mid -0.249642 -0.249642)
							(end -0.1778 -0.2794)
						)
						(arc
							(start 0.1778 -0.2794)
							(mid 0.249642 -0.249642)
							(end 0.2794 -0.1778)
						)
						(arc
							(start 0.2794 0.1778)
							(mid 0.249642 0.249642)
							(end 0.1778 0.2794)
						)
					)
					(width 0)
					(fill yes)
				)
			)
		)
		(pad "2" smd custom
			(at 0 0.4445)
			(size 0.1397 0.1397)
			(layers "B.Cu" "B.Mask" "B.Paste")
			(net "I2C_DEBUG_SCL_L")
			(options
				(clearance outline)
				(anchor circle)
			)
			(primitives
				(gr_poly
					(pts
						(arc
							(start -0.1778 0.2794)
							(mid -0.249642 0.249642)
							(end -0.2794 0.1778)
						)
						(arc
							(start -0.2794 -0.1778)
							(mid -0.249642 -0.249642)
							(end -0.1778 -0.2794)
						)
						(arc
							(start 0.1778 -0.2794)
							(mid 0.249642 -0.249642)
							(end 0.2794 -0.1778)
						)
						(arc
							(start 0.2794 0.1778)
							(mid 0.249642 0.249642)
							(end 0.1778 0.2794)
						)
					)
					(width 0)
					(fill yes)
				)
			)
		)
	)
	(footprint ""
		(layer "B.Cu")
		(at 179.577238 -71.92137)
		(property "Reference" "TP114"
			(at 0 0 0)
			(layer "B.SilkS")
			(hide yes)
			(effects
				(font
					(size 1.27 1.27)
				)
				(justify mirror)
			)
		)
		(property "Value" "TPAD28-2-GP"
			(at 0.0127 -1.6637 0)
			(unlocked yes)
			(layer "B.Fab")
			(hide yes)
			(effects
				(font
					(size 1.016 1.016)
					(thickness 0.1524)
				)
				(justify mirror)
			)
		)
		(property "Device Type" "TPAD28"
			(at 0.0127 -3.1877 0)
			(unlocked yes)
			(layer "B.Fab")
			(hide yes)
			(effects
				(font
					(size 1.016 1.016)
					(thickness 0.1524)
				)
				(justify mirror)
			)
		)
		(duplicate_pad_numbers_are_jumpers no)
		(fp_poly
			(pts
				(arc
					(start 0.3556 0)
					(mid -0.3556 0)
					(end 0.3556 0)
				)
			)
			(stroke
				(width 0)
				(type default)
			)
			(fill no)
			(layer "B.CrtYd")
		)
		(fp_poly
			(pts
				(arc
					(start 0.6096 0)
					(mid -0.6096 0)
					(end 0.6096 0)
				)
			)
			(stroke
				(width 0)
				(type default)
			)
			(fill no)
			(layer "B.Fab")
		)
		(pad "1" smd circle
			(at 0 0 180)
			(size 0.7112 0.7112)
			(layers "B.Cu" "B.Mask" "B.Paste")
			(net "IOC_GPIO_27")
		)
	)
	(footprint ""
		(layer "B.Cu")
		(at 89.52992 -149.317456)
		(property "Reference" "R40"
			(at 0 0 0)
			(layer "B.SilkS")
			(hide yes)
			(effects
				(font
					(size 1.27 1.27)
				)
				(justify mirror)
			)
		)
		(property "Value" "4K7R2F-GP"
			(at -0.064008 -3.993896 0)
			(unlocked yes)
			(layer "B.Fab")
			(hide yes)
			(effects
				(font
					(size 1.016 1.016)
					(thickness 0.1524)
				)
				(justify mirror)
			)
		)
		(property "Device Type" "R402H16"
			(at -0.064008 -5.517896 0)
			(unlocked yes)
			(layer "B.Fab")
			(hide yes)
			(effects
				(font
					(size 1.016 1.016)
					(thickness 0.1524)
				)
				(justify mirror)
			)
		)
		(duplicate_pad_numbers_are_jumpers no)
		(fp_line
			(start -0.508 -0.9398)
			(end 0.508 -0.9398)
			(stroke
				(width 0.1524)
				(type default)
			)
			(layer "B.SilkS")
		)
		(fp_line
			(start 0.508 -0.9398)
			(end 0.508 0.9398)
			(stroke
				(width 0.1524)
				(type default)
			)
			(layer "B.SilkS")
		)
		(fp_rect
			(start 0.508 0.9398)
			(end -0.508 -0.9398)
			(stroke
				(width 0)
				(type default)
			)
			(fill no)
			(layer "B.CrtYd")
		)
		(fp_rect
			(start 0.508 0.9398)
			(end -0.508 -0.9398)
			(stroke
				(width 0)
				(type default)
			)
			(fill no)
			(layer "B.Fab")
		)
		(pad "1" smd custom
			(at 0 -0.4445 180)
			(size 0.1397 0.1397)
			(layers "B.Cu" "B.Mask" "B.Paste")
			(net "USB_EN_1")
			(options
				(clearance outline)
				(anchor circle)
			)
			(primitives
				(gr_poly
					(pts
						(arc
							(start -0.1778 0.2794)
							(mid -0.249642 0.249642)
							(end -0.2794 0.1778)
						)
						(arc
							(start -0.2794 -0.1778)
							(mid -0.249642 -0.249642)
							(end -0.1778 -0.2794)
						)
						(arc
							(start 0.1778 -0.2794)
							(mid 0.249642 -0.249642)
							(end 0.2794 -0.1778)
						)
						(arc
							(start 0.2794 0.1778)
							(mid 0.249642 0.249642)
							(end 0.1778 0.2794)
						)
					)
					(width 0)
					(fill yes)
				)
			)
		)
		(pad "2" smd custom
			(at 0 0.4445 180)
			(size 0.1397 0.1397)
			(layers "B.Cu" "B.Mask" "B.Paste")
			(net "GND")
			(options
				(clearance outline)
				(anchor circle)
			)
			(primitives
				(gr_poly
					(pts
						(arc
							(start -0.1778 0.2794)
							(mid -0.249642 0.249642)
							(end -0.2794 0.1778)
						)
						(arc
							(start -0.2794 -0.1778)
							(mid -0.249642 -0.249642)
							(end -0.1778 -0.2794)
						)
						(arc
							(start 0.1778 -0.2794)
							(mid 0.249642 -0.249642)
							(end 0.2794 -0.1778)
						)
						(arc
							(start 0.2794 0.1778)
							(mid 0.249642 0.249642)
							(end 0.1778 0.2794)
						)
					)
					(width 0)
					(fill yes)
				)
			)
		)
	)
	(footprint ""
		(layer "B.Cu")
		(at 170.2308 -51.2064 180)
		(property "Reference" "R678"
			(at 0 0 0)
			(layer "B.SilkS")
			(hide yes)
			(effects
				(font
					(size 1.27 1.27)
				)
				(justify mirror)
			)
		)
		(property "Value" "10KR2F-2-GP"
			(at -0.064008 -3.993896 180)
			(unlocked yes)
			(layer "B.Fab")
			(hide yes)
			(effects
				(font
					(size 1.016 1.016)
					(thickness 0.1524)
				)
				(justify mirror)
			)
		)
		(property "Device Type" "R402H16"
			(at -0.064008 -5.517896 180)
			(unlocked yes)
			(layer "B.Fab")
			(hide yes)
			(effects
				(font
					(size 1.016 1.016)
					(thickness 0.1524)
				)
				(justify mirror)
			)
		)
		(duplicate_pad_numbers_are_jumpers no)
		(fp_line
			(start 0.508 -0.9398)
			(end 0.508 0.9398)
			(stroke
				(width 0.1524)
				(type default)
			)
			(layer "B.SilkS")
		)
		(fp_line
			(start -0.508 -0.9398)
			(end 0.508 -0.9398)
			(stroke
				(width 0.1524)
				(type default)
			)
			(layer "B.SilkS")
		)
		(fp_rect
			(start 0.508 0.9398)
			(end -0.508 -0.9398)
			(stroke
				(width 0)
				(type default)
			)
			(fill no)
			(layer "B.CrtYd")
		)
		(fp_rect
			(start 0.508 0.9398)
			(end -0.508 -0.9398)
			(stroke
				(width 0)
				(type default)
			)
			(fill no)
			(layer "B.Fab")
		)
		(pad "1" smd custom
			(at 0 -0.4445)
			(size 0.1397 0.1397)
			(layers "B.Cu" "B.Mask" "B.Paste")
			(net "P1V8")
			(options
				(clearance outline)
				(anchor circle)
			)
			(primitives
				(gr_poly
					(pts
						(arc
							(start -0.1778 0.2794)
							(mid -0.249642 0.249642)
							(end -0.2794 0.1778)
						)
						(arc
							(start -0.2794 -0.1778)
							(mid -0.249642 -0.249642)
							(end -0.1778 -0.2794)
						)
						(arc
							(start 0.1778 -0.2794)
							(mid 0.249642 -0.249642)
							(end 0.2794 -0.1778)
						)
						(arc
							(start 0.2794 0.1778)
							(mid 0.249642 0.249642)
							(end 0.1778 0.2794)
						)
					)
					(width 0)
					(fill yes)
				)
			)
		)
		(pad "2" smd custom
			(at 0 0.4445)
			(size 0.1397 0.1397)
			(layers "B.Cu" "B.Mask" "B.Paste")
			(net "XM_NOR_CS_N")
			(options
				(clearance outline)
				(anchor circle)
			)
			(primitives
				(gr_poly
					(pts
						(arc
							(start -0.1778 0.2794)
							(mid -0.249642 0.249642)
							(end -0.2794 0.1778)
						)
						(arc
							(start -0.2794 -0.1778)
							(mid -0.249642 -0.249642)
							(end -0.1778 -0.2794)
						)
						(arc
							(start 0.1778 -0.2794)
							(mid 0.249642 -0.249642)
							(end 0.2794 -0.1778)
						)
						(arc
							(start 0.2794 0.1778)
							(mid 0.249642 0.249642)
							(end 0.1778 0.2794)
						)
					)
					(width 0)
					(fill yes)
				)
			)
		)
	)
	(footprint ""
		(layer "B.Cu")
		(at 206.4258 -65.4812 -90)
		(property "Reference" "R625"
			(at 0 0 90)
			(layer "B.SilkS")
			(hide yes)
			(effects
				(font
					(size 1.27 1.27)
				)
				(justify mirror)
			)
		)
		(property "Value" "3KR2J-2-GP"
			(at -0.064008 -3.993896 270)
			(unlocked yes)
			(layer "B.Fab")
			(hide yes)
			(effects
				(font
					(size 1.016 1.016)
					(thickness 0.1524)
				)
				(justify mirror)
			)
		)
		(property "Device Type" "R402H16"
			(at -0.064008 -5.517896 270)
			(unlocked yes)
			(layer "B.Fab")
			(hide yes)
			(effects
				(font
					(size 1.016 1.016)
					(thickness 0.1524)
				)
				(justify mirror)
			)
		)
		(duplicate_pad_numbers_are_jumpers no)
		(fp_line
			(start -0.508 -0.9398)
			(end 0.508 -0.9398)
			(stroke
				(width 0.1524)
				(type default)
			)
			(layer "B.SilkS")
		)
		(fp_line
			(start 0.508 -0.9398)
			(end 0.508 0.9398)
			(stroke
				(width 0.1524)
				(type default)
			)
			(layer "B.SilkS")
		)
		(fp_rect
			(start 0.508 0.9398)
			(end -0.508 -0.9398)
			(stroke
				(width 0)
				(type default)
			)
			(fill no)
			(layer "B.CrtYd")
		)
		(fp_rect
			(start 0.508 0.9398)
			(end -0.508 -0.9398)
			(stroke
				(width 0)
				(type default)
			)
			(fill no)
			(layer "B.Fab")
		)
		(pad "1" smd custom
			(at 0 -0.4445 90)
			(size 0.1397 0.1397)
			(layers "B.Cu" "B.Mask" "B.Paste")
			(net "RTRIM")
			(options
				(clearance outline)
				(anchor circle)
			)
			(primitives
				(gr_poly
					(pts
						(arc
							(start -0.1778 0.2794)
							(mid -0.249642 0.249642)
							(end -0.2794 0.1778)
						)
						(arc
							(start -0.2794 -0.1778)
							(mid -0.249642 -0.249642)
							(end -0.1778 -0.2794)
						)
						(arc
							(start 0.1778 -0.2794)
							(mid 0.249642 -0.249642)
							(end 0.2794 -0.1778)
						)
						(arc
							(start 0.2794 0.1778)
							(mid 0.249642 0.249642)
							(end 0.1778 0.2794)
						)
					)
					(width 0)
					(fill yes)
				)
			)
		)
		(pad "2" smd custom
			(at 0 0.4445 90)
			(size 0.1397 0.1397)
			(layers "B.Cu" "B.Mask" "B.Paste")
			(net "RTRIM#")
			(options
				(clearance outline)
				(anchor circle)
			)
			(primitives
				(gr_poly
					(pts
						(arc
							(start -0.1778 0.2794)
							(mid -0.249642 0.249642)
							(end -0.2794 0.1778)
						)
						(arc
							(start -0.2794 -0.1778)
							(mid -0.249642 -0.249642)
							(end -0.1778 -0.2794)
						)
						(arc
							(start 0.1778 -0.2794)
							(mid 0.249642 -0.249642)
							(end 0.2794 -0.1778)
						)
						(arc
							(start 0.2794 0.1778)
							(mid 0.249642 0.249642)
							(end 0.1778 0.2794)
						)
					)
					(width 0)
					(fill yes)
				)
			)
		)
	)
	(footprint ""
		(layer "B.Cu")
		(at 156.206444 -93.286834 -90)
		(property "Reference" "R616"
			(at 0 0 90)
			(layer "B.SilkS")
			(hide yes)
			(effects
				(font
					(size 1.27 1.27)
				)
				(justify mirror)
			)
		)
		(property "Value" "4K7R2F-GP"
			(at -0.064008 -3.993896 270)
			(unlocked yes)
			(layer "B.Fab")
			(hide yes)
			(effects
				(font
					(size 1.016 1.016)
					(thickness 0.1524)
				)
				(justify mirror)
			)
		)
		(property "Device Type" "R402H16"
			(at -0.064008 -5.517896 270)
			(unlocked yes)
			(layer "B.Fab")
			(hide yes)
			(effects
				(font
					(size 1.016 1.016)
					(thickness 0.1524)
				)
				(justify mirror)
			)
		)
		(duplicate_pad_numbers_are_jumpers no)
		(fp_line
			(start -0.508 -0.9398)
			(end 0.508 -0.9398)
			(stroke
				(width 0.1524)
				(type default)
			)
			(layer "B.SilkS")
		)
		(fp_line
			(start 0.508 -0.9398)
			(end 0.508 0.9398)
			(stroke
				(width 0.1524)
				(type default)
			)
			(layer "B.SilkS")
		)
		(fp_rect
			(start 0.508 0.9398)
			(end -0.508 -0.9398)
			(stroke
				(width 0)
				(type default)
			)
			(fill no)
			(layer "B.CrtYd")
		)
		(fp_rect
			(start 0.508 0.9398)
			(end -0.508 -0.9398)
			(stroke
				(width 0)
				(type default)
			)
			(fill no)
			(layer "B.Fab")
		)
		(pad "1" smd custom
			(at 0 -0.4445 90)
			(size 0.1397 0.1397)
			(layers "B.Cu" "B.Mask" "B.Paste")
			(net "P1V8")
			(options
				(clearance outline)
				(anchor circle)
			)
			(primitives
				(gr_poly
					(pts
						(arc
							(start -0.1778 0.2794)
							(mid -0.249642 0.249642)
							(end -0.2794 0.1778)
						)
						(arc
							(start -0.2794 -0.1778)
							(mid -0.249642 -0.249642)
							(end -0.1778 -0.2794)
						)
						(arc
							(start 0.1778 -0.2794)
							(mid 0.249642 -0.249642)
							(end 0.2794 -0.1778)
						)
						(arc
							(start 0.2794 0.1778)
							(mid 0.249642 0.249642)
							(end 0.1778 0.2794)
						)
					)
					(width 0)
					(fill yes)
				)
			)
		)
		(pad "2" smd custom
			(at 0 0.4445 90)
			(size 0.1397 0.1397)
			(layers "B.Cu" "B.Mask" "B.Paste")
			(net "IOC_RESET#")
			(options
				(clearance outline)
				(anchor circle)
			)
			(primitives
				(gr_poly
					(pts
						(arc
							(start -0.1778 0.2794)
							(mid -0.249642 0.249642)
							(end -0.2794 0.1778)
						)
						(arc
							(start -0.2794 -0.1778)
							(mid -0.249642 -0.249642)
							(end -0.1778 -0.2794)
						)
						(arc
							(start 0.1778 -0.2794)
							(mid 0.249642 -0.249642)
							(end 0.2794 -0.1778)
						)
						(arc
							(start 0.2794 0.1778)
							(mid 0.249642 0.249642)
							(end 0.1778 0.2794)
						)
					)
					(width 0)
					(fill yes)
				)
			)
		)
	)
	(footprint ""
		(layer "B.Cu")
		(at 197.5612 -49.784 -90)
		(property "Reference" "C347"
			(at 0 0 90)
			(layer "B.SilkS")
			(hide yes)
			(effects
				(font
					(size 1.27 1.27)
				)
				(justify mirror)
			)
		)
		(property "Value" "SC10U6D3V5KX-4GP"
			(at 0.0762 -6.1214 270)
			(unlocked yes)
			(layer "B.Fab")
			(hide yes)
			(effects
				(font
					(size 1.016 1.016)
					(thickness 0.1524)
				)
				(justify mirror)
			)
		)
		(property "Device Type" "C805H58"
			(at 0.0762 -8.1534 270)
			(unlocked yes)
			(layer "B.Fab")
			(hide yes)
			(effects
				(font
					(size 1.016 1.016)
					(thickness 0.1524)
				)
				(justify mirror)
			)
		)
		(duplicate_pad_numbers_are_jumpers no)
		(fp_line
			(start -0.635 0)
			(end 0.635 0)
			(stroke
				(width 0.508)
				(type default)
			)
			(layer "B.SilkS")
		)
		(fp_rect
			(start 0.9652 1.778)
			(end -0.9652 -1.778)
			(stroke
				(width 0)
				(type default)
			)
			(fill no)
			(layer "B.CrtYd")
		)
		(fp_poly
			(pts
				(xy 0.9652 -1.778) (xy -0.9652 -1.778) (xy -0.9652 1.778) (xy 0.9652 1.778)
			)
			(stroke
				(width 0)
				(type default)
			)
			(fill no)
			(layer "B.Fab")
		)
		(pad "1" smd rect
			(at 0 -0.9652 90)
			(size 1.397 1.143)
			(layers "B.Cu" "B.Mask" "B.Paste")
			(net "VDDA_SAS_REF_CLK")
		)
		(pad "2" smd rect
			(at 0 0.9652 90)
			(size 1.397 1.143)
			(layers "B.Cu" "B.Mask" "B.Paste")
			(net "GND")
		)
	)
	(footprint ""
		(layer "B.Cu")
		(at 47.5742 -128.1938)
		(property "Reference" "R152"
			(at 0 0 0)
			(layer "B.SilkS")
			(hide yes)
			(effects
				(font
					(size 1.27 1.27)
				)
				(justify mirror)
			)
		)
		(property "Value" "0R2J-2-GP"
			(at -0.064008 -3.993896 0)
			(unlocked yes)
			(layer "B.Fab")
			(hide yes)
			(effects
				(font
					(size 1.016 1.016)
					(thickness 0.1524)
				)
				(justify mirror)
			)
		)
		(property "Device Type" "R402H16"
			(at -0.064008 -5.517896 0)
			(unlocked yes)
			(layer "B.Fab")
			(hide yes)
			(effects
				(font
					(size 1.016 1.016)
					(thickness 0.1524)
				)
				(justify mirror)
			)
		)
		(duplicate_pad_numbers_are_jumpers no)
		(fp_line
			(start -0.508 -0.9398)
			(end 0.508 -0.9398)
			(stroke
				(width 0.1524)
				(type default)
			)
			(layer "B.SilkS")
		)
		(fp_line
			(start 0.508 -0.9398)
			(end 0.508 0.9398)
			(stroke
				(width 0.1524)
				(type default)
			)
			(layer "B.SilkS")
		)
		(fp_rect
			(start 0.508 0.9398)
			(end -0.508 -0.9398)
			(stroke
				(width 0)
				(type default)
			)
			(fill no)
			(layer "B.CrtYd")
		)
		(fp_rect
			(start 0.508 0.9398)
			(end -0.508 -0.9398)
			(stroke
				(width 0)
				(type default)
			)
			(fill no)
			(layer "B.Fab")
		)
		(pad "1" smd custom
			(at 0 -0.4445 180)
			(size 0.1397 0.1397)
			(layers "B.Cu" "B.Mask" "B.Paste")
			(net "I2C_IOM_SCL")
			(options
				(clearance outline)
				(anchor circle)
			)
			(primitives
				(gr_poly
					(pts
						(arc
							(start -0.1778 0.2794)
							(mid -0.249642 0.249642)
							(end -0.2794 0.1778)
						)
						(arc
							(start -0.2794 -0.1778)
							(mid -0.249642 -0.249642)
							(end -0.1778 -0.2794)
						)
						(arc
							(start 0.1778 -0.2794)
							(mid 0.249642 -0.249642)
							(end 0.2794 -0.1778)
						)
						(arc
							(start 0.2794 0.1778)
							(mid 0.249642 0.249642)
							(end 0.1778 0.2794)
						)
					)
					(width 0)
					(fill yes)
				)
			)
		)
		(pad "2" smd custom
			(at 0 0.4445 180)
			(size 0.1397 0.1397)
			(layers "B.Cu" "B.Mask" "B.Paste")
			(net "BMC_SMB1_CLK")
			(options
				(clearance outline)
				(anchor circle)
			)
			(primitives
				(gr_poly
					(pts
						(arc
							(start -0.1778 0.2794)
							(mid -0.249642 0.249642)
							(end -0.2794 0.1778)
						)
						(arc
							(start -0.2794 -0.1778)
							(mid -0.249642 -0.249642)
							(end -0.1778 -0.2794)
						)
						(arc
							(start 0.1778 -0.2794)
							(mid 0.249642 -0.249642)
							(end 0.2794 -0.1778)
						)
						(arc
							(start 0.2794 0.1778)
							(mid 0.249642 0.249642)
							(end 0.1778 0.2794)
						)
					)
					(width 0)
					(fill yes)
				)
			)
		)
	)
	(footprint ""
		(layer "B.Cu")
		(at 195.60286 -56.66232)
		(property "Reference" "C386"
			(at 0 0 0)
			(layer "B.SilkS")
			(hide yes)
			(effects
				(font
					(size 1.27 1.27)
				)
				(justify mirror)
			)
		)
		(property "Value" "SC10U6D3V5KX-4GP"
			(at 0.0762 -6.1214 0)
			(unlocked yes)
			(layer "B.Fab")
			(hide yes)
			(effects
				(font
					(size 1.016 1.016)
					(thickness 0.1524)
				)
				(justify mirror)
			)
		)
		(property "Device Type" "C805H58"
			(at 0.0762 -8.1534 0)
			(unlocked yes)
			(layer "B.Fab")
			(hide yes)
			(effects
				(font
					(size 1.016 1.016)
					(thickness 0.1524)
				)
				(justify mirror)
			)
		)
		(duplicate_pad_numbers_are_jumpers no)
		(fp_line
			(start -0.635 0)
			(end 0.635 0)
			(stroke
				(width 0.508)
				(type default)
			)
			(layer "B.SilkS")
		)
		(fp_rect
			(start 0.9652 1.778)
			(end -0.9652 -1.778)
			(stroke
				(width 0)
				(type default)
			)
			(fill no)
			(layer "B.CrtYd")
		)
		(fp_poly
			(pts
				(xy 0.9652 -1.778) (xy -0.9652 -1.778) (xy -0.9652 1.778) (xy 0.9652 1.778)
			)
			(stroke
				(width 0)
				(type default)
			)
			(fill no)
			(layer "B.Fab")
		)
		(pad "1" smd rect
			(at 0 -0.9652 180)
			(size 1.397 1.143)
			(layers "B.Cu" "B.Mask" "B.Paste")
			(net "P0V975")
		)
		(pad "2" smd rect
			(at 0 0.9652 180)
			(size 1.397 1.143)
			(layers "B.Cu" "B.Mask" "B.Paste")
			(net "GND")
		)
	)
	(footprint ""
		(layer "B.Cu")
		(at 200.279 -71.247 -90)
		(property "Reference" "C355"
			(at 0 0 90)
			(layer "B.SilkS")
			(hide yes)
			(effects
				(font
					(size 1.27 1.27)
				)
				(justify mirror)
			)
		)
		(property "Value" "SCD1U6D3V1KX-GP"
			(at 2.8321 -1.7399 270)
			(unlocked yes)
			(layer "B.Fab")
			(hide yes)
			(effects
				(font
					(size 1.016 1.016)
					(thickness 0.1524)
				)
				(justify mirror)
			)
		)
		(property "Device Type" "C0201H13"
			(at 2.8321 -3.2639 270)
			(unlocked yes)
			(layer "B.Fab")
			(hide yes)
			(effects
				(font
					(size 1.016 1.016)
					(thickness 0.1524)
				)
				(justify mirror)
			)
		)
		(duplicate_pad_numbers_are_jumpers no)
		(fp_rect
			(start 0.2794 0.6477)
			(end -0.2794 -0.6477)
			(stroke
				(width 0)
				(type default)
			)
			(fill no)
			(layer "B.CrtYd")
		)
		(fp_rect
			(start 0.2794 0.6477)
			(end -0.2794 -0.6477)
			(stroke
				(width 0)
				(type default)
			)
			(fill no)
			(layer "B.Fab")
		)
		(pad "1" smd custom
			(at 0 -0.2794 90)
			(size 0.0762 0.0762)
			(layers "B.Cu" "B.Mask" "B.Paste")
			(net "SAS0_VDDH")
			(options
				(clearance outline)
				(anchor circle)
			)
			(primitives
				(gr_poly
					(pts
						(arc
							(start 0.1524 0.127)
							(mid 0.137521 0.162921)
							(end 0.1016 0.1778)
						)
						(arc
							(start -0.1016 0.1778)
							(mid -0.137521 0.162921)
							(end -0.1524 0.127)
						)
						(arc
							(start -0.1524 -0.127)
							(mid -0.137521 -0.162921)
							(end -0.1016 -0.1778)
						)
						(arc
							(start 0.1016 -0.1778)
							(mid 0.137521 -0.162921)
							(end 0.1524 -0.127)
						)
					)
					(width 0)
					(fill yes)
				)
			)
		)
		(pad "2" smd custom
			(at 0 0.2794 90)
			(size 0.0762 0.0762)
			(layers "B.Cu" "B.Mask" "B.Paste")
			(net "GND")
			(options
				(clearance outline)
				(anchor circle)
			)
			(primitives
				(gr_poly
					(pts
						(arc
							(start 0.1524 0.127)
							(mid 0.137521 0.162921)
							(end 0.1016 0.1778)
						)
						(arc
							(start -0.1016 0.1778)
							(mid -0.137521 0.162921)
							(end -0.1524 0.127)
						)
						(arc
							(start -0.1524 -0.127)
							(mid -0.137521 -0.162921)
							(end -0.1016 -0.1778)
						)
						(arc
							(start 0.1016 -0.1778)
							(mid 0.137521 -0.162921)
							(end 0.1524 -0.127)
						)
					)
					(width 0)
					(fill yes)
				)
			)
		)
	)
	(footprint ""
		(layer "B.Cu")
		(at 17.749012 -129.051558 180)
		(property "Reference" "R240"
			(at 0 0 0)
			(layer "B.SilkS")
			(hide yes)
			(effects
				(font
					(size 1.27 1.27)
				)
				(justify mirror)
			)
		)
		(property "Value" "120R2F-GP"
			(at -0.064008 -3.993896 180)
			(unlocked yes)
			(layer "B.Fab")
			(hide yes)
			(effects
				(font
					(size 1.016 1.016)
					(thickness 0.1524)
				)
				(justify mirror)
			)
		)
		(property "Device Type" "R402H16"
			(at -0.064008 -5.517896 180)
			(unlocked yes)
			(layer "B.Fab")
			(hide yes)
			(effects
				(font
					(size 1.016 1.016)
					(thickness 0.1524)
				)
				(justify mirror)
			)
		)
		(duplicate_pad_numbers_are_jumpers no)
		(fp_line
			(start 0.508 -0.9398)
			(end 0.508 0.9398)
			(stroke
				(width 0.1524)
				(type default)
			)
			(layer "B.SilkS")
		)
		(fp_line
			(start -0.508 -0.9398)
			(end 0.508 -0.9398)
			(stroke
				(width 0.1524)
				(type default)
			)
			(layer "B.SilkS")
		)
		(fp_rect
			(start 0.508 0.9398)
			(end -0.508 -0.9398)
			(stroke
				(width 0)
				(type default)
			)
			(fill no)
			(layer "B.CrtYd")
		)
		(fp_rect
			(start 0.508 0.9398)
			(end -0.508 -0.9398)
			(stroke
				(width 0)
				(type default)
			)
			(fill no)
			(layer "B.Fab")
		)
		(pad "1" smd custom
			(at 0 -0.4445)
			(size 0.1397 0.1397)
			(layers "B.Cu" "B.Mask" "B.Paste")
			(net "GND")
			(options
				(clearance outline)
				(anchor circle)
			)
			(primitives
				(gr_poly
					(pts
						(arc
							(start -0.1778 0.2794)
							(mid -0.249642 0.249642)
							(end -0.2794 0.1778)
						)
						(arc
							(start -0.2794 -0.1778)
							(mid -0.249642 -0.249642)
							(end -0.1778 -0.2794)
						)
						(arc
							(start 0.1778 -0.2794)
							(mid 0.249642 -0.249642)
							(end 0.2794 -0.1778)
						)
						(arc
							(start 0.2794 0.1778)
							(mid 0.249642 0.249642)
							(end 0.1778 0.2794)
						)
					)
					(width 0)
					(fill yes)
				)
			)
		)
		(pad "2" smd custom
			(at 0 0.4445)
			(size 0.1397 0.1397)
			(layers "B.Cu" "B.Mask" "B.Paste")
			(net "MEMA_3")
			(options
				(clearance outline)
				(anchor circle)
			)
			(primitives
				(gr_poly
					(pts
						(arc
							(start -0.1778 0.2794)
							(mid -0.249642 0.249642)
							(end -0.2794 0.1778)
						)
						(arc
							(start -0.2794 -0.1778)
							(mid -0.249642 -0.249642)
							(end -0.1778 -0.2794)
						)
						(arc
							(start 0.1778 -0.2794)
							(mid 0.249642 -0.249642)
							(end 0.2794 -0.1778)
						)
						(arc
							(start 0.2794 0.1778)
							(mid 0.249642 0.249642)
							(end 0.1778 0.2794)
						)
					)
					(width 0)
					(fill yes)
				)
			)
		)
	)
	(footprint ""
		(layer "B.Cu")
		(at 186.358784 -76.451714)
		(property "Reference" "TP86"
			(at 0 0 0)
			(layer "B.SilkS")
			(hide yes)
			(effects
				(font
					(size 1.27 1.27)
				)
				(justify mirror)
			)
		)
		(property "Value" "TPAD28-2-GP"
			(at 0.0127 -1.6637 0)
			(unlocked yes)
			(layer "B.Fab")
			(hide yes)
			(effects
				(font
					(size 1.016 1.016)
					(thickness 0.1524)
				)
				(justify mirror)
			)
		)
		(property "Device Type" "TPAD28"
			(at 0.0127 -3.1877 0)
			(unlocked yes)
			(layer "B.Fab")
			(hide yes)
			(effects
				(font
					(size 1.016 1.016)
					(thickness 0.1524)
				)
				(justify mirror)
			)
		)
		(duplicate_pad_numbers_are_jumpers no)
		(fp_poly
			(pts
				(arc
					(start 0.3556 0)
					(mid -0.3556 0)
					(end 0.3556 0)
				)
			)
			(stroke
				(width 0)
				(type default)
			)
			(fill no)
			(layer "B.CrtYd")
		)
		(fp_poly
			(pts
				(arc
					(start 0.6096 0)
					(mid -0.6096 0)
					(end 0.6096 0)
				)
			)
			(stroke
				(width 0)
				(type default)
			)
			(fill no)
			(layer "B.Fab")
		)
		(pad "1" smd circle
			(at 0 0 180)
			(size 0.7112 0.7112)
			(layers "B.Cu" "B.Mask" "B.Paste")
			(net "IOC_GPIO_5")
		)
	)
	(footprint ""
		(layer "B.Cu")
		(at 16.294354 -131.007358 180)
		(property "Reference" "R259"
			(at 0 0 0)
			(layer "B.SilkS")
			(hide yes)
			(effects
				(font
					(size 1.27 1.27)
				)
				(justify mirror)
			)
		)
		(property "Value" "120R2F-GP"
			(at -0.064008 -3.993896 180)
			(unlocked yes)
			(layer "B.Fab")
			(hide yes)
			(effects
				(font
					(size 1.016 1.016)
					(thickness 0.1524)
				)
				(justify mirror)
			)
		)
		(property "Device Type" "R402H16"
			(at -0.064008 -5.517896 180)
			(unlocked yes)
			(layer "B.Fab")
			(hide yes)
			(effects
				(font
					(size 1.016 1.016)
					(thickness 0.1524)
				)
				(justify mirror)
			)
		)
		(duplicate_pad_numbers_are_jumpers no)
		(fp_line
			(start 0.508 -0.9398)
			(end 0.508 0.9398)
			(stroke
				(width 0.1524)
				(type default)
			)
			(layer "B.SilkS")
		)
		(fp_line
			(start -0.508 -0.9398)
			(end 0.508 -0.9398)
			(stroke
				(width 0.1524)
				(type default)
			)
			(layer "B.SilkS")
		)
		(fp_rect
			(start 0.508 0.9398)
			(end -0.508 -0.9398)
			(stroke
				(width 0)
				(type default)
			)
			(fill no)
			(layer "B.CrtYd")
		)
		(fp_rect
			(start 0.508 0.9398)
			(end -0.508 -0.9398)
			(stroke
				(width 0)
				(type default)
			)
			(fill no)
			(layer "B.Fab")
		)
		(pad "1" smd custom
			(at 0 -0.4445)
			(size 0.1397 0.1397)
			(layers "B.Cu" "B.Mask" "B.Paste")
			(net "MEMA_12")
			(options
				(clearance outline)
				(anchor circle)
			)
			(primitives
				(gr_poly
					(pts
						(arc
							(start -0.1778 0.2794)
							(mid -0.249642 0.249642)
							(end -0.2794 0.1778)
						)
						(arc
							(start -0.2794 -0.1778)
							(mid -0.249642 -0.249642)
							(end -0.1778 -0.2794)
						)
						(arc
							(start 0.1778 -0.2794)
							(mid 0.249642 -0.249642)
							(end 0.2794 -0.1778)
						)
						(arc
							(start 0.2794 0.1778)
							(mid 0.249642 0.249642)
							(end 0.1778 0.2794)
						)
					)
					(width 0)
					(fill yes)
				)
			)
		)
		(pad "2" smd custom
			(at 0 0.4445)
			(size 0.1397 0.1397)
			(layers "B.Cu" "B.Mask" "B.Paste")
			(net "P1V2_STBY")
			(options
				(clearance outline)
				(anchor circle)
			)
			(primitives
				(gr_poly
					(pts
						(arc
							(start -0.1778 0.2794)
							(mid -0.249642 0.249642)
							(end -0.2794 0.1778)
						)
						(arc
							(start -0.2794 -0.1778)
							(mid -0.249642 -0.249642)
							(end -0.1778 -0.2794)
						)
						(arc
							(start 0.1778 -0.2794)
							(mid 0.249642 -0.249642)
							(end 0.2794 -0.1778)
						)
						(arc
							(start 0.2794 0.1778)
							(mid 0.249642 0.249642)
							(end 0.1778 0.2794)
						)
					)
					(width 0)
					(fill yes)
				)
			)
		)
	)
	(footprint ""
		(layer "B.Cu")
		(at 165.72611 -76.267564)
		(property "Reference" "R677"
			(at 0 0 0)
			(layer "B.SilkS")
			(hide yes)
			(effects
				(font
					(size 1.27 1.27)
				)
				(justify mirror)
			)
		)
		(property "Value" "10KR2F-2-GP"
			(at -0.064008 -3.993896 0)
			(unlocked yes)
			(layer "B.Fab")
			(hide yes)
			(effects
				(font
					(size 1.016 1.016)
					(thickness 0.1524)
				)
				(justify mirror)
			)
		)
		(property "Device Type" "R402H16"
			(at -0.064008 -5.517896 0)
			(unlocked yes)
			(layer "B.Fab")
			(hide yes)
			(effects
				(font
					(size 1.016 1.016)
					(thickness 0.1524)
				)
				(justify mirror)
			)
		)
		(duplicate_pad_numbers_are_jumpers no)
		(fp_line
			(start -0.508 -0.9398)
			(end 0.508 -0.9398)
			(stroke
				(width 0.1524)
				(type default)
			)
			(layer "B.SilkS")
		)
		(fp_line
			(start 0.508 -0.9398)
			(end 0.508 0.9398)
			(stroke
				(width 0.1524)
				(type default)
			)
			(layer "B.SilkS")
		)
		(fp_rect
			(start 0.508 0.9398)
			(end -0.508 -0.9398)
			(stroke
				(width 0)
				(type default)
			)
			(fill no)
			(layer "B.CrtYd")
		)
		(fp_rect
			(start 0.508 0.9398)
			(end -0.508 -0.9398)
			(stroke
				(width 0)
				(type default)
			)
			(fill no)
			(layer "B.Fab")
		)
		(pad "1" smd custom
			(at 0 -0.4445 180)
			(size 0.1397 0.1397)
			(layers "B.Cu" "B.Mask" "B.Paste")
			(net "P1V8")
			(options
				(clearance outline)
				(anchor circle)
			)
			(primitives
				(gr_poly
					(pts
						(arc
							(start -0.1778 0.2794)
							(mid -0.249642 0.249642)
							(end -0.2794 0.1778)
						)
						(arc
							(start -0.2794 -0.1778)
							(mid -0.249642 -0.249642)
							(end -0.1778 -0.2794)
						)
						(arc
							(start 0.1778 -0.2794)
							(mid 0.249642 -0.249642)
							(end 0.2794 -0.1778)
						)
						(arc
							(start 0.2794 0.1778)
							(mid 0.249642 0.249642)
							(end 0.1778 0.2794)
						)
					)
					(width 0)
					(fill yes)
				)
			)
		)
		(pad "2" smd custom
			(at 0 0.4445 180)
			(size 0.1397 0.1397)
			(layers "B.Cu" "B.Mask" "B.Paste")
			(net "XM_WE_N")
			(options
				(clearance outline)
				(anchor circle)
			)
			(primitives
				(gr_poly
					(pts
						(arc
							(start -0.1778 0.2794)
							(mid -0.249642 0.249642)
							(end -0.2794 0.1778)
						)
						(arc
							(start -0.2794 -0.1778)
							(mid -0.249642 -0.249642)
							(end -0.1778 -0.2794)
						)
						(arc
							(start 0.1778 -0.2794)
							(mid 0.249642 -0.249642)
							(end 0.2794 -0.1778)
						)
						(arc
							(start 0.2794 0.1778)
							(mid 0.249642 0.249642)
							(end 0.1778 0.2794)
						)
					)
					(width 0)
					(fill yes)
				)
			)
		)
	)
	(footprint ""
		(layer "B.Cu")
		(at 67.973448 -148.287486 -90)
		(property "Reference" "R334"
			(at 0 0 90)
			(layer "B.SilkS")
			(hide yes)
			(effects
				(font
					(size 1.27 1.27)
				)
				(justify mirror)
			)
		)
		(property "Value" "0R2J-2-GP"
			(at -0.064008 -3.993896 270)
			(unlocked yes)
			(layer "B.Fab")
			(hide yes)
			(effects
				(font
					(size 1.016 1.016)
					(thickness 0.1524)
				)
				(justify mirror)
			)
		)
		(property "Device Type" "R402H16"
			(at -0.064008 -5.517896 270)
			(unlocked yes)
			(layer "B.Fab")
			(hide yes)
			(effects
				(font
					(size 1.016 1.016)
					(thickness 0.1524)
				)
				(justify mirror)
			)
		)
		(duplicate_pad_numbers_are_jumpers no)
		(fp_line
			(start -0.508 -0.9398)
			(end 0.508 -0.9398)
			(stroke
				(width 0.1524)
				(type default)
			)
			(layer "B.SilkS")
		)
		(fp_line
			(start 0.508 -0.9398)
			(end 0.508 0.9398)
			(stroke
				(width 0.1524)
				(type default)
			)
			(layer "B.SilkS")
		)
		(fp_rect
			(start 0.508 0.9398)
			(end -0.508 -0.9398)
			(stroke
				(width 0)
				(type default)
			)
			(fill no)
			(layer "B.CrtYd")
		)
		(fp_rect
			(start 0.508 0.9398)
			(end -0.508 -0.9398)
			(stroke
				(width 0)
				(type default)
			)
			(fill no)
			(layer "B.Fab")
		)
		(pad "1" smd custom
			(at 0 -0.4445 90)
			(size 0.1397 0.1397)
			(layers "B.Cu" "B.Mask" "B.Paste")
			(net "NCSI_TXD0")
			(options
				(clearance outline)
				(anchor circle)
			)
			(primitives
				(gr_poly
					(pts
						(arc
							(start -0.1778 0.2794)
							(mid -0.249642 0.249642)
							(end -0.2794 0.1778)
						)
						(arc
							(start -0.2794 -0.1778)
							(mid -0.249642 -0.249642)
							(end -0.1778 -0.2794)
						)
						(arc
							(start 0.1778 -0.2794)
							(mid 0.249642 -0.249642)
							(end 0.2794 -0.1778)
						)
						(arc
							(start 0.2794 0.1778)
							(mid 0.249642 0.249642)
							(end 0.1778 0.2794)
						)
					)
					(width 0)
					(fill yes)
				)
			)
		)
		(pad "2" smd custom
			(at 0 0.4445 90)
			(size 0.1397 0.1397)
			(layers "B.Cu" "B.Mask" "B.Paste")
			(net "NCSI_TXD0_R")
			(options
				(clearance outline)
				(anchor circle)
			)
			(primitives
				(gr_poly
					(pts
						(arc
							(start -0.1778 0.2794)
							(mid -0.249642 0.249642)
							(end -0.2794 0.1778)
						)
						(arc
							(start -0.2794 -0.1778)
							(mid -0.249642 -0.249642)
							(end -0.1778 -0.2794)
						)
						(arc
							(start 0.1778 -0.2794)
							(mid 0.249642 -0.249642)
							(end 0.2794 -0.1778)
						)
						(arc
							(start 0.2794 0.1778)
							(mid 0.249642 0.249642)
							(end 0.1778 0.2794)
						)
					)
					(width 0)
					(fill yes)
				)
			)
		)
	)
	(footprint ""
		(layer "B.Cu")
		(at 202.565 -57.404)
		(property "Reference" "TP117"
			(at 0 0 0)
			(layer "B.SilkS")
			(hide yes)
			(effects
				(font
					(size 1.27 1.27)
				)
				(justify mirror)
			)
		)
		(property "Value" "TPAD28-2-GP"
			(at 0.0127 -1.6637 0)
			(unlocked yes)
			(layer "B.Fab")
			(hide yes)
			(effects
				(font
					(size 1.016 1.016)
					(thickness 0.1524)
				)
				(justify mirror)
			)
		)
		(property "Device Type" "TPAD28"
			(at 0.0127 -3.1877 0)
			(unlocked yes)
			(layer "B.Fab")
			(hide yes)
			(effects
				(font
					(size 1.016 1.016)
					(thickness 0.1524)
				)
				(justify mirror)
			)
		)
		(duplicate_pad_numbers_are_jumpers no)
		(fp_poly
			(pts
				(arc
					(start 0.3556 0)
					(mid -0.3556 0)
					(end 0.3556 0)
				)
			)
			(stroke
				(width 0)
				(type default)
			)
			(fill no)
			(layer "B.CrtYd")
		)
		(fp_poly
			(pts
				(arc
					(start 0.6096 0)
					(mid -0.6096 0)
					(end 0.6096 0)
				)
			)
			(stroke
				(width 0)
				(type default)
			)
			(fill no)
			(layer "B.Fab")
		)
		(pad "1" smd circle
			(at 0 0 180)
			(size 0.7112 0.7112)
			(layers "B.Cu" "B.Mask" "B.Paste")
			(net "SIO_LOAD_0")
		)
	)
	(footprint ""
		(layer "B.Cu")
		(at 191.672718 -81.153 180)
		(property "Reference" "C300"
			(at 0 0 0)
			(layer "B.SilkS")
			(hide yes)
			(effects
				(font
					(size 1.27 1.27)
				)
				(justify mirror)
			)
		)
		(property "Value" "SCD22U10V1KX-GP"
			(at 2.8321 -1.7399 180)
			(unlocked yes)
			(layer "B.Fab")
			(hide yes)
			(effects
				(font
					(size 1.016 1.016)
					(thickness 0.1524)
				)
				(justify mirror)
			)
		)
		(property "Device Type" "C0201H13"
			(at 2.8321 -3.2639 180)
			(unlocked yes)
			(layer "B.Fab")
			(hide yes)
			(effects
				(font
					(size 1.016 1.016)
					(thickness 0.1524)
				)
				(justify mirror)
			)
		)
		(duplicate_pad_numbers_are_jumpers no)
		(fp_rect
			(start 0.2794 0.6477)
			(end -0.2794 -0.6477)
			(stroke
				(width 0)
				(type default)
			)
			(fill no)
			(layer "B.CrtYd")
		)
		(fp_rect
			(start 0.2794 0.6477)
			(end -0.2794 -0.6477)
			(stroke
				(width 0)
				(type default)
			)
			(fill no)
			(layer "B.Fab")
		)
		(pad "1" smd custom
			(at 0 -0.2794)
			(size 0.0762 0.0762)
			(layers "B.Cu" "B.Mask" "B.Paste")
			(net "PCIE_IOM_TO_COMP_13_DN_C")
			(options
				(clearance outline)
				(anchor circle)
			)
			(primitives
				(gr_poly
					(pts
						(arc
							(start 0.1524 0.127)
							(mid 0.137521 0.162921)
							(end 0.1016 0.1778)
						)
						(arc
							(start -0.1016 0.1778)
							(mid -0.137521 0.162921)
							(end -0.1524 0.127)
						)
						(arc
							(start -0.1524 -0.127)
							(mid -0.137521 -0.162921)
							(end -0.1016 -0.1778)
						)
						(arc
							(start 0.1016 -0.1778)
							(mid 0.137521 -0.162921)
							(end 0.1524 -0.127)
						)
					)
					(width 0)
					(fill yes)
				)
			)
		)
		(pad "2" smd custom
			(at 0 0.2794)
			(size 0.0762 0.0762)
			(layers "B.Cu" "B.Mask" "B.Paste")
			(net "PCIE_IOM_TO_COMP_13_DN")
			(options
				(clearance outline)
				(anchor circle)
			)
			(primitives
				(gr_poly
					(pts
						(arc
							(start 0.1524 0.127)
							(mid 0.137521 0.162921)
							(end 0.1016 0.1778)
						)
						(arc
							(start -0.1016 0.1778)
							(mid -0.137521 0.162921)
							(end -0.1524 0.127)
						)
						(arc
							(start -0.1524 -0.127)
							(mid -0.137521 -0.162921)
							(end -0.1016 -0.1778)
						)
						(arc
							(start 0.1016 -0.1778)
							(mid 0.137521 -0.162921)
							(end 0.1524 -0.127)
						)
					)
					(width 0)
					(fill yes)
				)
			)
		)
	)
	(footprint ""
		(layer "B.Cu")
		(at 193.2051 -58.99658)
		(property "Reference" "C388"
			(at 0 0 0)
			(layer "B.SilkS")
			(hide yes)
			(effects
				(font
					(size 1.27 1.27)
				)
				(justify mirror)
			)
		)
		(property "Value" "SC10U6D3V5KX-4GP"
			(at 0.0762 -6.1214 0)
			(unlocked yes)
			(layer "B.Fab")
			(hide yes)
			(effects
				(font
					(size 1.016 1.016)
					(thickness 0.1524)
				)
				(justify mirror)
			)
		)
		(property "Device Type" "C805H58"
			(at 0.0762 -8.1534 0)
			(unlocked yes)
			(layer "B.Fab")
			(hide yes)
			(effects
				(font
					(size 1.016 1.016)
					(thickness 0.1524)
				)
				(justify mirror)
			)
		)
		(duplicate_pad_numbers_are_jumpers no)
		(fp_line
			(start -0.635 0)
			(end 0.635 0)
			(stroke
				(width 0.508)
				(type default)
			)
			(layer "B.SilkS")
		)
		(fp_rect
			(start 0.9652 1.778)
			(end -0.9652 -1.778)
			(stroke
				(width 0)
				(type default)
			)
			(fill no)
			(layer "B.CrtYd")
		)
		(fp_poly
			(pts
				(xy 0.9652 -1.778) (xy -0.9652 -1.778) (xy -0.9652 1.778) (xy 0.9652 1.778)
			)
			(stroke
				(width 0)
				(type default)
			)
			(fill no)
			(layer "B.Fab")
		)
		(pad "1" smd rect
			(at 0 -0.9652 180)
			(size 1.397 1.143)
			(layers "B.Cu" "B.Mask" "B.Paste")
			(net "P0V975")
		)
		(pad "2" smd rect
			(at 0 0.9652 180)
			(size 1.397 1.143)
			(layers "B.Cu" "B.Mask" "B.Paste")
			(net "GND")
		)
	)
	(footprint ""
		(layer "B.Cu")
		(at 169.33799 -38.442138)
		(property "Reference" "C494"
			(at 0 0 0)
			(layer "B.SilkS")
			(hide yes)
			(effects
				(font
					(size 1.27 1.27)
				)
				(justify mirror)
			)
		)
		(property "Value" "SCD01U16V1KX-GP"
			(at 2.8321 -1.7399 0)
			(unlocked yes)
			(layer "B.Fab")
			(hide yes)
			(effects
				(font
					(size 1.016 1.016)
					(thickness 0.1524)
				)
				(justify mirror)
			)
		)
		(property "Device Type" "C0201H13"
			(at 2.8321 -3.2639 0)
			(unlocked yes)
			(layer "B.Fab")
			(hide yes)
			(effects
				(font
					(size 1.016 1.016)
					(thickness 0.1524)
				)
				(justify mirror)
			)
		)
		(duplicate_pad_numbers_are_jumpers no)
		(fp_rect
			(start 0.2794 0.6477)
			(end -0.2794 -0.6477)
			(stroke
				(width 0)
				(type default)
			)
			(fill no)
			(layer "B.CrtYd")
		)
		(fp_rect
			(start 0.2794 0.6477)
			(end -0.2794 -0.6477)
			(stroke
				(width 0)
				(type default)
			)
			(fill no)
			(layer "B.Fab")
		)
		(pad "1" smd custom
			(at 0 -0.2794 180)
			(size 0.0762 0.0762)
			(layers "B.Cu" "B.Mask" "B.Paste")
			(net "PHY_CON_B_TO_IOC_0_DP")
			(options
				(clearance outline)
				(anchor circle)
			)
			(primitives
				(gr_poly
					(pts
						(arc
							(start 0.1524 0.127)
							(mid 0.137521 0.162921)
							(end 0.1016 0.1778)
						)
						(arc
							(start -0.1016 0.1778)
							(mid -0.137521 0.162921)
							(end -0.1524 0.127)
						)
						(arc
							(start -0.1524 -0.127)
							(mid -0.137521 -0.162921)
							(end -0.1016 -0.1778)
						)
						(arc
							(start 0.1016 -0.1778)
							(mid 0.137521 -0.162921)
							(end 0.1524 -0.127)
						)
					)
					(width 0)
					(fill yes)
				)
			)
		)
		(pad "2" smd custom
			(at 0 0.2794 180)
			(size 0.0762 0.0762)
			(layers "B.Cu" "B.Mask" "B.Paste")
			(net "PHY_CON_B_TO_IOC_0_DP_C")
			(options
				(clearance outline)
				(anchor circle)
			)
			(primitives
				(gr_poly
					(pts
						(arc
							(start 0.1524 0.127)
							(mid 0.137521 0.162921)
							(end 0.1016 0.1778)
						)
						(arc
							(start -0.1016 0.1778)
							(mid -0.137521 0.162921)
							(end -0.1524 0.127)
						)
						(arc
							(start -0.1524 -0.127)
							(mid -0.137521 -0.162921)
							(end -0.1016 -0.1778)
						)
						(arc
							(start 0.1016 -0.1778)
							(mid 0.137521 -0.162921)
							(end 0.1524 -0.127)
						)
					)
					(width 0)
					(fill yes)
				)
			)
		)
	)
	(footprint ""
		(layer "B.Cu")
		(at 63.000128 -147.083018 90)
		(property "Reference" "R201"
			(at 0 0 90)
			(layer "B.SilkS")
			(hide yes)
			(effects
				(font
					(size 1.27 1.27)
				)
				(justify mirror)
			)
		)
		(property "Value" "2K2R2F-GP"
			(at -0.064008 -3.993896 90)
			(unlocked yes)
			(layer "B.Fab")
			(hide yes)
			(effects
				(font
					(size 1.016 1.016)
					(thickness 0.1524)
				)
				(justify mirror)
			)
		)
		(property "Device Type" "R402H16"
			(at -0.064008 -5.517896 90)
			(unlocked yes)
			(layer "B.Fab")
			(hide yes)
			(effects
				(font
					(size 1.016 1.016)
					(thickness 0.1524)
				)
				(justify mirror)
			)
		)
		(duplicate_pad_numbers_are_jumpers no)
		(fp_line
			(start 0.508 -0.9398)
			(end 0.508 0.9398)
			(stroke
				(width 0.1524)
				(type default)
			)
			(layer "B.SilkS")
		)
		(fp_line
			(start -0.508 -0.9398)
			(end 0.508 -0.9398)
			(stroke
				(width 0.1524)
				(type default)
			)
			(layer "B.SilkS")
		)
		(fp_rect
			(start 0.508 0.9398)
			(end -0.508 -0.9398)
			(stroke
				(width 0)
				(type default)
			)
			(fill no)
			(layer "B.CrtYd")
		)
		(fp_rect
			(start 0.508 0.9398)
			(end -0.508 -0.9398)
			(stroke
				(width 0)
				(type default)
			)
			(fill no)
			(layer "B.Fab")
		)
		(pad "1" smd custom
			(at 0 -0.4445 270)
			(size 0.1397 0.1397)
			(layers "B.Cu" "B.Mask" "B.Paste")
			(net "I2C_MEZZ_FRU_SENSOR_SCL")
			(options
				(clearance outline)
				(anchor circle)
			)
			(primitives
				(gr_poly
					(pts
						(arc
							(start -0.1778 0.2794)
							(mid -0.249642 0.249642)
							(end -0.2794 0.1778)
						)
						(arc
							(start -0.2794 -0.1778)
							(mid -0.249642 -0.249642)
							(end -0.1778 -0.2794)
						)
						(arc
							(start 0.1778 -0.2794)
							(mid 0.249642 -0.249642)
							(end 0.2794 -0.1778)
						)
						(arc
							(start 0.2794 0.1778)
							(mid 0.249642 0.249642)
							(end 0.1778 0.2794)
						)
					)
					(width 0)
					(fill yes)
				)
			)
		)
		(pad "2" smd custom
			(at 0 0.4445 270)
			(size 0.1397 0.1397)
			(layers "B.Cu" "B.Mask" "B.Paste")
			(net "P3V3_STBY")
			(options
				(clearance outline)
				(anchor circle)
			)
			(primitives
				(gr_poly
					(pts
						(arc
							(start -0.1778 0.2794)
							(mid -0.249642 0.249642)
							(end -0.2794 0.1778)
						)
						(arc
							(start -0.2794 -0.1778)
							(mid -0.249642 -0.249642)
							(end -0.1778 -0.2794)
						)
						(arc
							(start 0.1778 -0.2794)
							(mid 0.249642 -0.249642)
							(end 0.2794 -0.1778)
						)
						(arc
							(start 0.2794 0.1778)
							(mid 0.249642 0.249642)
							(end 0.1778 0.2794)
						)
					)
					(width 0)
					(fill yes)
				)
			)
		)
	)
	(footprint ""
		(layer "B.Cu")
		(at 38.45941 -117.941852 90)
		(property "Reference" "R347"
			(at 0 0 90)
			(layer "B.SilkS")
			(hide yes)
			(effects
				(font
					(size 1.27 1.27)
				)
				(justify mirror)
			)
		)
		(property "Value" "4K7R2F-GP"
			(at -0.064008 -3.993896 90)
			(unlocked yes)
			(layer "B.Fab")
			(hide yes)
			(effects
				(font
					(size 1.016 1.016)
					(thickness 0.1524)
				)
				(justify mirror)
			)
		)
		(property "Device Type" "R402H16"
			(at -0.064008 -5.517896 90)
			(unlocked yes)
			(layer "B.Fab")
			(hide yes)
			(effects
				(font
					(size 1.016 1.016)
					(thickness 0.1524)
				)
				(justify mirror)
			)
		)
		(duplicate_pad_numbers_are_jumpers no)
		(fp_line
			(start 0.508 -0.9398)
			(end 0.508 0.9398)
			(stroke
				(width 0.1524)
				(type default)
			)
			(layer "B.SilkS")
		)
		(fp_line
			(start -0.508 -0.9398)
			(end 0.508 -0.9398)
			(stroke
				(width 0.1524)
				(type default)
			)
			(layer "B.SilkS")
		)
		(fp_rect
			(start 0.508 0.9398)
			(end -0.508 -0.9398)
			(stroke
				(width 0)
				(type default)
			)
			(fill no)
			(layer "B.CrtYd")
		)
		(fp_rect
			(start 0.508 0.9398)
			(end -0.508 -0.9398)
			(stroke
				(width 0)
				(type default)
			)
			(fill no)
			(layer "B.Fab")
		)
		(pad "1" smd custom
			(at 0 -0.4445 270)
			(size 0.1397 0.1397)
			(layers "B.Cu" "B.Mask" "B.Paste")
			(net "P3V3_STBY")
			(options
				(clearance outline)
				(anchor circle)
			)
			(primitives
				(gr_poly
					(pts
						(arc
							(start -0.1778 0.2794)
							(mid -0.249642 0.249642)
							(end -0.2794 0.1778)
						)
						(arc
							(start -0.2794 -0.1778)
							(mid -0.249642 -0.249642)
							(end -0.1778 -0.2794)
						)
						(arc
							(start 0.1778 -0.2794)
							(mid 0.249642 -0.249642)
							(end 0.2794 -0.1778)
						)
						(arc
							(start 0.2794 0.1778)
							(mid 0.249642 0.249642)
							(end 0.1778 0.2794)
						)
					)
					(width 0)
					(fill yes)
				)
			)
		)
		(pad "2" smd custom
			(at 0 0.4445 270)
			(size 0.1397 0.1397)
			(layers "B.Cu" "B.Mask" "B.Paste")
			(net "TEMP_3_A2")
			(options
				(clearance outline)
				(anchor circle)
			)
			(primitives
				(gr_poly
					(pts
						(arc
							(start -0.1778 0.2794)
							(mid -0.249642 0.249642)
							(end -0.2794 0.1778)
						)
						(arc
							(start -0.2794 -0.1778)
							(mid -0.249642 -0.249642)
							(end -0.1778 -0.2794)
						)
						(arc
							(start 0.1778 -0.2794)
							(mid 0.249642 -0.249642)
							(end 0.2794 -0.1778)
						)
						(arc
							(start 0.2794 0.1778)
							(mid 0.249642 0.249642)
							(end 0.1778 0.2794)
						)
					)
					(width 0)
					(fill yes)
				)
			)
		)
	)
	(footprint ""
		(layer "B.Cu")
		(at 87.796116 -177.37201)
		(property "Reference" "R93"
			(at 0 0 0)
			(layer "B.SilkS")
			(hide yes)
			(effects
				(font
					(size 1.27 1.27)
				)
				(justify mirror)
			)
		)
		(property "Value" "0R2J-2-GP"
			(at -0.064008 -3.993896 0)
			(unlocked yes)
			(layer "B.Fab")
			(hide yes)
			(effects
				(font
					(size 1.016 1.016)
					(thickness 0.1524)
				)
				(justify mirror)
			)
		)
		(property "Device Type" "R402H16"
			(at -0.064008 -5.517896 0)
			(unlocked yes)
			(layer "B.Fab")
			(hide yes)
			(effects
				(font
					(size 1.016 1.016)
					(thickness 0.1524)
				)
				(justify mirror)
			)
		)
		(duplicate_pad_numbers_are_jumpers no)
		(fp_line
			(start -0.508 -0.9398)
			(end 0.508 -0.9398)
			(stroke
				(width 0.1524)
				(type default)
			)
			(layer "B.SilkS")
		)
		(fp_line
			(start 0.508 -0.9398)
			(end 0.508 0.9398)
			(stroke
				(width 0.1524)
				(type default)
			)
			(layer "B.SilkS")
		)
		(fp_rect
			(start 0.508 0.9398)
			(end -0.508 -0.9398)
			(stroke
				(width 0)
				(type default)
			)
			(fill no)
			(layer "B.CrtYd")
		)
		(fp_rect
			(start 0.508 0.9398)
			(end -0.508 -0.9398)
			(stroke
				(width 0)
				(type default)
			)
			(fill no)
			(layer "B.Fab")
		)
		(pad "1" smd custom
			(at 0 -0.4445 180)
			(size 0.1397 0.1397)
			(layers "B.Cu" "B.Mask" "B.Paste")
			(net "I2C_BMC_COMP_SCL_OUT")
			(options
				(clearance outline)
				(anchor circle)
			)
			(primitives
				(gr_poly
					(pts
						(arc
							(start -0.1778 0.2794)
							(mid -0.249642 0.249642)
							(end -0.2794 0.1778)
						)
						(arc
							(start -0.2794 -0.1778)
							(mid -0.249642 -0.249642)
							(end -0.1778 -0.2794)
						)
						(arc
							(start 0.1778 -0.2794)
							(mid 0.249642 -0.249642)
							(end 0.2794 -0.1778)
						)
						(arc
							(start 0.2794 0.1778)
							(mid 0.249642 0.249642)
							(end 0.1778 0.2794)
						)
					)
					(width 0)
					(fill yes)
				)
			)
		)
		(pad "2" smd custom
			(at 0 0.4445 180)
			(size 0.1397 0.1397)
			(layers "B.Cu" "B.Mask" "B.Paste")
			(net "I2C_BMC_COMP_SCL_R")
			(options
				(clearance outline)
				(anchor circle)
			)
			(primitives
				(gr_poly
					(pts
						(arc
							(start -0.1778 0.2794)
							(mid -0.249642 0.249642)
							(end -0.2794 0.1778)
						)
						(arc
							(start -0.2794 -0.1778)
							(mid -0.249642 -0.249642)
							(end -0.1778 -0.2794)
						)
						(arc
							(start 0.1778 -0.2794)
							(mid 0.249642 -0.249642)
							(end 0.2794 -0.1778)
						)
						(arc
							(start 0.2794 0.1778)
							(mid 0.249642 0.249642)
							(end 0.1778 0.2794)
						)
					)
					(width 0)
					(fill yes)
				)
			)
		)
	)
	(footprint ""
		(layer "B.Cu")
		(at 93.291406 -140.716 -90)
		(property "Reference" "C137"
			(at 0 0 90)
			(layer "B.SilkS")
			(hide yes)
			(effects
				(font
					(size 1.27 1.27)
				)
				(justify mirror)
			)
		)
		(property "Value" "SCD1U16V2KX-3GP"
			(at -1.1811 -2.7051 270)
			(unlocked yes)
			(layer "B.Fab")
			(hide yes)
			(effects
				(font
					(size 1.016 1.016)
					(thickness 0.1524)
				)
				(justify mirror)
			)
		)
		(property "Device Type" "C402H22"
			(at -1.1811 -4.2291 270)
			(unlocked yes)
			(layer "B.Fab")
			(hide yes)
			(effects
				(font
					(size 1.016 1.016)
					(thickness 0.1524)
				)
				(justify mirror)
			)
		)
		(duplicate_pad_numbers_are_jumpers no)
		(fp_rect
			(start 0.4318 0.9525)
			(end -0.4318 -0.9525)
			(stroke
				(width 0)
				(type default)
			)
			(fill no)
			(layer "B.CrtYd")
		)
		(fp_rect
			(start 0.4318 0.9525)
			(end -0.4318 -0.9525)
			(stroke
				(width 0)
				(type default)
			)
			(fill no)
			(layer "B.Fab")
		)
		(pad "1" smd custom
			(at 0 -0.4445 90)
			(size 0.1524 0.1524)
			(layers "B.Cu" "B.Mask" "B.Paste")
			(net "DEBUG_CARD_PRSNT")
			(options
				(clearance outline)
				(anchor circle)
			)
			(primitives
				(gr_poly
					(pts
						(arc
							(start 0.3048 0.2032)
							(mid 0.275042 0.275042)
							(end 0.2032 0.3048)
						)
						(arc
							(start -0.2032 0.3048)
							(mid -0.275042 0.275042)
							(end -0.3048 0.2032)
						)
						(arc
							(start -0.3048 -0.2032)
							(mid -0.275042 -0.275042)
							(end -0.2032 -0.3048)
						)
						(arc
							(start 0.2032 -0.3048)
							(mid 0.275042 -0.275042)
							(end 0.3048 -0.2032)
						)
					)
					(width 0)
					(fill yes)
				)
			)
		)
		(pad "2" smd custom
			(at 0 0.4445 90)
			(size 0.1524 0.1524)
			(layers "B.Cu" "B.Mask" "B.Paste")
			(net "GND")
			(options
				(clearance outline)
				(anchor circle)
			)
			(primitives
				(gr_poly
					(pts
						(arc
							(start 0.3048 0.2032)
							(mid 0.275042 0.275042)
							(end 0.2032 0.3048)
						)
						(arc
							(start -0.2032 0.3048)
							(mid -0.275042 0.275042)
							(end -0.3048 0.2032)
						)
						(arc
							(start -0.3048 -0.2032)
							(mid -0.275042 -0.275042)
							(end -0.2032 -0.3048)
						)
						(arc
							(start 0.2032 -0.3048)
							(mid 0.275042 -0.275042)
							(end 0.3048 -0.2032)
						)
					)
					(width 0)
					(fill yes)
				)
			)
		)
	)
	(footprint ""
		(layer "B.Cu")
		(at 60.96 -142.9004 90)
		(property "Reference" "R151"
			(at 0 0 90)
			(layer "B.SilkS")
			(hide yes)
			(effects
				(font
					(size 1.27 1.27)
				)
				(justify mirror)
			)
		)
		(property "Value" "0R2J-2-GP"
			(at -0.064008 -3.993896 90)
			(unlocked yes)
			(layer "B.Fab")
			(hide yes)
			(effects
				(font
					(size 1.016 1.016)
					(thickness 0.1524)
				)
				(justify mirror)
			)
		)
		(property "Device Type" "R402H16"
			(at -0.064008 -5.517896 90)
			(unlocked yes)
			(layer "B.Fab")
			(hide yes)
			(effects
				(font
					(size 1.016 1.016)
					(thickness 0.1524)
				)
				(justify mirror)
			)
		)
		(duplicate_pad_numbers_are_jumpers no)
		(fp_line
			(start 0.508 -0.9398)
			(end 0.508 0.9398)
			(stroke
				(width 0.1524)
				(type default)
			)
			(layer "B.SilkS")
		)
		(fp_line
			(start -0.508 -0.9398)
			(end 0.508 -0.9398)
			(stroke
				(width 0.1524)
				(type default)
			)
			(layer "B.SilkS")
		)
		(fp_rect
			(start 0.508 0.9398)
			(end -0.508 -0.9398)
			(stroke
				(width 0)
				(type default)
			)
			(fill no)
			(layer "B.CrtYd")
		)
		(fp_rect
			(start 0.508 0.9398)
			(end -0.508 -0.9398)
			(stroke
				(width 0)
				(type default)
			)
			(fill no)
			(layer "B.Fab")
		)
		(pad "1" smd custom
			(at 0 -0.4445 270)
			(size 0.1397 0.1397)
			(layers "B.Cu" "B.Mask" "B.Paste")
			(net "BMC_SMB10_CLK")
			(options
				(clearance outline)
				(anchor circle)
			)
			(primitives
				(gr_poly
					(pts
						(arc
							(start -0.1778 0.2794)
							(mid -0.249642 0.249642)
							(end -0.2794 0.1778)
						)
						(arc
							(start -0.2794 -0.1778)
							(mid -0.249642 -0.249642)
							(end -0.1778 -0.2794)
						)
						(arc
							(start 0.1778 -0.2794)
							(mid 0.249642 -0.249642)
							(end 0.2794 -0.1778)
						)
						(arc
							(start 0.2794 0.1778)
							(mid 0.249642 0.249642)
							(end 0.1778 0.2794)
						)
					)
					(width 0)
					(fill yes)
				)
			)
		)
		(pad "2" smd custom
			(at 0 0.4445 270)
			(size 0.1397 0.1397)
			(layers "B.Cu" "B.Mask" "B.Paste")
			(net "I2C_EXP_LOC_SCL_OUT")
			(options
				(clearance outline)
				(anchor circle)
			)
			(primitives
				(gr_poly
					(pts
						(arc
							(start -0.1778 0.2794)
							(mid -0.249642 0.249642)
							(end -0.2794 0.1778)
						)
						(arc
							(start -0.2794 -0.1778)
							(mid -0.249642 -0.249642)
							(end -0.1778 -0.2794)
						)
						(arc
							(start 0.1778 -0.2794)
							(mid 0.249642 -0.249642)
							(end 0.2794 -0.1778)
						)
						(arc
							(start 0.2794 0.1778)
							(mid 0.249642 0.249642)
							(end 0.1778 0.2794)
						)
					)
					(width 0)
					(fill yes)
				)
			)
		)
	)
	(footprint ""
		(layer "B.Cu")
		(at 61.0108 -140.8176 90)
		(property "Reference" "R272"
			(at 0 0 90)
			(layer "B.SilkS")
			(hide yes)
			(effects
				(font
					(size 1.27 1.27)
				)
				(justify mirror)
			)
		)
		(property "Value" "4K7R2F-GP"
			(at -0.064008 -3.993896 90)
			(unlocked yes)
			(layer "B.Fab")
			(hide yes)
			(effects
				(font
					(size 1.016 1.016)
					(thickness 0.1524)
				)
				(justify mirror)
			)
		)
		(property "Device Type" "R402H16"
			(at -0.064008 -5.517896 90)
			(unlocked yes)
			(layer "B.Fab")
			(hide yes)
			(effects
				(font
					(size 1.016 1.016)
					(thickness 0.1524)
				)
				(justify mirror)
			)
		)
		(duplicate_pad_numbers_are_jumpers no)
		(fp_line
			(start 0.508 -0.9398)
			(end 0.508 0.9398)
			(stroke
				(width 0.1524)
				(type default)
			)
			(layer "B.SilkS")
		)
		(fp_line
			(start -0.508 -0.9398)
			(end 0.508 -0.9398)
			(stroke
				(width 0.1524)
				(type default)
			)
			(layer "B.SilkS")
		)
		(fp_rect
			(start 0.508 0.9398)
			(end -0.508 -0.9398)
			(stroke
				(width 0)
				(type default)
			)
			(fill no)
			(layer "B.CrtYd")
		)
		(fp_rect
			(start 0.508 0.9398)
			(end -0.508 -0.9398)
			(stroke
				(width 0)
				(type default)
			)
			(fill no)
			(layer "B.Fab")
		)
		(pad "1" smd custom
			(at 0 -0.4445 270)
			(size 0.1397 0.1397)
			(layers "B.Cu" "B.Mask" "B.Paste")
			(net "SYS_PWR_LED")
			(options
				(clearance outline)
				(anchor circle)
			)
			(primitives
				(gr_poly
					(pts
						(arc
							(start -0.1778 0.2794)
							(mid -0.249642 0.249642)
							(end -0.2794 0.1778)
						)
						(arc
							(start -0.2794 -0.1778)
							(mid -0.249642 -0.249642)
							(end -0.1778 -0.2794)
						)
						(arc
							(start 0.1778 -0.2794)
							(mid 0.249642 -0.249642)
							(end 0.2794 -0.1778)
						)
						(arc
							(start 0.2794 0.1778)
							(mid 0.249642 0.249642)
							(end 0.1778 0.2794)
						)
					)
					(width 0)
					(fill yes)
				)
			)
		)
		(pad "2" smd custom
			(at 0 0.4445 270)
			(size 0.1397 0.1397)
			(layers "B.Cu" "B.Mask" "B.Paste")
			(net "P3V3_STBY")
			(options
				(clearance outline)
				(anchor circle)
			)
			(primitives
				(gr_poly
					(pts
						(arc
							(start -0.1778 0.2794)
							(mid -0.249642 0.249642)
							(end -0.2794 0.1778)
						)
						(arc
							(start -0.2794 -0.1778)
							(mid -0.249642 -0.249642)
							(end -0.1778 -0.2794)
						)
						(arc
							(start 0.1778 -0.2794)
							(mid 0.249642 -0.249642)
							(end 0.2794 -0.1778)
						)
						(arc
							(start 0.2794 0.1778)
							(mid 0.249642 0.249642)
							(end 0.1778 0.2794)
						)
					)
					(width 0)
					(fill yes)
				)
			)
		)
	)
	(footprint ""
		(layer "B.Cu")
		(at 129.286 -16.51 -90)
		(property "Reference" "R446"
			(at 0 0 90)
			(layer "B.SilkS")
			(hide yes)
			(effects
				(font
					(size 1.27 1.27)
				)
				(justify mirror)
			)
		)
		(property "Value" "49K9R2F-L-GP"
			(at -0.064008 -3.993896 270)
			(unlocked yes)
			(layer "B.Fab")
			(hide yes)
			(effects
				(font
					(size 1.016 1.016)
					(thickness 0.1524)
				)
				(justify mirror)
			)
		)
		(property "Device Type" "R402H16"
			(at -0.064008 -5.517896 270)
			(unlocked yes)
			(layer "B.Fab")
			(hide yes)
			(effects
				(font
					(size 1.016 1.016)
					(thickness 0.1524)
				)
				(justify mirror)
			)
		)
		(duplicate_pad_numbers_are_jumpers no)
		(fp_line
			(start -0.508 -0.9398)
			(end 0.508 -0.9398)
			(stroke
				(width 0.1524)
				(type default)
			)
			(layer "B.SilkS")
		)
		(fp_line
			(start 0.508 -0.9398)
			(end 0.508 0.9398)
			(stroke
				(width 0.1524)
				(type default)
			)
			(layer "B.SilkS")
		)
		(fp_rect
			(start 0.508 0.9398)
			(end -0.508 -0.9398)
			(stroke
				(width 0)
				(type default)
			)
			(fill no)
			(layer "B.CrtYd")
		)
		(fp_rect
			(start 0.508 0.9398)
			(end -0.508 -0.9398)
			(stroke
				(width 0)
				(type default)
			)
			(fill no)
			(layer "B.Fab")
		)
		(pad "1" smd custom
			(at 0 -0.4445 90)
			(size 0.1397 0.1397)
			(layers "B.Cu" "B.Mask" "B.Paste")
			(net "P12V_IOM")
			(options
				(clearance outline)
				(anchor circle)
			)
			(primitives
				(gr_poly
					(pts
						(arc
							(start -0.1778 0.2794)
							(mid -0.249642 0.249642)
							(end -0.2794 0.1778)
						)
						(arc
							(start -0.2794 -0.1778)
							(mid -0.249642 -0.249642)
							(end -0.1778 -0.2794)
						)
						(arc
							(start 0.1778 -0.2794)
							(mid 0.249642 -0.249642)
							(end 0.2794 -0.1778)
						)
						(arc
							(start 0.2794 0.1778)
							(mid 0.249642 0.249642)
							(end 0.1778 0.2794)
						)
					)
					(width 0)
					(fill yes)
				)
			)
		)
		(pad "2" smd custom
			(at 0 0.4445 90)
			(size 0.1397 0.1397)
			(layers "B.Cu" "B.Mask" "B.Paste")
			(net "MB0_CM_UV_R")
			(options
				(clearance outline)
				(anchor circle)
			)
			(primitives
				(gr_poly
					(pts
						(arc
							(start -0.1778 0.2794)
							(mid -0.249642 0.249642)
							(end -0.2794 0.1778)
						)
						(arc
							(start -0.2794 -0.1778)
							(mid -0.249642 -0.249642)
							(end -0.1778 -0.2794)
						)
						(arc
							(start 0.1778 -0.2794)
							(mid 0.249642 -0.249642)
							(end 0.2794 -0.1778)
						)
						(arc
							(start 0.2794 0.1778)
							(mid 0.249642 0.249642)
							(end 0.1778 0.2794)
						)
					)
					(width 0)
					(fill yes)
				)
			)
		)
	)
	(footprint ""
		(layer "B.Cu")
		(at 49.78781 -119.846852 90)
		(property "Reference" "R344"
			(at 0 0 90)
			(layer "B.SilkS")
			(hide yes)
			(effects
				(font
					(size 1.27 1.27)
				)
				(justify mirror)
			)
		)
		(property "Value" "0R2J-2-GP"
			(at -0.064008 -3.993896 90)
			(unlocked yes)
			(layer "B.Fab")
			(hide yes)
			(effects
				(font
					(size 1.016 1.016)
					(thickness 0.1524)
				)
				(justify mirror)
			)
		)
		(property "Device Type" "R402H16"
			(at -0.064008 -5.517896 90)
			(unlocked yes)
			(layer "B.Fab")
			(hide yes)
			(effects
				(font
					(size 1.016 1.016)
					(thickness 0.1524)
				)
				(justify mirror)
			)
		)
		(duplicate_pad_numbers_are_jumpers no)
		(fp_line
			(start 0.508 -0.9398)
			(end 0.508 0.9398)
			(stroke
				(width 0.1524)
				(type default)
			)
			(layer "B.SilkS")
		)
		(fp_line
			(start -0.508 -0.9398)
			(end 0.508 -0.9398)
			(stroke
				(width 0.1524)
				(type default)
			)
			(layer "B.SilkS")
		)
		(fp_rect
			(start 0.508 0.9398)
			(end -0.508 -0.9398)
			(stroke
				(width 0)
				(type default)
			)
			(fill no)
			(layer "B.CrtYd")
		)
		(fp_rect
			(start 0.508 0.9398)
			(end -0.508 -0.9398)
			(stroke
				(width 0)
				(type default)
			)
			(fill no)
			(layer "B.Fab")
		)
		(pad "1" smd custom
			(at 0 -0.4445 270)
			(size 0.1397 0.1397)
			(layers "B.Cu" "B.Mask" "B.Paste")
			(net "TEMP_3_SCL")
			(options
				(clearance outline)
				(anchor circle)
			)
			(primitives
				(gr_poly
					(pts
						(arc
							(start -0.1778 0.2794)
							(mid -0.249642 0.249642)
							(end -0.2794 0.1778)
						)
						(arc
							(start -0.2794 -0.1778)
							(mid -0.249642 -0.249642)
							(end -0.1778 -0.2794)
						)
						(arc
							(start 0.1778 -0.2794)
							(mid 0.249642 -0.249642)
							(end 0.2794 -0.1778)
						)
						(arc
							(start 0.2794 0.1778)
							(mid 0.249642 0.249642)
							(end 0.1778 0.2794)
						)
					)
					(width 0)
					(fill yes)
				)
			)
		)
		(pad "2" smd custom
			(at 0 0.4445 270)
			(size 0.1397 0.1397)
			(layers "B.Cu" "B.Mask" "B.Paste")
			(net "I2C_IOM_SCL")
			(options
				(clearance outline)
				(anchor circle)
			)
			(primitives
				(gr_poly
					(pts
						(arc
							(start -0.1778 0.2794)
							(mid -0.249642 0.249642)
							(end -0.2794 0.1778)
						)
						(arc
							(start -0.2794 -0.1778)
							(mid -0.249642 -0.249642)
							(end -0.1778 -0.2794)
						)
						(arc
							(start 0.1778 -0.2794)
							(mid 0.249642 -0.249642)
							(end 0.2794 -0.1778)
						)
						(arc
							(start 0.2794 0.1778)
							(mid 0.249642 0.249642)
							(end 0.1778 0.2794)
						)
					)
					(width 0)
					(fill yes)
				)
			)
		)
	)
	(footprint ""
		(layer "B.Cu")
		(at 191.7192 -70.3199)
		(property "Reference" "C366"
			(at 0 0 0)
			(layer "B.SilkS")
			(hide yes)
			(effects
				(font
					(size 1.27 1.27)
				)
				(justify mirror)
			)
		)
		(property "Value" "SCD1U6D3V1KX-GP"
			(at 2.8321 -1.7399 0)
			(unlocked yes)
			(layer "B.Fab")
			(hide yes)
			(effects
				(font
					(size 1.016 1.016)
					(thickness 0.1524)
				)
				(justify mirror)
			)
		)
		(property "Device Type" "C0201H13"
			(at 2.8321 -3.2639 0)
			(unlocked yes)
			(layer "B.Fab")
			(hide yes)
			(effects
				(font
					(size 1.016 1.016)
					(thickness 0.1524)
				)
				(justify mirror)
			)
		)
		(duplicate_pad_numbers_are_jumpers no)
		(fp_rect
			(start 0.2794 0.6477)
			(end -0.2794 -0.6477)
			(stroke
				(width 0)
				(type default)
			)
			(fill no)
			(layer "B.CrtYd")
		)
		(fp_rect
			(start 0.2794 0.6477)
			(end -0.2794 -0.6477)
			(stroke
				(width 0)
				(type default)
			)
			(fill no)
			(layer "B.Fab")
		)
		(pad "1" smd custom
			(at 0 -0.2794 180)
			(size 0.0762 0.0762)
			(layers "B.Cu" "B.Mask" "B.Paste")
			(net "PCE_AVDD")
			(options
				(clearance outline)
				(anchor circle)
			)
			(primitives
				(gr_poly
					(pts
						(arc
							(start 0.1524 0.127)
							(mid 0.137521 0.162921)
							(end 0.1016 0.1778)
						)
						(arc
							(start -0.1016 0.1778)
							(mid -0.137521 0.162921)
							(end -0.1524 0.127)
						)
						(arc
							(start -0.1524 -0.127)
							(mid -0.137521 -0.162921)
							(end -0.1016 -0.1778)
						)
						(arc
							(start 0.1016 -0.1778)
							(mid 0.137521 -0.162921)
							(end 0.1524 -0.127)
						)
					)
					(width 0)
					(fill yes)
				)
			)
		)
		(pad "2" smd custom
			(at 0 0.2794 180)
			(size 0.0762 0.0762)
			(layers "B.Cu" "B.Mask" "B.Paste")
			(net "GND")
			(options
				(clearance outline)
				(anchor circle)
			)
			(primitives
				(gr_poly
					(pts
						(arc
							(start 0.1524 0.127)
							(mid 0.137521 0.162921)
							(end 0.1016 0.1778)
						)
						(arc
							(start -0.1016 0.1778)
							(mid -0.137521 0.162921)
							(end -0.1524 0.127)
						)
						(arc
							(start -0.1524 -0.127)
							(mid -0.137521 -0.162921)
							(end -0.1016 -0.1778)
						)
						(arc
							(start 0.1016 -0.1778)
							(mid 0.137521 -0.162921)
							(end 0.1524 -0.127)
						)
					)
					(width 0)
					(fill yes)
				)
			)
		)
	)
	(footprint ""
		(layer "B.Cu")
		(at 46.3804 -135.7122 180)
		(property "Reference" "R156"
			(at 0 0 0)
			(layer "B.SilkS")
			(hide yes)
			(effects
				(font
					(size 1.27 1.27)
				)
				(justify mirror)
			)
		)
		(property "Value" "0R2J-2-GP"
			(at -0.064008 -3.993896 180)
			(unlocked yes)
			(layer "B.Fab")
			(hide yes)
			(effects
				(font
					(size 1.016 1.016)
					(thickness 0.1524)
				)
				(justify mirror)
			)
		)
		(property "Device Type" "R402H16"
			(at -0.064008 -5.517896 180)
			(unlocked yes)
			(layer "B.Fab")
			(hide yes)
			(effects
				(font
					(size 1.016 1.016)
					(thickness 0.1524)
				)
				(justify mirror)
			)
		)
		(duplicate_pad_numbers_are_jumpers no)
		(fp_line
			(start 0.508 -0.9398)
			(end 0.508 0.9398)
			(stroke
				(width 0.1524)
				(type default)
			)
			(layer "B.SilkS")
		)
		(fp_line
			(start -0.508 -0.9398)
			(end 0.508 -0.9398)
			(stroke
				(width 0.1524)
				(type default)
			)
			(layer "B.SilkS")
		)
		(fp_rect
			(start 0.508 0.9398)
			(end -0.508 -0.9398)
			(stroke
				(width 0)
				(type default)
			)
			(fill no)
			(layer "B.CrtYd")
		)
		(fp_rect
			(start 0.508 0.9398)
			(end -0.508 -0.9398)
			(stroke
				(width 0)
				(type default)
			)
			(fill no)
			(layer "B.Fab")
		)
		(pad "1" smd custom
			(at 0 -0.4445)
			(size 0.1397 0.1397)
			(layers "B.Cu" "B.Mask" "B.Paste")
			(net "I2C_IOC_SCL")
			(options
				(clearance outline)
				(anchor circle)
			)
			(primitives
				(gr_poly
					(pts
						(arc
							(start -0.1778 0.2794)
							(mid -0.249642 0.249642)
							(end -0.2794 0.1778)
						)
						(arc
							(start -0.2794 -0.1778)
							(mid -0.249642 -0.249642)
							(end -0.1778 -0.2794)
						)
						(arc
							(start 0.1778 -0.2794)
							(mid 0.249642 -0.249642)
							(end 0.2794 -0.1778)
						)
						(arc
							(start 0.2794 0.1778)
							(mid 0.249642 0.249642)
							(end 0.1778 0.2794)
						)
					)
					(width 0)
					(fill yes)
				)
			)
		)
		(pad "2" smd custom
			(at 0 0.4445)
			(size 0.1397 0.1397)
			(layers "B.Cu" "B.Mask" "B.Paste")
			(net "BMC_SMB2_CLK")
			(options
				(clearance outline)
				(anchor circle)
			)
			(primitives
				(gr_poly
					(pts
						(arc
							(start -0.1778 0.2794)
							(mid -0.249642 0.249642)
							(end -0.2794 0.1778)
						)
						(arc
							(start -0.2794 -0.1778)
							(mid -0.249642 -0.249642)
							(end -0.1778 -0.2794)
						)
						(arc
							(start 0.1778 -0.2794)
							(mid 0.249642 -0.249642)
							(end 0.2794 -0.1778)
						)
						(arc
							(start 0.2794 0.1778)
							(mid 0.249642 0.249642)
							(end 0.1778 0.2794)
						)
					)
					(width 0)
					(fill yes)
				)
			)
		)
	)
	(footprint ""
		(layer "B.Cu")
		(at 204.978 -58.547)
		(property "Reference" "TP126"
			(at 0 0 0)
			(layer "B.SilkS")
			(hide yes)
			(effects
				(font
					(size 1.27 1.27)
				)
				(justify mirror)
			)
		)
		(property "Value" "TPAD28-2-GP"
			(at 0.0127 -1.6637 0)
			(unlocked yes)
			(layer "B.Fab")
			(hide yes)
			(effects
				(font
					(size 1.016 1.016)
					(thickness 0.1524)
				)
				(justify mirror)
			)
		)
		(property "Device Type" "TPAD28"
			(at 0.0127 -3.1877 0)
			(unlocked yes)
			(layer "B.Fab")
			(hide yes)
			(effects
				(font
					(size 1.016 1.016)
					(thickness 0.1524)
				)
				(justify mirror)
			)
		)
		(duplicate_pad_numbers_are_jumpers no)
		(fp_poly
			(pts
				(arc
					(start 0.3556 0)
					(mid -0.3556 0)
					(end 0.3556 0)
				)
			)
			(stroke
				(width 0)
				(type default)
			)
			(fill no)
			(layer "B.CrtYd")
		)
		(fp_poly
			(pts
				(arc
					(start 0.6096 0)
					(mid -0.6096 0)
					(end 0.6096 0)
				)
			)
			(stroke
				(width 0)
				(type default)
			)
			(fill no)
			(layer "B.Fab")
		)
		(pad "1" smd circle
			(at 0 0 180)
			(size 0.7112 0.7112)
			(layers "B.Cu" "B.Mask" "B.Paste")
			(net "SIO_LOAD_1")
		)
	)
	(footprint ""
		(layer "B.Cu")
		(at 178.335686 -75.667362)
		(property "Reference" "TP101"
			(at 0 0 0)
			(layer "B.SilkS")
			(hide yes)
			(effects
				(font
					(size 1.27 1.27)
				)
				(justify mirror)
			)
		)
		(property "Value" "TPAD28-2-GP"
			(at 0.0127 -1.6637 0)
			(unlocked yes)
			(layer "B.Fab")
			(hide yes)
			(effects
				(font
					(size 1.016 1.016)
					(thickness 0.1524)
				)
				(justify mirror)
			)
		)
		(property "Device Type" "TPAD28"
			(at 0.0127 -3.1877 0)
			(unlocked yes)
			(layer "B.Fab")
			(hide yes)
			(effects
				(font
					(size 1.016 1.016)
					(thickness 0.1524)
				)
				(justify mirror)
			)
		)
		(duplicate_pad_numbers_are_jumpers no)
		(fp_poly
			(pts
				(arc
					(start 0.3556 0)
					(mid -0.3556 0)
					(end 0.3556 0)
				)
			)
			(stroke
				(width 0)
				(type default)
			)
			(fill no)
			(layer "B.CrtYd")
		)
		(fp_poly
			(pts
				(arc
					(start 0.6096 0)
					(mid -0.6096 0)
					(end 0.6096 0)
				)
			)
			(stroke
				(width 0)
				(type default)
			)
			(fill no)
			(layer "B.Fab")
		)
		(pad "1" smd circle
			(at 0 0 180)
			(size 0.7112 0.7112)
			(layers "B.Cu" "B.Mask" "B.Paste")
			(net "IOC_GPIO_16")
		)
	)
	(footprint ""
		(layer "B.Cu")
		(at 193.9671 -63.7794 90)
		(property "Reference" "C407"
			(at 0 0 90)
			(layer "B.SilkS")
			(hide yes)
			(effects
				(font
					(size 1.27 1.27)
				)
				(justify mirror)
			)
		)
		(property "Value" "SCD1U6D3V1KX-GP"
			(at 2.8321 -1.7399 90)
			(unlocked yes)
			(layer "B.Fab")
			(hide yes)
			(effects
				(font
					(size 1.016 1.016)
					(thickness 0.1524)
				)
				(justify mirror)
			)
		)
		(property "Device Type" "C0201H13"
			(at 2.8321 -3.2639 90)
			(unlocked yes)
			(layer "B.Fab")
			(hide yes)
			(effects
				(font
					(size 1.016 1.016)
					(thickness 0.1524)
				)
				(justify mirror)
			)
		)
		(duplicate_pad_numbers_are_jumpers no)
		(fp_rect
			(start 0.2794 0.6477)
			(end -0.2794 -0.6477)
			(stroke
				(width 0)
				(type default)
			)
			(fill no)
			(layer "B.CrtYd")
		)
		(fp_rect
			(start 0.2794 0.6477)
			(end -0.2794 -0.6477)
			(stroke
				(width 0)
				(type default)
			)
			(fill no)
			(layer "B.Fab")
		)
		(pad "1" smd custom
			(at 0 -0.2794 270)
			(size 0.0762 0.0762)
			(layers "B.Cu" "B.Mask" "B.Paste")
			(net "P0V975")
			(options
				(clearance outline)
				(anchor circle)
			)
			(primitives
				(gr_poly
					(pts
						(arc
							(start 0.1524 0.127)
							(mid 0.137521 0.162921)
							(end 0.1016 0.1778)
						)
						(arc
							(start -0.1016 0.1778)
							(mid -0.137521 0.162921)
							(end -0.1524 0.127)
						)
						(arc
							(start -0.1524 -0.127)
							(mid -0.137521 -0.162921)
							(end -0.1016 -0.1778)
						)
						(arc
							(start 0.1016 -0.1778)
							(mid 0.137521 -0.162921)
							(end 0.1524 -0.127)
						)
					)
					(width 0)
					(fill yes)
				)
			)
		)
		(pad "2" smd custom
			(at 0 0.2794 270)
			(size 0.0762 0.0762)
			(layers "B.Cu" "B.Mask" "B.Paste")
			(net "GND")
			(options
				(clearance outline)
				(anchor circle)
			)
			(primitives
				(gr_poly
					(pts
						(arc
							(start 0.1524 0.127)
							(mid 0.137521 0.162921)
							(end 0.1016 0.1778)
						)
						(arc
							(start -0.1016 0.1778)
							(mid -0.137521 0.162921)
							(end -0.1524 0.127)
						)
						(arc
							(start -0.1524 -0.127)
							(mid -0.137521 -0.162921)
							(end -0.1016 -0.1778)
						)
						(arc
							(start 0.1016 -0.1778)
							(mid 0.137521 -0.162921)
							(end 0.1524 -0.127)
						)
					)
					(width 0)
					(fill yes)
				)
			)
		)
	)
	(footprint ""
		(layer "B.Cu")
		(at 199.92848 -71.88962 90)
		(property "Reference" "C382"
			(at 0 0 90)
			(layer "B.SilkS")
			(hide yes)
			(effects
				(font
					(size 1.27 1.27)
				)
				(justify mirror)
			)
		)
		(property "Value" "SCD1U6D3V1KX-GP"
			(at 2.8321 -1.7399 90)
			(unlocked yes)
			(layer "B.Fab")
			(hide yes)
			(effects
				(font
					(size 1.016 1.016)
					(thickness 0.1524)
				)
				(justify mirror)
			)
		)
		(property "Device Type" "C0201H13"
			(at 2.8321 -3.2639 90)
			(unlocked yes)
			(layer "B.Fab")
			(hide yes)
			(effects
				(font
					(size 1.016 1.016)
					(thickness 0.1524)
				)
				(justify mirror)
			)
		)
		(duplicate_pad_numbers_are_jumpers no)
		(fp_rect
			(start 0.2794 0.6477)
			(end -0.2794 -0.6477)
			(stroke
				(width 0)
				(type default)
			)
			(fill no)
			(layer "B.CrtYd")
		)
		(fp_rect
			(start 0.2794 0.6477)
			(end -0.2794 -0.6477)
			(stroke
				(width 0)
				(type default)
			)
			(fill no)
			(layer "B.Fab")
		)
		(pad "1" smd custom
			(at 0 -0.2794 270)
			(size 0.0762 0.0762)
			(layers "B.Cu" "B.Mask" "B.Paste")
			(net "SAS0_AVDD")
			(options
				(clearance outline)
				(anchor circle)
			)
			(primitives
				(gr_poly
					(pts
						(arc
							(start 0.1524 0.127)
							(mid 0.137521 0.162921)
							(end 0.1016 0.1778)
						)
						(arc
							(start -0.1016 0.1778)
							(mid -0.137521 0.162921)
							(end -0.1524 0.127)
						)
						(arc
							(start -0.1524 -0.127)
							(mid -0.137521 -0.162921)
							(end -0.1016 -0.1778)
						)
						(arc
							(start 0.1016 -0.1778)
							(mid 0.137521 -0.162921)
							(end 0.1524 -0.127)
						)
					)
					(width 0)
					(fill yes)
				)
			)
		)
		(pad "2" smd custom
			(at 0 0.2794 270)
			(size 0.0762 0.0762)
			(layers "B.Cu" "B.Mask" "B.Paste")
			(net "GND")
			(options
				(clearance outline)
				(anchor circle)
			)
			(primitives
				(gr_poly
					(pts
						(arc
							(start 0.1524 0.127)
							(mid 0.137521 0.162921)
							(end 0.1016 0.1778)
						)
						(arc
							(start -0.1016 0.1778)
							(mid -0.137521 0.162921)
							(end -0.1524 0.127)
						)
						(arc
							(start -0.1524 -0.127)
							(mid -0.137521 -0.162921)
							(end -0.1016 -0.1778)
						)
						(arc
							(start 0.1016 -0.1778)
							(mid 0.137521 -0.162921)
							(end 0.1524 -0.127)
						)
					)
					(width 0)
					(fill yes)
				)
			)
		)
	)
	(footprint ""
		(layer "B.Cu")
		(at 38.45941 -120.075452 90)
		(property "Reference" "R339"
			(at 0 0 90)
			(layer "B.SilkS")
			(hide yes)
			(effects
				(font
					(size 1.27 1.27)
				)
				(justify mirror)
			)
		)
		(property "Value" "4K7R2F-GP"
			(at -0.064008 -3.993896 90)
			(unlocked yes)
			(layer "B.Fab")
			(hide yes)
			(effects
				(font
					(size 1.016 1.016)
					(thickness 0.1524)
				)
				(justify mirror)
			)
		)
		(property "Device Type" "R402H16"
			(at -0.064008 -5.517896 90)
			(unlocked yes)
			(layer "B.Fab")
			(hide yes)
			(effects
				(font
					(size 1.016 1.016)
					(thickness 0.1524)
				)
				(justify mirror)
			)
		)
		(duplicate_pad_numbers_are_jumpers no)
		(fp_line
			(start 0.508 -0.9398)
			(end 0.508 0.9398)
			(stroke
				(width 0.1524)
				(type default)
			)
			(layer "B.SilkS")
		)
		(fp_line
			(start -0.508 -0.9398)
			(end 0.508 -0.9398)
			(stroke
				(width 0.1524)
				(type default)
			)
			(layer "B.SilkS")
		)
		(fp_rect
			(start 0.508 0.9398)
			(end -0.508 -0.9398)
			(stroke
				(width 0)
				(type default)
			)
			(fill no)
			(layer "B.CrtYd")
		)
		(fp_rect
			(start 0.508 0.9398)
			(end -0.508 -0.9398)
			(stroke
				(width 0)
				(type default)
			)
			(fill no)
			(layer "B.Fab")
		)
		(pad "1" smd custom
			(at 0 -0.4445 270)
			(size 0.1397 0.1397)
			(layers "B.Cu" "B.Mask" "B.Paste")
			(net "P3V3_STBY")
			(options
				(clearance outline)
				(anchor circle)
			)
			(primitives
				(gr_poly
					(pts
						(arc
							(start -0.1778 0.2794)
							(mid -0.249642 0.249642)
							(end -0.2794 0.1778)
						)
						(arc
							(start -0.2794 -0.1778)
							(mid -0.249642 -0.249642)
							(end -0.1778 -0.2794)
						)
						(arc
							(start 0.1778 -0.2794)
							(mid 0.249642 -0.249642)
							(end 0.2794 -0.1778)
						)
						(arc
							(start 0.2794 0.1778)
							(mid 0.249642 0.249642)
							(end 0.1778 0.2794)
						)
					)
					(width 0)
					(fill yes)
				)
			)
		)
		(pad "2" smd custom
			(at 0 0.4445 270)
			(size 0.1397 0.1397)
			(layers "B.Cu" "B.Mask" "B.Paste")
			(net "TEMP_3_A1")
			(options
				(clearance outline)
				(anchor circle)
			)
			(primitives
				(gr_poly
					(pts
						(arc
							(start -0.1778 0.2794)
							(mid -0.249642 0.249642)
							(end -0.2794 0.1778)
						)
						(arc
							(start -0.2794 -0.1778)
							(mid -0.249642 -0.249642)
							(end -0.1778 -0.2794)
						)
						(arc
							(start 0.1778 -0.2794)
							(mid 0.249642 -0.249642)
							(end 0.2794 -0.1778)
						)
						(arc
							(start 0.2794 0.1778)
							(mid 0.249642 0.249642)
							(end 0.1778 0.2794)
						)
					)
					(width 0)
					(fill yes)
				)
			)
		)
	)
	(footprint ""
		(layer "B.Cu")
		(at 22.011386 -131.007358 180)
		(property "Reference" "R261"
			(at 0 0 0)
			(layer "B.SilkS")
			(hide yes)
			(effects
				(font
					(size 1.27 1.27)
				)
				(justify mirror)
			)
		)
		(property "Value" "120R2F-GP"
			(at -0.064008 -3.993896 180)
			(unlocked yes)
			(layer "B.Fab")
			(hide yes)
			(effects
				(font
					(size 1.016 1.016)
					(thickness 0.1524)
				)
				(justify mirror)
			)
		)
		(property "Device Type" "R402H16"
			(at -0.064008 -5.517896 180)
			(unlocked yes)
			(layer "B.Fab")
			(hide yes)
			(effects
				(font
					(size 1.016 1.016)
					(thickness 0.1524)
				)
				(justify mirror)
			)
		)
		(duplicate_pad_numbers_are_jumpers no)
		(fp_line
			(start 0.508 -0.9398)
			(end 0.508 0.9398)
			(stroke
				(width 0.1524)
				(type default)
			)
			(layer "B.SilkS")
		)
		(fp_line
			(start -0.508 -0.9398)
			(end 0.508 -0.9398)
			(stroke
				(width 0.1524)
				(type default)
			)
			(layer "B.SilkS")
		)
		(fp_rect
			(start 0.508 0.9398)
			(end -0.508 -0.9398)
			(stroke
				(width 0)
				(type default)
			)
			(fill no)
			(layer "B.CrtYd")
		)
		(fp_rect
			(start 0.508 0.9398)
			(end -0.508 -0.9398)
			(stroke
				(width 0)
				(type default)
			)
			(fill no)
			(layer "B.Fab")
		)
		(pad "1" smd custom
			(at 0 -0.4445)
			(size 0.1397 0.1397)
			(layers "B.Cu" "B.Mask" "B.Paste")
			(net "MEMA_13")
			(options
				(clearance outline)
				(anchor circle)
			)
			(primitives
				(gr_poly
					(pts
						(arc
							(start -0.1778 0.2794)
							(mid -0.249642 0.249642)
							(end -0.2794 0.1778)
						)
						(arc
							(start -0.2794 -0.1778)
							(mid -0.249642 -0.249642)
							(end -0.1778 -0.2794)
						)
						(arc
							(start 0.1778 -0.2794)
							(mid 0.249642 -0.249642)
							(end 0.2794 -0.1778)
						)
						(arc
							(start 0.2794 0.1778)
							(mid 0.249642 0.249642)
							(end 0.1778 0.2794)
						)
					)
					(width 0)
					(fill yes)
				)
			)
		)
		(pad "2" smd custom
			(at 0 0.4445)
			(size 0.1397 0.1397)
			(layers "B.Cu" "B.Mask" "B.Paste")
			(net "P1V2_STBY")
			(options
				(clearance outline)
				(anchor circle)
			)
			(primitives
				(gr_poly
					(pts
						(arc
							(start -0.1778 0.2794)
							(mid -0.249642 0.249642)
							(end -0.2794 0.1778)
						)
						(arc
							(start -0.2794 -0.1778)
							(mid -0.249642 -0.249642)
							(end -0.1778 -0.2794)
						)
						(arc
							(start 0.1778 -0.2794)
							(mid 0.249642 -0.249642)
							(end 0.2794 -0.1778)
						)
						(arc
							(start 0.2794 0.1778)
							(mid 0.249642 0.249642)
							(end 0.1778 0.2794)
						)
					)
					(width 0)
					(fill yes)
				)
			)
		)
	)
	(footprint ""
		(layer "B.Cu")
		(at 45.02404 -156.30652 -90)
		(property "Reference" "C102"
			(at 0 0 90)
			(layer "B.SilkS")
			(hide yes)
			(effects
				(font
					(size 1.27 1.27)
				)
				(justify mirror)
			)
		)
		(property "Value" "SC1U16V3KX-5GP"
			(at 0 -2.8194 270)
			(unlocked yes)
			(layer "B.Fab")
			(hide yes)
			(effects
				(font
					(size 1.016 1.016)
					(thickness 0.1524)
				)
				(justify mirror)
			)
		)
		(property "Device Type" "C603H36"
			(at 0 -4.3434 270)
			(unlocked yes)
			(layer "B.Fab")
			(hide yes)
			(effects
				(font
					(size 1.016 1.016)
					(thickness 0.1524)
				)
				(justify mirror)
			)
		)
		(duplicate_pad_numbers_are_jumpers no)
		(fp_line
			(start -0.508 0)
			(end 0.508 0)
			(stroke
				(width 0.2032)
				(type default)
			)
			(layer "B.SilkS")
		)
		(fp_rect
			(start 0.5842 1.3335)
			(end -0.5842 -1.3335)
			(stroke
				(width 0)
				(type default)
			)
			(fill no)
			(layer "B.CrtYd")
		)
		(fp_rect
			(start 0.5842 1.3335)
			(end -0.5842 -1.3335)
			(stroke
				(width 0)
				(type default)
			)
			(fill no)
			(layer "B.Fab")
		)
		(pad "1" smd custom
			(at 0 -0.762 90)
			(size 0.2159 0.2159)
			(layers "B.Cu" "B.Mask" "B.Paste")
			(net "V1PLLAV11")
			(options
				(clearance outline)
				(anchor circle)
			)
			(primitives
				(gr_poly
					(pts
						(arc
							(start -0.3302 0.4318)
							(mid -0.402042 0.402042)
							(end -0.4318 0.3302)
						)
						(arc
							(start -0.4318 -0.3302)
							(mid -0.402042 -0.402042)
							(end -0.3302 -0.4318)
						)
						(arc
							(start 0.3302 -0.4318)
							(mid 0.402042 -0.402042)
							(end 0.4318 -0.3302)
						)
						(arc
							(start 0.4318 0.3302)
							(mid 0.402042 0.402042)
							(end 0.3302 0.4318)
						)
					)
					(width 0)
					(fill yes)
				)
			)
		)
		(pad "2" smd custom
			(at 0 0.762 90)
			(size 0.2159 0.2159)
			(layers "B.Cu" "B.Mask" "B.Paste")
			(net "GND")
			(options
				(clearance outline)
				(anchor circle)
			)
			(primitives
				(gr_poly
					(pts
						(arc
							(start -0.3302 0.4318)
							(mid -0.402042 0.402042)
							(end -0.4318 0.3302)
						)
						(arc
							(start -0.4318 -0.3302)
							(mid -0.402042 -0.402042)
							(end -0.3302 -0.4318)
						)
						(arc
							(start 0.3302 -0.4318)
							(mid 0.402042 -0.402042)
							(end 0.4318 -0.3302)
						)
						(arc
							(start 0.4318 0.3302)
							(mid 0.402042 0.402042)
							(end 0.3302 0.4318)
						)
					)
					(width 0)
					(fill yes)
				)
			)
		)
	)
	(footprint ""
		(layer "B.Cu")
		(at 204.77734 -54.95036)
		(property "Reference" "C446"
			(at 0 0 0)
			(layer "B.SilkS")
			(hide yes)
			(effects
				(font
					(size 1.27 1.27)
				)
				(justify mirror)
			)
		)
		(property "Value" "SCD1U16V2KX-3GP"
			(at -1.1811 -2.7051 0)
			(unlocked yes)
			(layer "B.Fab")
			(hide yes)
			(effects
				(font
					(size 1.016 1.016)
					(thickness 0.1524)
				)
				(justify mirror)
			)
		)
		(property "Device Type" "C402H22"
			(at -1.1811 -4.2291 0)
			(unlocked yes)
			(layer "B.Fab")
			(hide yes)
			(effects
				(font
					(size 1.016 1.016)
					(thickness 0.1524)
				)
				(justify mirror)
			)
		)
		(duplicate_pad_numbers_are_jumpers no)
		(fp_rect
			(start 0.4318 0.9525)
			(end -0.4318 -0.9525)
			(stroke
				(width 0)
				(type default)
			)
			(fill no)
			(layer "B.CrtYd")
		)
		(fp_rect
			(start 0.4318 0.9525)
			(end -0.4318 -0.9525)
			(stroke
				(width 0)
				(type default)
			)
			(fill no)
			(layer "B.Fab")
		)
		(pad "1" smd custom
			(at 0 -0.4445 180)
			(size 0.1524 0.1524)
			(layers "B.Cu" "B.Mask" "B.Paste")
			(net "P1V8")
			(options
				(clearance outline)
				(anchor circle)
			)
			(primitives
				(gr_poly
					(pts
						(arc
							(start 0.3048 0.2032)
							(mid 0.275042 0.275042)
							(end 0.2032 0.3048)
						)
						(arc
							(start -0.2032 0.3048)
							(mid -0.275042 0.275042)
							(end -0.3048 0.2032)
						)
						(arc
							(start -0.3048 -0.2032)
							(mid -0.275042 -0.275042)
							(end -0.2032 -0.3048)
						)
						(arc
							(start 0.2032 -0.3048)
							(mid 0.275042 -0.275042)
							(end 0.3048 -0.2032)
						)
					)
					(width 0)
					(fill yes)
				)
			)
		)
		(pad "2" smd custom
			(at 0 0.4445 180)
			(size 0.1524 0.1524)
			(layers "B.Cu" "B.Mask" "B.Paste")
			(net "GND")
			(options
				(clearance outline)
				(anchor circle)
			)
			(primitives
				(gr_poly
					(pts
						(arc
							(start 0.3048 0.2032)
							(mid 0.275042 0.275042)
							(end 0.2032 0.3048)
						)
						(arc
							(start -0.2032 0.3048)
							(mid -0.275042 0.275042)
							(end -0.3048 0.2032)
						)
						(arc
							(start -0.3048 -0.2032)
							(mid -0.275042 -0.275042)
							(end -0.2032 -0.3048)
						)
						(arc
							(start 0.2032 -0.3048)
							(mid 0.275042 -0.275042)
							(end 0.3048 -0.2032)
						)
					)
					(width 0)
					(fill yes)
				)
			)
		)
	)
	(footprint ""
		(layer "B.Cu")
		(at 192.278 -70.3199)
		(property "Reference" "C371"
			(at 0 0 0)
			(layer "B.SilkS")
			(hide yes)
			(effects
				(font
					(size 1.27 1.27)
				)
				(justify mirror)
			)
		)
		(property "Value" "SCD1U6D3V1KX-GP"
			(at 2.8321 -1.7399 0)
			(unlocked yes)
			(layer "B.Fab")
			(hide yes)
			(effects
				(font
					(size 1.016 1.016)
					(thickness 0.1524)
				)
				(justify mirror)
			)
		)
		(property "Device Type" "C0201H13"
			(at 2.8321 -3.2639 0)
			(unlocked yes)
			(layer "B.Fab")
			(hide yes)
			(effects
				(font
					(size 1.016 1.016)
					(thickness 0.1524)
				)
				(justify mirror)
			)
		)
		(duplicate_pad_numbers_are_jumpers no)
		(fp_rect
			(start 0.2794 0.6477)
			(end -0.2794 -0.6477)
			(stroke
				(width 0)
				(type default)
			)
			(fill no)
			(layer "B.CrtYd")
		)
		(fp_rect
			(start 0.2794 0.6477)
			(end -0.2794 -0.6477)
			(stroke
				(width 0)
				(type default)
			)
			(fill no)
			(layer "B.Fab")
		)
		(pad "1" smd custom
			(at 0 -0.2794 180)
			(size 0.0762 0.0762)
			(layers "B.Cu" "B.Mask" "B.Paste")
			(net "PCE_AVDD")
			(options
				(clearance outline)
				(anchor circle)
			)
			(primitives
				(gr_poly
					(pts
						(arc
							(start 0.1524 0.127)
							(mid 0.137521 0.162921)
							(end 0.1016 0.1778)
						)
						(arc
							(start -0.1016 0.1778)
							(mid -0.137521 0.162921)
							(end -0.1524 0.127)
						)
						(arc
							(start -0.1524 -0.127)
							(mid -0.137521 -0.162921)
							(end -0.1016 -0.1778)
						)
						(arc
							(start 0.1016 -0.1778)
							(mid 0.137521 -0.162921)
							(end 0.1524 -0.127)
						)
					)
					(width 0)
					(fill yes)
				)
			)
		)
		(pad "2" smd custom
			(at 0 0.2794 180)
			(size 0.0762 0.0762)
			(layers "B.Cu" "B.Mask" "B.Paste")
			(net "GND")
			(options
				(clearance outline)
				(anchor circle)
			)
			(primitives
				(gr_poly
					(pts
						(arc
							(start 0.1524 0.127)
							(mid 0.137521 0.162921)
							(end 0.1016 0.1778)
						)
						(arc
							(start -0.1016 0.1778)
							(mid -0.137521 0.162921)
							(end -0.1524 0.127)
						)
						(arc
							(start -0.1524 -0.127)
							(mid -0.137521 -0.162921)
							(end -0.1016 -0.1778)
						)
						(arc
							(start 0.1016 -0.1778)
							(mid 0.137521 -0.162921)
							(end 0.1524 -0.127)
						)
					)
					(width 0)
					(fill yes)
				)
			)
		)
	)
	(footprint ""
		(layer "B.Cu")
		(at 210.510374 -58.689494 -90)
		(property "Reference" "TP142"
			(at 0 0 90)
			(layer "B.SilkS")
			(hide yes)
			(effects
				(font
					(size 1.27 1.27)
				)
				(justify mirror)
			)
		)
		(property "Value" "TPAD28-2-GP"
			(at 0.0127 -1.6637 270)
			(unlocked yes)
			(layer "B.Fab")
			(hide yes)
			(effects
				(font
					(size 1.016 1.016)
					(thickness 0.1524)
				)
				(justify mirror)
			)
		)
		(property "Device Type" "TPAD28"
			(at 0.0127 -3.1877 270)
			(unlocked yes)
			(layer "B.Fab")
			(hide yes)
			(effects
				(font
					(size 1.016 1.016)
					(thickness 0.1524)
				)
				(justify mirror)
			)
		)
		(duplicate_pad_numbers_are_jumpers no)
		(fp_poly
			(pts
				(arc
					(start 0 -0.3556)
					(mid 0 0.3556)
					(end 0 -0.3556)
				)
			)
			(stroke
				(width 0)
				(type default)
			)
			(fill no)
			(layer "B.CrtYd")
		)
		(fp_poly
			(pts
				(arc
					(start 0 -0.6096)
					(mid 0 0.6096)
					(end 0 -0.6096)
				)
			)
			(stroke
				(width 0)
				(type default)
			)
			(fill no)
			(layer "B.Fab")
		)
		(pad "1" smd circle
			(at 0 0 90)
			(size 0.7112 0.7112)
			(layers "B.Cu" "B.Mask" "B.Paste")
			(net "ICE1_TDI")
		)
	)
	(footprint ""
		(layer "B.Cu")
		(at 178.4096 -72.8218)
		(property "Reference" "TP102"
			(at 0 0 0)
			(layer "B.SilkS")
			(hide yes)
			(effects
				(font
					(size 1.27 1.27)
				)
				(justify mirror)
			)
		)
		(property "Value" "TPAD28-2-GP"
			(at 0.0127 -1.6637 0)
			(unlocked yes)
			(layer "B.Fab")
			(hide yes)
			(effects
				(font
					(size 1.016 1.016)
					(thickness 0.1524)
				)
				(justify mirror)
			)
		)
		(property "Device Type" "TPAD28"
			(at 0.0127 -3.1877 0)
			(unlocked yes)
			(layer "B.Fab")
			(hide yes)
			(effects
				(font
					(size 1.016 1.016)
					(thickness 0.1524)
				)
				(justify mirror)
			)
		)
		(duplicate_pad_numbers_are_jumpers no)
		(fp_poly
			(pts
				(arc
					(start 0.3556 0)
					(mid -0.3556 0)
					(end 0.3556 0)
				)
			)
			(stroke
				(width 0)
				(type default)
			)
			(fill no)
			(layer "B.CrtYd")
		)
		(fp_poly
			(pts
				(arc
					(start 0.6096 0)
					(mid -0.6096 0)
					(end 0.6096 0)
				)
			)
			(stroke
				(width 0)
				(type default)
			)
			(fill no)
			(layer "B.Fab")
		)
		(pad "1" smd circle
			(at 0 0 180)
			(size 0.7112 0.7112)
			(layers "B.Cu" "B.Mask" "B.Paste")
			(net "IOC_GPIO_17")
		)
	)
	(footprint ""
		(layer "B.Cu")
		(at 183.632094 -76.449428)
		(property "Reference" "TP156"
			(at 0 0 0)
			(layer "B.SilkS")
			(hide yes)
			(effects
				(font
					(size 1.27 1.27)
				)
				(justify mirror)
			)
		)
		(property "Value" "TPAD28-2-GP"
			(at 0.0127 -1.6637 0)
			(unlocked yes)
			(layer "B.Fab")
			(hide yes)
			(effects
				(font
					(size 1.016 1.016)
					(thickness 0.1524)
				)
				(justify mirror)
			)
		)
		(property "Device Type" "TPAD28"
			(at 0.0127 -3.1877 0)
			(unlocked yes)
			(layer "B.Fab")
			(hide yes)
			(effects
				(font
					(size 1.016 1.016)
					(thickness 0.1524)
				)
				(justify mirror)
			)
		)
		(duplicate_pad_numbers_are_jumpers no)
		(fp_poly
			(pts
				(arc
					(start 0.3556 0)
					(mid -0.3556 0)
					(end 0.3556 0)
				)
			)
			(stroke
				(width 0)
				(type default)
			)
			(fill no)
			(layer "B.CrtYd")
		)
		(fp_poly
			(pts
				(arc
					(start 0.6096 0)
					(mid -0.6096 0)
					(end 0.6096 0)
				)
			)
			(stroke
				(width 0)
				(type default)
			)
			(fill no)
			(layer "B.Fab")
		)
		(pad "1" smd circle
			(at 0 0 180)
			(size 0.7112 0.7112)
			(layers "B.Cu" "B.Mask" "B.Paste")
			(net "SPARE0")
		)
	)
	(footprint ""
		(layer "B.Cu")
		(at 67.31127 -139.596876 -90)
		(property "Reference" "C27"
			(at 0 0 90)
			(layer "B.SilkS")
			(hide yes)
			(effects
				(font
					(size 1.27 1.27)
				)
				(justify mirror)
			)
		)
		(property "Value" "SCD1U16V2KX-3GP"
			(at -1.1811 -2.7051 270)
			(unlocked yes)
			(layer "B.Fab")
			(hide yes)
			(effects
				(font
					(size 1.016 1.016)
					(thickness 0.1524)
				)
				(justify mirror)
			)
		)
		(property "Device Type" "C402H22"
			(at -1.1811 -4.2291 270)
			(unlocked yes)
			(layer "B.Fab")
			(hide yes)
			(effects
				(font
					(size 1.016 1.016)
					(thickness 0.1524)
				)
				(justify mirror)
			)
		)
		(duplicate_pad_numbers_are_jumpers no)
		(fp_rect
			(start 0.4318 0.9525)
			(end -0.4318 -0.9525)
			(stroke
				(width 0)
				(type default)
			)
			(fill no)
			(layer "B.CrtYd")
		)
		(fp_rect
			(start 0.4318 0.9525)
			(end -0.4318 -0.9525)
			(stroke
				(width 0)
				(type default)
			)
			(fill no)
			(layer "B.Fab")
		)
		(pad "1" smd custom
			(at 0 -0.4445 90)
			(size 0.1524 0.1524)
			(layers "B.Cu" "B.Mask" "B.Paste")
			(net "P3V3_STBY")
			(options
				(clearance outline)
				(anchor circle)
			)
			(primitives
				(gr_poly
					(pts
						(arc
							(start 0.3048 0.2032)
							(mid 0.275042 0.275042)
							(end 0.2032 0.3048)
						)
						(arc
							(start -0.2032 0.3048)
							(mid -0.275042 0.275042)
							(end -0.3048 0.2032)
						)
						(arc
							(start -0.3048 -0.2032)
							(mid -0.275042 -0.275042)
							(end -0.2032 -0.3048)
						)
						(arc
							(start 0.2032 -0.3048)
							(mid 0.275042 -0.275042)
							(end 0.3048 -0.2032)
						)
					)
					(width 0)
					(fill yes)
				)
			)
		)
		(pad "2" smd custom
			(at 0 0.4445 90)
			(size 0.1524 0.1524)
			(layers "B.Cu" "B.Mask" "B.Paste")
			(net "GND")
			(options
				(clearance outline)
				(anchor circle)
			)
			(primitives
				(gr_poly
					(pts
						(arc
							(start 0.3048 0.2032)
							(mid 0.275042 0.275042)
							(end 0.2032 0.3048)
						)
						(arc
							(start -0.2032 0.3048)
							(mid -0.275042 0.275042)
							(end -0.3048 0.2032)
						)
						(arc
							(start -0.3048 -0.2032)
							(mid -0.275042 -0.275042)
							(end -0.2032 -0.3048)
						)
						(arc
							(start 0.2032 -0.3048)
							(mid 0.275042 -0.275042)
							(end 0.3048 -0.2032)
						)
					)
					(width 0)
					(fill yes)
				)
			)
		)
	)
	(footprint ""
		(layer "B.Cu")
		(at 200.4314 -56.9976 -90)
		(property "Reference" "C441"
			(at 0 0 90)
			(layer "B.SilkS")
			(hide yes)
			(effects
				(font
					(size 1.27 1.27)
				)
				(justify mirror)
			)
		)
		(property "Value" "SCD1U16V2KX-3GP"
			(at -1.1811 -2.7051 270)
			(unlocked yes)
			(layer "B.Fab")
			(hide yes)
			(effects
				(font
					(size 1.016 1.016)
					(thickness 0.1524)
				)
				(justify mirror)
			)
		)
		(property "Device Type" "C402H22"
			(at -1.1811 -4.2291 270)
			(unlocked yes)
			(layer "B.Fab")
			(hide yes)
			(effects
				(font
					(size 1.016 1.016)
					(thickness 0.1524)
				)
				(justify mirror)
			)
		)
		(duplicate_pad_numbers_are_jumpers no)
		(fp_rect
			(start 0.4318 0.9525)
			(end -0.4318 -0.9525)
			(stroke
				(width 0)
				(type default)
			)
			(fill no)
			(layer "B.CrtYd")
		)
		(fp_rect
			(start 0.4318 0.9525)
			(end -0.4318 -0.9525)
			(stroke
				(width 0)
				(type default)
			)
			(fill no)
			(layer "B.Fab")
		)
		(pad "1" smd custom
			(at 0 -0.4445 90)
			(size 0.1524 0.1524)
			(layers "B.Cu" "B.Mask" "B.Paste")
			(net "P1V8")
			(options
				(clearance outline)
				(anchor circle)
			)
			(primitives
				(gr_poly
					(pts
						(arc
							(start 0.3048 0.2032)
							(mid 0.275042 0.275042)
							(end 0.2032 0.3048)
						)
						(arc
							(start -0.2032 0.3048)
							(mid -0.275042 0.275042)
							(end -0.3048 0.2032)
						)
						(arc
							(start -0.3048 -0.2032)
							(mid -0.275042 -0.275042)
							(end -0.2032 -0.3048)
						)
						(arc
							(start 0.2032 -0.3048)
							(mid 0.275042 -0.275042)
							(end 0.3048 -0.2032)
						)
					)
					(width 0)
					(fill yes)
				)
			)
		)
		(pad "2" smd custom
			(at 0 0.4445 90)
			(size 0.1524 0.1524)
			(layers "B.Cu" "B.Mask" "B.Paste")
			(net "GND")
			(options
				(clearance outline)
				(anchor circle)
			)
			(primitives
				(gr_poly
					(pts
						(arc
							(start 0.3048 0.2032)
							(mid 0.275042 0.275042)
							(end 0.2032 0.3048)
						)
						(arc
							(start -0.2032 0.3048)
							(mid -0.275042 0.275042)
							(end -0.3048 0.2032)
						)
						(arc
							(start -0.3048 -0.2032)
							(mid -0.275042 -0.275042)
							(end -0.2032 -0.3048)
						)
						(arc
							(start 0.2032 -0.3048)
							(mid 0.275042 -0.275042)
							(end 0.3048 -0.2032)
						)
					)
					(width 0)
					(fill yes)
				)
			)
		)
	)
	(footprint ""
		(layer "B.Cu")
		(at 50.4444 -135.763 180)
		(property "Reference" "R291"
			(at 0 0 0)
			(layer "B.SilkS")
			(hide yes)
			(effects
				(font
					(size 1.27 1.27)
				)
				(justify mirror)
			)
		)
		(property "Value" "0R2J-2-GP"
			(at -0.064008 -3.993896 180)
			(unlocked yes)
			(layer "B.Fab")
			(hide yes)
			(effects
				(font
					(size 1.016 1.016)
					(thickness 0.1524)
				)
				(justify mirror)
			)
		)
		(property "Device Type" "R402H16"
			(at -0.064008 -5.517896 180)
			(unlocked yes)
			(layer "B.Fab")
			(hide yes)
			(effects
				(font
					(size 1.016 1.016)
					(thickness 0.1524)
				)
				(justify mirror)
			)
		)
		(duplicate_pad_numbers_are_jumpers no)
		(fp_line
			(start 0.508 -0.9398)
			(end 0.508 0.9398)
			(stroke
				(width 0.1524)
				(type default)
			)
			(layer "B.SilkS")
		)
		(fp_line
			(start -0.508 -0.9398)
			(end 0.508 -0.9398)
			(stroke
				(width 0.1524)
				(type default)
			)
			(layer "B.SilkS")
		)
		(fp_rect
			(start 0.508 0.9398)
			(end -0.508 -0.9398)
			(stroke
				(width 0)
				(type default)
			)
			(fill no)
			(layer "B.CrtYd")
		)
		(fp_rect
			(start 0.508 0.9398)
			(end -0.508 -0.9398)
			(stroke
				(width 0)
				(type default)
			)
			(fill no)
			(layer "B.Fab")
		)
		(pad "1" smd custom
			(at 0 -0.4445)
			(size 0.1397 0.1397)
			(layers "B.Cu" "B.Mask" "B.Paste")
			(net "DPB_MISC_ALERT_OUT")
			(options
				(clearance outline)
				(anchor circle)
			)
			(primitives
				(gr_poly
					(pts
						(arc
							(start -0.1778 0.2794)
							(mid -0.249642 0.249642)
							(end -0.2794 0.1778)
						)
						(arc
							(start -0.2794 -0.1778)
							(mid -0.249642 -0.249642)
							(end -0.1778 -0.2794)
						)
						(arc
							(start 0.1778 -0.2794)
							(mid 0.249642 -0.249642)
							(end 0.2794 -0.1778)
						)
						(arc
							(start 0.2794 0.1778)
							(mid 0.249642 0.249642)
							(end 0.1778 0.2794)
						)
					)
					(width 0)
					(fill yes)
				)
			)
		)
		(pad "2" smd custom
			(at 0 0.4445)
			(size 0.1397 0.1397)
			(layers "B.Cu" "B.Mask" "B.Paste")
			(net "DPB_MISC_ALERT_O_R")
			(options
				(clearance outline)
				(anchor circle)
			)
			(primitives
				(gr_poly
					(pts
						(arc
							(start -0.1778 0.2794)
							(mid -0.249642 0.249642)
							(end -0.2794 0.1778)
						)
						(arc
							(start -0.2794 -0.1778)
							(mid -0.249642 -0.249642)
							(end -0.1778 -0.2794)
						)
						(arc
							(start 0.1778 -0.2794)
							(mid 0.249642 -0.249642)
							(end 0.2794 -0.1778)
						)
						(arc
							(start 0.2794 0.1778)
							(mid 0.249642 0.249642)
							(end 0.1778 0.2794)
						)
					)
					(width 0)
					(fill yes)
				)
			)
		)
	)
	(footprint ""
		(layer "B.Cu")
		(at 79.826866 -58.205878 90)
		(property "Reference" "C188"
			(at 0 0 90)
			(layer "B.SilkS")
			(hide yes)
			(effects
				(font
					(size 1.27 1.27)
				)
				(justify mirror)
			)
		)
		(property "Value" "SC10U6D3V5KX-4GP"
			(at 0.0762 -6.1214 90)
			(unlocked yes)
			(layer "B.Fab")
			(hide yes)
			(effects
				(font
					(size 1.016 1.016)
					(thickness 0.1524)
				)
				(justify mirror)
			)
		)
		(property "Device Type" "C805H58"
			(at 0.0762 -8.1534 90)
			(unlocked yes)
			(layer "B.Fab")
			(hide yes)
			(effects
				(font
					(size 1.016 1.016)
					(thickness 0.1524)
				)
				(justify mirror)
			)
		)
		(duplicate_pad_numbers_are_jumpers no)
		(fp_line
			(start -0.635 0)
			(end 0.635 0)
			(stroke
				(width 0.508)
				(type default)
			)
			(layer "B.SilkS")
		)
		(fp_rect
			(start 0.9652 1.778)
			(end -0.9652 -1.778)
			(stroke
				(width 0)
				(type default)
			)
			(fill no)
			(layer "B.CrtYd")
		)
		(fp_poly
			(pts
				(xy 0.9652 -1.778) (xy -0.9652 -1.778) (xy -0.9652 1.778) (xy 0.9652 1.778)
			)
			(stroke
				(width 0)
				(type default)
			)
			(fill no)
			(layer "B.Fab")
		)
		(pad "1" smd rect
			(at 0 -0.9652 270)
			(size 1.397 1.143)
			(layers "B.Cu" "B.Mask" "B.Paste")
			(net "P3V3")
		)
		(pad "2" smd rect
			(at 0 0.9652 270)
			(size 1.397 1.143)
			(layers "B.Cu" "B.Mask" "B.Paste")
			(net "GND")
		)
	)
	(footprint ""
		(layer "B.Cu")
		(at 62.996318 -144.769078 90)
		(property "Reference" "R202"
			(at 0 0 90)
			(layer "B.SilkS")
			(hide yes)
			(effects
				(font
					(size 1.27 1.27)
				)
				(justify mirror)
			)
		)
		(property "Value" "2K2R2F-GP"
			(at -0.064008 -3.993896 90)
			(unlocked yes)
			(layer "B.Fab")
			(hide yes)
			(effects
				(font
					(size 1.016 1.016)
					(thickness 0.1524)
				)
				(justify mirror)
			)
		)
		(property "Device Type" "R402H16"
			(at -0.064008 -5.517896 90)
			(unlocked yes)
			(layer "B.Fab")
			(hide yes)
			(effects
				(font
					(size 1.016 1.016)
					(thickness 0.1524)
				)
				(justify mirror)
			)
		)
		(duplicate_pad_numbers_are_jumpers no)
		(fp_line
			(start 0.508 -0.9398)
			(end 0.508 0.9398)
			(stroke
				(width 0.1524)
				(type default)
			)
			(layer "B.SilkS")
		)
		(fp_line
			(start -0.508 -0.9398)
			(end 0.508 -0.9398)
			(stroke
				(width 0.1524)
				(type default)
			)
			(layer "B.SilkS")
		)
		(fp_rect
			(start 0.508 0.9398)
			(end -0.508 -0.9398)
			(stroke
				(width 0)
				(type default)
			)
			(fill no)
			(layer "B.CrtYd")
		)
		(fp_rect
			(start 0.508 0.9398)
			(end -0.508 -0.9398)
			(stroke
				(width 0)
				(type default)
			)
			(fill no)
			(layer "B.Fab")
		)
		(pad "1" smd custom
			(at 0 -0.4445 270)
			(size 0.1397 0.1397)
			(layers "B.Cu" "B.Mask" "B.Paste")
			(net "I2C_MEZZ_FRU_SENSOR_SDA")
			(options
				(clearance outline)
				(anchor circle)
			)
			(primitives
				(gr_poly
					(pts
						(arc
							(start -0.1778 0.2794)
							(mid -0.249642 0.249642)
							(end -0.2794 0.1778)
						)
						(arc
							(start -0.2794 -0.1778)
							(mid -0.249642 -0.249642)
							(end -0.1778 -0.2794)
						)
						(arc
							(start 0.1778 -0.2794)
							(mid 0.249642 -0.249642)
							(end 0.2794 -0.1778)
						)
						(arc
							(start 0.2794 0.1778)
							(mid 0.249642 0.249642)
							(end 0.1778 0.2794)
						)
					)
					(width 0)
					(fill yes)
				)
			)
		)
		(pad "2" smd custom
			(at 0 0.4445 270)
			(size 0.1397 0.1397)
			(layers "B.Cu" "B.Mask" "B.Paste")
			(net "P3V3_STBY")
			(options
				(clearance outline)
				(anchor circle)
			)
			(primitives
				(gr_poly
					(pts
						(arc
							(start -0.1778 0.2794)
							(mid -0.249642 0.249642)
							(end -0.2794 0.1778)
						)
						(arc
							(start -0.2794 -0.1778)
							(mid -0.249642 -0.249642)
							(end -0.1778 -0.2794)
						)
						(arc
							(start 0.1778 -0.2794)
							(mid 0.249642 -0.249642)
							(end 0.2794 -0.1778)
						)
						(arc
							(start 0.2794 0.1778)
							(mid 0.249642 0.249642)
							(end 0.1778 0.2794)
						)
					)
					(width 0)
					(fill yes)
				)
			)
		)
	)
	(footprint ""
		(layer "B.Cu")
		(at 192.405 -62.1792 90)
		(property "Reference" "C410"
			(at 0 0 90)
			(layer "B.SilkS")
			(hide yes)
			(effects
				(font
					(size 1.27 1.27)
				)
				(justify mirror)
			)
		)
		(property "Value" "SCD1U6D3V1KX-GP"
			(at 2.8321 -1.7399 90)
			(unlocked yes)
			(layer "B.Fab")
			(hide yes)
			(effects
				(font
					(size 1.016 1.016)
					(thickness 0.1524)
				)
				(justify mirror)
			)
		)
		(property "Device Type" "C0201H13"
			(at 2.8321 -3.2639 90)
			(unlocked yes)
			(layer "B.Fab")
			(hide yes)
			(effects
				(font
					(size 1.016 1.016)
					(thickness 0.1524)
				)
				(justify mirror)
			)
		)
		(duplicate_pad_numbers_are_jumpers no)
		(fp_rect
			(start 0.2794 0.6477)
			(end -0.2794 -0.6477)
			(stroke
				(width 0)
				(type default)
			)
			(fill no)
			(layer "B.CrtYd")
		)
		(fp_rect
			(start 0.2794 0.6477)
			(end -0.2794 -0.6477)
			(stroke
				(width 0)
				(type default)
			)
			(fill no)
			(layer "B.Fab")
		)
		(pad "1" smd custom
			(at 0 -0.2794 270)
			(size 0.0762 0.0762)
			(layers "B.Cu" "B.Mask" "B.Paste")
			(net "P0V975")
			(options
				(clearance outline)
				(anchor circle)
			)
			(primitives
				(gr_poly
					(pts
						(arc
							(start 0.1524 0.127)
							(mid 0.137521 0.162921)
							(end 0.1016 0.1778)
						)
						(arc
							(start -0.1016 0.1778)
							(mid -0.137521 0.162921)
							(end -0.1524 0.127)
						)
						(arc
							(start -0.1524 -0.127)
							(mid -0.137521 -0.162921)
							(end -0.1016 -0.1778)
						)
						(arc
							(start 0.1016 -0.1778)
							(mid 0.137521 -0.162921)
							(end 0.1524 -0.127)
						)
					)
					(width 0)
					(fill yes)
				)
			)
		)
		(pad "2" smd custom
			(at 0 0.2794 270)
			(size 0.0762 0.0762)
			(layers "B.Cu" "B.Mask" "B.Paste")
			(net "GND")
			(options
				(clearance outline)
				(anchor circle)
			)
			(primitives
				(gr_poly
					(pts
						(arc
							(start 0.1524 0.127)
							(mid 0.137521 0.162921)
							(end 0.1016 0.1778)
						)
						(arc
							(start -0.1016 0.1778)
							(mid -0.137521 0.162921)
							(end -0.1524 0.127)
						)
						(arc
							(start -0.1524 -0.127)
							(mid -0.137521 -0.162921)
							(end -0.1016 -0.1778)
						)
						(arc
							(start 0.1016 -0.1778)
							(mid 0.137521 -0.162921)
							(end 0.1524 -0.127)
						)
					)
					(width 0)
					(fill yes)
				)
			)
		)
	)
	(footprint ""
		(layer "B.Cu")
		(at 61.4934 -148.5138 180)
		(property "Reference" "R389"
			(at 0 0 0)
			(layer "B.SilkS")
			(hide yes)
			(effects
				(font
					(size 1.27 1.27)
				)
				(justify mirror)
			)
		)
		(property "Value" "4K7R2F-GP"
			(at -0.064008 -3.993896 180)
			(unlocked yes)
			(layer "B.Fab")
			(hide yes)
			(effects
				(font
					(size 1.016 1.016)
					(thickness 0.1524)
				)
				(justify mirror)
			)
		)
		(property "Device Type" "R402H16"
			(at -0.064008 -5.517896 180)
			(unlocked yes)
			(layer "B.Fab")
			(hide yes)
			(effects
				(font
					(size 1.016 1.016)
					(thickness 0.1524)
				)
				(justify mirror)
			)
		)
		(duplicate_pad_numbers_are_jumpers no)
		(fp_line
			(start 0.508 -0.9398)
			(end 0.508 0.9398)
			(stroke
				(width 0.1524)
				(type default)
			)
			(layer "B.SilkS")
		)
		(fp_line
			(start -0.508 -0.9398)
			(end 0.508 -0.9398)
			(stroke
				(width 0.1524)
				(type default)
			)
			(layer "B.SilkS")
		)
		(fp_rect
			(start 0.508 0.9398)
			(end -0.508 -0.9398)
			(stroke
				(width 0)
				(type default)
			)
			(fill no)
			(layer "B.CrtYd")
		)
		(fp_rect
			(start 0.508 0.9398)
			(end -0.508 -0.9398)
			(stroke
				(width 0)
				(type default)
			)
			(fill no)
			(layer "B.Fab")
		)
		(pad "1" smd custom
			(at 0 -0.4445)
			(size 0.1397 0.1397)
			(layers "B.Cu" "B.Mask" "B.Paste")
			(net "GND")
			(options
				(clearance outline)
				(anchor circle)
			)
			(primitives
				(gr_poly
					(pts
						(arc
							(start -0.1778 0.2794)
							(mid -0.249642 0.249642)
							(end -0.2794 0.1778)
						)
						(arc
							(start -0.2794 -0.1778)
							(mid -0.249642 -0.249642)
							(end -0.1778 -0.2794)
						)
						(arc
							(start 0.1778 -0.2794)
							(mid 0.249642 -0.249642)
							(end 0.2794 -0.1778)
						)
						(arc
							(start 0.2794 0.1778)
							(mid 0.249642 0.249642)
							(end 0.1778 0.2794)
						)
					)
					(width 0)
					(fill yes)
				)
			)
		)
		(pad "2" smd custom
			(at 0 0.4445)
			(size 0.1397 0.1397)
			(layers "B.Cu" "B.Mask" "B.Paste")
			(net "MAC1_TXD3")
			(options
				(clearance outline)
				(anchor circle)
			)
			(primitives
				(gr_poly
					(pts
						(arc
							(start -0.1778 0.2794)
							(mid -0.249642 0.249642)
							(end -0.2794 0.1778)
						)
						(arc
							(start -0.2794 -0.1778)
							(mid -0.249642 -0.249642)
							(end -0.1778 -0.2794)
						)
						(arc
							(start 0.1778 -0.2794)
							(mid 0.249642 -0.249642)
							(end 0.2794 -0.1778)
						)
						(arc
							(start 0.2794 0.1778)
							(mid 0.249642 0.249642)
							(end 0.1778 0.2794)
						)
					)
					(width 0)
					(fill yes)
				)
			)
		)
	)
	(footprint ""
		(layer "B.Cu")
		(at 80.6196 -130.048 -90)
		(property "Reference" "U103"
			(at 0 0 90)
			(layer "B.SilkS")
			(hide yes)
			(effects
				(font
					(size 1.27 1.27)
				)
				(justify mirror)
			)
		)
		(property "Value" "SNLVC1G126DCKR-GP"
			(at 2.3368 -8.6868 270)
			(unlocked yes)
			(layer "B.Fab")
			(hide yes)
			(effects
				(font
					(size 1.016 1.016)
					(thickness 0.1524)
				)
				(justify mirror)
			)
		)
		(property "Device Type" "SC70-5H44"
			(at 2.3114 -10.414 270)
			(unlocked yes)
			(layer "B.Fab")
			(hide yes)
			(effects
				(font
					(size 1.016 1.016)
					(thickness 0.1524)
				)
				(justify mirror)
			)
		)
		(duplicate_pad_numbers_are_jumpers no)
		(fp_line
			(start -1.27 1.7018)
			(end 1.27 1.7018)
			(stroke
				(width 0.1524)
				(type default)
			)
			(layer "B.SilkS")
		)
		(fp_line
			(start 1.27 1.7018)
			(end 1.27 -1.7018)
			(stroke
				(width 0.1524)
				(type default)
			)
			(layer "B.SilkS")
		)
		(fp_line
			(start -1.27 -1.7018)
			(end -1.27 1.7018)
			(stroke
				(width 0.1524)
				(type default)
			)
			(layer "B.SilkS")
		)
		(fp_line
			(start 1.27 -1.7018)
			(end -1.27 -1.7018)
			(stroke
				(width 0.1524)
				(type default)
			)
			(layer "B.SilkS")
		)
		(fp_line
			(start -1.3843 -1.8034)
			(end -1.3843 -1.1176)
			(stroke
				(width 0.3302)
				(type default)
			)
			(layer "B.SilkS")
		)
		(fp_line
			(start -0.6604 -1.8034)
			(end -1.3843 -1.8034)
			(stroke
				(width 0.3302)
				(type default)
			)
			(layer "B.SilkS")
		)
		(fp_rect
			(start 1.524 1.9558)
			(end -1.524 -1.9558)
			(stroke
				(width 0)
				(type default)
			)
			(fill no)
			(layer "B.CrtYd")
		)
		(fp_poly
			(pts
				(xy 1.524 -1.9558) (xy -1.524 -1.9558) (xy -1.524 1.9558) (xy 1.524 1.9558)
			)
			(stroke
				(width 0)
				(type default)
			)
			(fill no)
			(layer "B.Fab")
		)
		(pad "1" smd rect
			(at -0.65024 -0.8255 90)
			(size 0.4064 1.2192)
			(layers "B.Cu" "B.Mask" "B.Paste")
			(net "PWRGD_P3V3_STBY")
		)
		(pad "2" smd rect
			(at 0 -0.8255 90)
			(size 0.4064 1.2192)
			(layers "B.Cu" "B.Mask" "B.Paste")
			(net "BMC_TO_EXP_RESET_OUT_R")
		)
		(pad "3" smd rect
			(at 0.65024 -0.8255 90)
			(size 0.4064 1.2192)
			(layers "B.Cu" "B.Mask" "B.Paste")
			(net "GND")
		)
		(pad "4" smd rect
			(at 0.65024 0.8255 90)
			(size 0.4064 1.2192)
			(layers "B.Cu" "B.Mask" "B.Paste")
			(net "BMC_TO_EXP_RESET_N")
		)
		(pad "5" smd rect
			(at -0.65024 0.8255 90)
			(size 0.4064 1.2192)
			(layers "B.Cu" "B.Mask" "B.Paste")
			(net "P3V3_STBY")
		)
	)
	(footprint ""
		(layer "B.Cu")
		(at 90.880184 -138.48588 -90)
		(property "Reference" "R721"
			(at 0 0 90)
			(layer "B.SilkS")
			(hide yes)
			(effects
				(font
					(size 1.27 1.27)
				)
				(justify mirror)
			)
		)
		(property "Value" "4K7R2F-GP"
			(at -0.064008 -3.993896 270)
			(unlocked yes)
			(layer "B.Fab")
			(hide yes)
			(effects
				(font
					(size 1.016 1.016)
					(thickness 0.1524)
				)
				(justify mirror)
			)
		)
		(property "Device Type" "R402H16"
			(at -0.064008 -5.517896 270)
			(unlocked yes)
			(layer "B.Fab")
			(hide yes)
			(effects
				(font
					(size 1.016 1.016)
					(thickness 0.1524)
				)
				(justify mirror)
			)
		)
		(duplicate_pad_numbers_are_jumpers no)
		(fp_line
			(start -0.508 -0.9398)
			(end 0.508 -0.9398)
			(stroke
				(width 0.1524)
				(type default)
			)
			(layer "B.SilkS")
		)
		(fp_line
			(start 0.508 -0.9398)
			(end 0.508 0.9398)
			(stroke
				(width 0.1524)
				(type default)
			)
			(layer "B.SilkS")
		)
		(fp_rect
			(start 0.508 0.9398)
			(end -0.508 -0.9398)
			(stroke
				(width 0)
				(type default)
			)
			(fill no)
			(layer "B.CrtYd")
		)
		(fp_rect
			(start 0.508 0.9398)
			(end -0.508 -0.9398)
			(stroke
				(width 0)
				(type default)
			)
			(fill no)
			(layer "B.Fab")
		)
		(pad "1" smd custom
			(at 0 -0.4445 90)
			(size 0.1397 0.1397)
			(layers "B.Cu" "B.Mask" "B.Paste")
			(net "P3V3_STBY")
			(options
				(clearance outline)
				(anchor circle)
			)
			(primitives
				(gr_poly
					(pts
						(arc
							(start -0.1778 0.2794)
							(mid -0.249642 0.249642)
							(end -0.2794 0.1778)
						)
						(arc
							(start -0.2794 -0.1778)
							(mid -0.249642 -0.249642)
							(end -0.1778 -0.2794)
						)
						(arc
							(start 0.1778 -0.2794)
							(mid 0.249642 -0.249642)
							(end 0.2794 -0.1778)
						)
						(arc
							(start 0.2794 0.1778)
							(mid 0.249642 0.249642)
							(end 0.1778 0.2794)
						)
					)
					(width 0)
					(fill yes)
				)
			)
		)
		(pad "2" smd custom
			(at 0 0.4445 90)
			(size 0.1397 0.1397)
			(layers "B.Cu" "B.Mask" "B.Paste")
			(net "DEBUG_HDR_UART_SEL")
			(options
				(clearance outline)
				(anchor circle)
			)
			(primitives
				(gr_poly
					(pts
						(arc
							(start -0.1778 0.2794)
							(mid -0.249642 0.249642)
							(end -0.2794 0.1778)
						)
						(arc
							(start -0.2794 -0.1778)
							(mid -0.249642 -0.249642)
							(end -0.1778 -0.2794)
						)
						(arc
							(start 0.1778 -0.2794)
							(mid 0.249642 -0.249642)
							(end 0.2794 -0.1778)
						)
						(arc
							(start 0.2794 0.1778)
							(mid 0.249642 0.249642)
							(end 0.1778 0.2794)
						)
					)
					(width 0)
					(fill yes)
				)
			)
		)
	)
	(footprint ""
		(layer "B.Cu")
		(at 174.5742 -67.3354 90)
		(property "Reference" "R577"
			(at 0 0 90)
			(layer "B.SilkS")
			(hide yes)
			(effects
				(font
					(size 1.27 1.27)
				)
				(justify mirror)
			)
		)
		(property "Value" "2K2R2F-GP"
			(at -0.064008 -3.993896 90)
			(unlocked yes)
			(layer "B.Fab")
			(hide yes)
			(effects
				(font
					(size 1.016 1.016)
					(thickness 0.1524)
				)
				(justify mirror)
			)
		)
		(property "Device Type" "R402H16"
			(at -0.064008 -5.517896 90)
			(unlocked yes)
			(layer "B.Fab")
			(hide yes)
			(effects
				(font
					(size 1.016 1.016)
					(thickness 0.1524)
				)
				(justify mirror)
			)
		)
		(duplicate_pad_numbers_are_jumpers no)
		(fp_line
			(start 0.508 -0.9398)
			(end 0.508 0.9398)
			(stroke
				(width 0.1524)
				(type default)
			)
			(layer "B.SilkS")
		)
		(fp_line
			(start -0.508 -0.9398)
			(end 0.508 -0.9398)
			(stroke
				(width 0.1524)
				(type default)
			)
			(layer "B.SilkS")
		)
		(fp_rect
			(start 0.508 0.9398)
			(end -0.508 -0.9398)
			(stroke
				(width 0)
				(type default)
			)
			(fill no)
			(layer "B.CrtYd")
		)
		(fp_rect
			(start 0.508 0.9398)
			(end -0.508 -0.9398)
			(stroke
				(width 0)
				(type default)
			)
			(fill no)
			(layer "B.Fab")
		)
		(pad "1" smd custom
			(at 0 -0.4445 270)
			(size 0.1397 0.1397)
			(layers "B.Cu" "B.Mask" "B.Paste")
			(net "P1V8")
			(options
				(clearance outline)
				(anchor circle)
			)
			(primitives
				(gr_poly
					(pts
						(arc
							(start -0.1778 0.2794)
							(mid -0.249642 0.249642)
							(end -0.2794 0.1778)
						)
						(arc
							(start -0.2794 -0.1778)
							(mid -0.249642 -0.249642)
							(end -0.1778 -0.2794)
						)
						(arc
							(start 0.1778 -0.2794)
							(mid 0.249642 -0.249642)
							(end 0.2794 -0.1778)
						)
						(arc
							(start 0.2794 0.1778)
							(mid 0.249642 0.249642)
							(end 0.1778 0.2794)
						)
					)
					(width 0)
					(fill yes)
				)
			)
		)
		(pad "2" smd custom
			(at 0 0.4445 270)
			(size 0.1397 0.1397)
			(layers "B.Cu" "B.Mask" "B.Paste")
			(net "IOC_SDA_2")
			(options
				(clearance outline)
				(anchor circle)
			)
			(primitives
				(gr_poly
					(pts
						(arc
							(start -0.1778 0.2794)
							(mid -0.249642 0.249642)
							(end -0.2794 0.1778)
						)
						(arc
							(start -0.2794 -0.1778)
							(mid -0.249642 -0.249642)
							(end -0.1778 -0.2794)
						)
						(arc
							(start 0.1778 -0.2794)
							(mid 0.249642 -0.249642)
							(end 0.2794 -0.1778)
						)
						(arc
							(start 0.2794 0.1778)
							(mid 0.249642 0.249642)
							(end 0.1778 0.2794)
						)
					)
					(width 0)
					(fill yes)
				)
			)
		)
	)
	(footprint ""
		(layer "B.Cu")
		(at 56.80456 -156.29128 -90)
		(property "Reference" "L2"
			(at 0 0 90)
			(layer "B.SilkS")
			(hide yes)
			(effects
				(font
					(size 1.27 1.27)
				)
				(justify mirror)
			)
		)
		(property "Value" "MMZ2012S601ATA1N-GP"
			(at 0 -4.2418 270)
			(unlocked yes)
			(layer "B.Fab")
			(hide yes)
			(effects
				(font
					(size 1.016 1.016)
					(thickness 0.1524)
				)
				(justify mirror)
			)
		)
		(property "Device Type" "L805H42"
			(at 0 -5.7912 270)
			(unlocked yes)
			(layer "B.Fab")
			(hide yes)
			(effects
				(font
					(size 1.016 1.016)
					(thickness 0.1524)
				)
				(justify mirror)
			)
		)
		(duplicate_pad_numbers_are_jumpers no)
		(fp_line
			(start -0.889 1.7018)
			(end 0.889 1.7018)
			(stroke
				(width 0.1524)
				(type default)
			)
			(layer "B.SilkS")
		)
		(fp_line
			(start 0.889 1.7018)
			(end 0.889 -1.7018)
			(stroke
				(width 0.1524)
				(type default)
			)
			(layer "B.SilkS")
		)
		(fp_line
			(start -0.889 -1.7018)
			(end -0.889 1.7018)
			(stroke
				(width 0.1524)
				(type default)
			)
			(layer "B.SilkS")
		)
		(fp_line
			(start 0.889 -1.7018)
			(end -0.889 -1.7018)
			(stroke
				(width 0.1524)
				(type default)
			)
			(layer "B.SilkS")
		)
		(fp_rect
			(start 0.9652 1.778)
			(end -0.9652 -1.778)
			(stroke
				(width 0)
				(type default)
			)
			(fill no)
			(layer "B.CrtYd")
		)
		(fp_rect
			(start 0.9652 1.778)
			(end -0.9652 -1.778)
			(stroke
				(width 0)
				(type default)
			)
			(fill no)
			(layer "B.Fab")
		)
		(pad "1" smd rect
			(at 0 -0.9652 90)
			(size 1.397 1.143)
			(layers "B.Cu" "B.Mask" "B.Paste")
			(net "P3V3_STBY")
		)
		(pad "2" smd rect
			(at 0 0.9652 90)
			(size 1.397 1.143)
			(layers "B.Cu" "B.Mask" "B.Paste")
			(net "ADCAV33")
		)
	)
	(footprint ""
		(layer "B.Cu")
		(at 195.206366 -50.204116 180)
		(property "Reference" "R618"
			(at 0 0 0)
			(layer "B.SilkS")
			(hide yes)
			(effects
				(font
					(size 1.27 1.27)
				)
				(justify mirror)
			)
		)
		(property "Value" "10KR2F-2-GP"
			(at -0.064008 -3.993896 180)
			(unlocked yes)
			(layer "B.Fab")
			(hide yes)
			(effects
				(font
					(size 1.016 1.016)
					(thickness 0.1524)
				)
				(justify mirror)
			)
		)
		(property "Device Type" "R402H16"
			(at -0.064008 -5.517896 180)
			(unlocked yes)
			(layer "B.Fab")
			(hide yes)
			(effects
				(font
					(size 1.016 1.016)
					(thickness 0.1524)
				)
				(justify mirror)
			)
		)
		(duplicate_pad_numbers_are_jumpers no)
		(fp_line
			(start 0.508 -0.9398)
			(end 0.508 0.9398)
			(stroke
				(width 0.1524)
				(type default)
			)
			(layer "B.SilkS")
		)
		(fp_line
			(start -0.508 -0.9398)
			(end 0.508 -0.9398)
			(stroke
				(width 0.1524)
				(type default)
			)
			(layer "B.SilkS")
		)
		(fp_rect
			(start 0.508 0.9398)
			(end -0.508 -0.9398)
			(stroke
				(width 0)
				(type default)
			)
			(fill no)
			(layer "B.CrtYd")
		)
		(fp_rect
			(start 0.508 0.9398)
			(end -0.508 -0.9398)
			(stroke
				(width 0)
				(type default)
			)
			(fill no)
			(layer "B.Fab")
		)
		(pad "1" smd custom
			(at 0 -0.4445)
			(size 0.1397 0.1397)
			(layers "B.Cu" "B.Mask" "B.Paste")
			(net "P1V8")
			(options
				(clearance outline)
				(anchor circle)
			)
			(primitives
				(gr_poly
					(pts
						(arc
							(start -0.1778 0.2794)
							(mid -0.249642 0.249642)
							(end -0.2794 0.1778)
						)
						(arc
							(start -0.2794 -0.1778)
							(mid -0.249642 -0.249642)
							(end -0.1778 -0.2794)
						)
						(arc
							(start 0.1778 -0.2794)
							(mid 0.249642 -0.249642)
							(end 0.2794 -0.1778)
						)
						(arc
							(start 0.2794 0.1778)
							(mid 0.249642 0.249642)
							(end 0.1778 0.2794)
						)
					)
					(width 0)
					(fill yes)
				)
			)
		)
		(pad "2" smd custom
			(at 0 0.4445)
			(size 0.1397 0.1397)
			(layers "B.Cu" "B.Mask" "B.Paste")
			(net "AVSO_IDDTN18")
			(options
				(clearance outline)
				(anchor circle)
			)
			(primitives
				(gr_poly
					(pts
						(arc
							(start -0.1778 0.2794)
							(mid -0.249642 0.249642)
							(end -0.2794 0.1778)
						)
						(arc
							(start -0.2794 -0.1778)
							(mid -0.249642 -0.249642)
							(end -0.1778 -0.2794)
						)
						(arc
							(start 0.1778 -0.2794)
							(mid 0.249642 -0.249642)
							(end 0.2794 -0.1778)
						)
						(arc
							(start 0.2794 0.1778)
							(mid 0.249642 0.249642)
							(end 0.1778 0.2794)
						)
					)
					(width 0)
					(fill yes)
				)
			)
		)
	)
	(footprint ""
		(layer "B.Cu")
		(at 189.992 -73.152)
		(property "Reference" "TP161"
			(at 0 0 0)
			(layer "B.SilkS")
			(hide yes)
			(effects
				(font
					(size 1.27 1.27)
				)
				(justify mirror)
			)
		)
		(property "Value" "TPAD28-2-GP"
			(at 0.0127 -1.6637 0)
			(unlocked yes)
			(layer "B.Fab")
			(hide yes)
			(effects
				(font
					(size 1.016 1.016)
					(thickness 0.1524)
				)
				(justify mirror)
			)
		)
		(property "Device Type" "TPAD28"
			(at 0.0127 -3.1877 0)
			(unlocked yes)
			(layer "B.Fab")
			(hide yes)
			(effects
				(font
					(size 1.016 1.016)
					(thickness 0.1524)
				)
				(justify mirror)
			)
		)
		(duplicate_pad_numbers_are_jumpers no)
		(fp_poly
			(pts
				(arc
					(start 0.3556 0)
					(mid -0.3556 0)
					(end 0.3556 0)
				)
			)
			(stroke
				(width 0)
				(type default)
			)
			(fill no)
			(layer "B.CrtYd")
		)
		(fp_poly
			(pts
				(arc
					(start 0.6096 0)
					(mid -0.6096 0)
					(end 0.6096 0)
				)
			)
			(stroke
				(width 0)
				(type default)
			)
			(fill no)
			(layer "B.Fab")
		)
		(pad "1" smd circle
			(at 0 0 180)
			(size 0.7112 0.7112)
			(layers "B.Cu" "B.Mask" "B.Paste")
			(net "SPARE5")
		)
	)
	(footprint ""
		(layer "B.Cu")
		(at 190.8556 -63.2206 90)
		(property "Reference" "C398"
			(at 0 0 90)
			(layer "B.SilkS")
			(hide yes)
			(effects
				(font
					(size 1.27 1.27)
				)
				(justify mirror)
			)
		)
		(property "Value" "SCD1U6D3V1KX-GP"
			(at 2.8321 -1.7399 90)
			(unlocked yes)
			(layer "B.Fab")
			(hide yes)
			(effects
				(font
					(size 1.016 1.016)
					(thickness 0.1524)
				)
				(justify mirror)
			)
		)
		(property "Device Type" "C0201H13"
			(at 2.8321 -3.2639 90)
			(unlocked yes)
			(layer "B.Fab")
			(hide yes)
			(effects
				(font
					(size 1.016 1.016)
					(thickness 0.1524)
				)
				(justify mirror)
			)
		)
		(duplicate_pad_numbers_are_jumpers no)
		(fp_rect
			(start 0.2794 0.6477)
			(end -0.2794 -0.6477)
			(stroke
				(width 0)
				(type default)
			)
			(fill no)
			(layer "B.CrtYd")
		)
		(fp_rect
			(start 0.2794 0.6477)
			(end -0.2794 -0.6477)
			(stroke
				(width 0)
				(type default)
			)
			(fill no)
			(layer "B.Fab")
		)
		(pad "1" smd custom
			(at 0 -0.2794 270)
			(size 0.0762 0.0762)
			(layers "B.Cu" "B.Mask" "B.Paste")
			(net "P0V975")
			(options
				(clearance outline)
				(anchor circle)
			)
			(primitives
				(gr_poly
					(pts
						(arc
							(start 0.1524 0.127)
							(mid 0.137521 0.162921)
							(end 0.1016 0.1778)
						)
						(arc
							(start -0.1016 0.1778)
							(mid -0.137521 0.162921)
							(end -0.1524 0.127)
						)
						(arc
							(start -0.1524 -0.127)
							(mid -0.137521 -0.162921)
							(end -0.1016 -0.1778)
						)
						(arc
							(start 0.1016 -0.1778)
							(mid 0.137521 -0.162921)
							(end 0.1524 -0.127)
						)
					)
					(width 0)
					(fill yes)
				)
			)
		)
		(pad "2" smd custom
			(at 0 0.2794 270)
			(size 0.0762 0.0762)
			(layers "B.Cu" "B.Mask" "B.Paste")
			(net "GND")
			(options
				(clearance outline)
				(anchor circle)
			)
			(primitives
				(gr_poly
					(pts
						(arc
							(start 0.1524 0.127)
							(mid 0.137521 0.162921)
							(end 0.1016 0.1778)
						)
						(arc
							(start -0.1016 0.1778)
							(mid -0.137521 0.162921)
							(end -0.1524 0.127)
						)
						(arc
							(start -0.1524 -0.127)
							(mid -0.137521 -0.162921)
							(end -0.1016 -0.1778)
						)
						(arc
							(start 0.1016 -0.1778)
							(mid 0.137521 -0.162921)
							(end 0.1524 -0.127)
						)
					)
					(width 0)
					(fill yes)
				)
			)
		)
	)
	(footprint ""
		(layer "B.Cu")
		(at 195.5927 -63.23076 90)
		(property "Reference" "C409"
			(at 0 0 90)
			(layer "B.SilkS")
			(hide yes)
			(effects
				(font
					(size 1.27 1.27)
				)
				(justify mirror)
			)
		)
		(property "Value" "SCD1U6D3V1KX-GP"
			(at 2.8321 -1.7399 90)
			(unlocked yes)
			(layer "B.Fab")
			(hide yes)
			(effects
				(font
					(size 1.016 1.016)
					(thickness 0.1524)
				)
				(justify mirror)
			)
		)
		(property "Device Type" "C0201H13"
			(at 2.8321 -3.2639 90)
			(unlocked yes)
			(layer "B.Fab")
			(hide yes)
			(effects
				(font
					(size 1.016 1.016)
					(thickness 0.1524)
				)
				(justify mirror)
			)
		)
		(duplicate_pad_numbers_are_jumpers no)
		(fp_rect
			(start 0.2794 0.6477)
			(end -0.2794 -0.6477)
			(stroke
				(width 0)
				(type default)
			)
			(fill no)
			(layer "B.CrtYd")
		)
		(fp_rect
			(start 0.2794 0.6477)
			(end -0.2794 -0.6477)
			(stroke
				(width 0)
				(type default)
			)
			(fill no)
			(layer "B.Fab")
		)
		(pad "1" smd custom
			(at 0 -0.2794 270)
			(size 0.0762 0.0762)
			(layers "B.Cu" "B.Mask" "B.Paste")
			(net "P0V975")
			(options
				(clearance outline)
				(anchor circle)
			)
			(primitives
				(gr_poly
					(pts
						(arc
							(start 0.1524 0.127)
							(mid 0.137521 0.162921)
							(end 0.1016 0.1778)
						)
						(arc
							(start -0.1016 0.1778)
							(mid -0.137521 0.162921)
							(end -0.1524 0.127)
						)
						(arc
							(start -0.1524 -0.127)
							(mid -0.137521 -0.162921)
							(end -0.1016 -0.1778)
						)
						(arc
							(start 0.1016 -0.1778)
							(mid 0.137521 -0.162921)
							(end 0.1524 -0.127)
						)
					)
					(width 0)
					(fill yes)
				)
			)
		)
		(pad "2" smd custom
			(at 0 0.2794 270)
			(size 0.0762 0.0762)
			(layers "B.Cu" "B.Mask" "B.Paste")
			(net "GND")
			(options
				(clearance outline)
				(anchor circle)
			)
			(primitives
				(gr_poly
					(pts
						(arc
							(start 0.1524 0.127)
							(mid 0.137521 0.162921)
							(end 0.1016 0.1778)
						)
						(arc
							(start -0.1016 0.1778)
							(mid -0.137521 0.162921)
							(end -0.1524 0.127)
						)
						(arc
							(start -0.1524 -0.127)
							(mid -0.137521 -0.162921)
							(end -0.1016 -0.1778)
						)
						(arc
							(start 0.1016 -0.1778)
							(mid 0.137521 -0.162921)
							(end 0.1524 -0.127)
						)
					)
					(width 0)
					(fill yes)
				)
			)
		)
	)
	(footprint ""
		(layer "B.Cu")
		(at 55.800752 -149.300184)
		(property "Reference" "TP80"
			(at 0 0 0)
			(layer "B.SilkS")
			(hide yes)
			(effects
				(font
					(size 1.27 1.27)
				)
				(justify mirror)
			)
		)
		(property "Value" "TPAD28-2-GP"
			(at 0.0127 -1.6637 0)
			(unlocked yes)
			(layer "B.Fab")
			(hide yes)
			(effects
				(font
					(size 1.016 1.016)
					(thickness 0.1524)
				)
				(justify mirror)
			)
		)
		(property "Device Type" "TPAD28"
			(at 0.0127 -3.1877 0)
			(unlocked yes)
			(layer "B.Fab")
			(hide yes)
			(effects
				(font
					(size 1.016 1.016)
					(thickness 0.1524)
				)
				(justify mirror)
			)
		)
		(duplicate_pad_numbers_are_jumpers no)
		(fp_poly
			(pts
				(arc
					(start 0.3556 0)
					(mid -0.3556 0)
					(end 0.3556 0)
				)
			)
			(stroke
				(width 0)
				(type default)
			)
			(fill no)
			(layer "B.CrtYd")
		)
		(fp_poly
			(pts
				(arc
					(start 0.6096 0)
					(mid -0.6096 0)
					(end 0.6096 0)
				)
			)
			(stroke
				(width 0)
				(type default)
			)
			(fill no)
			(layer "B.Fab")
		)
		(pad "1" smd circle
			(at 0 0 180)
			(size 0.7112 0.7112)
			(layers "B.Cu" "B.Mask" "B.Paste")
			(net "JTAG_BMC_TMS")
		)
	)
	(footprint ""
		(layer "B.Cu")
		(at 174.1678 -77.9272 180)
		(property "Reference" "C342"
			(at 0 0 0)
			(layer "B.SilkS")
			(hide yes)
			(effects
				(font
					(size 1.27 1.27)
				)
				(justify mirror)
			)
		)
		(property "Value" "SC22U6D3V3MX-9-GP-U"
			(at 0 -2.8194 180)
			(unlocked yes)
			(layer "B.Fab")
			(hide yes)
			(effects
				(font
					(size 1.016 1.016)
					(thickness 0.1524)
				)
				(justify mirror)
			)
		)
		(property "Device Type" "C603H40"
			(at 0 -4.3434 180)
			(unlocked yes)
			(layer "B.Fab")
			(hide yes)
			(effects
				(font
					(size 1.016 1.016)
					(thickness 0.1524)
				)
				(justify mirror)
			)
		)
		(duplicate_pad_numbers_are_jumpers no)
		(fp_line
			(start -0.508 0)
			(end 0.508 0)
			(stroke
				(width 0.2032)
				(type default)
			)
			(layer "B.SilkS")
		)
		(fp_rect
			(start 0.5842 1.3335)
			(end -0.5842 -1.3335)
			(stroke
				(width 0)
				(type default)
			)
			(fill no)
			(layer "B.CrtYd")
		)
		(fp_rect
			(start 0.5842 1.3335)
			(end -0.5842 -1.3335)
			(stroke
				(width 0)
				(type default)
			)
			(fill no)
			(layer "B.Fab")
		)
		(pad "1" smd custom
			(at 0 -0.762)
			(size 0.2159 0.2159)
			(layers "B.Cu" "B.Mask" "B.Paste")
			(net "PLL_VDD")
			(options
				(clearance outline)
				(anchor circle)
			)
			(primitives
				(gr_poly
					(pts
						(arc
							(start -0.3302 0.4318)
							(mid -0.402042 0.402042)
							(end -0.4318 0.3302)
						)
						(arc
							(start -0.4318 -0.3302)
							(mid -0.402042 -0.402042)
							(end -0.3302 -0.4318)
						)
						(arc
							(start 0.3302 -0.4318)
							(mid 0.402042 -0.402042)
							(end 0.4318 -0.3302)
						)
						(arc
							(start 0.4318 0.3302)
							(mid 0.402042 0.402042)
							(end 0.3302 0.4318)
						)
					)
					(width 0)
					(fill yes)
				)
			)
		)
		(pad "2" smd custom
			(at 0 0.762)
			(size 0.2159 0.2159)
			(layers "B.Cu" "B.Mask" "B.Paste")
			(net "GND")
			(options
				(clearance outline)
				(anchor circle)
			)
			(primitives
				(gr_poly
					(pts
						(arc
							(start -0.3302 0.4318)
							(mid -0.402042 0.402042)
							(end -0.4318 0.3302)
						)
						(arc
							(start -0.4318 -0.3302)
							(mid -0.402042 -0.402042)
							(end -0.3302 -0.4318)
						)
						(arc
							(start 0.3302 -0.4318)
							(mid 0.402042 -0.402042)
							(end 0.4318 -0.3302)
						)
						(arc
							(start 0.4318 0.3302)
							(mid 0.402042 0.402042)
							(end 0.3302 0.4318)
						)
					)
					(width 0)
					(fill yes)
				)
			)
		)
	)
	(footprint ""
		(layer "B.Cu")
		(at 185.40222 -53.83276)
		(property "Reference" "TP166"
			(at 0 0 0)
			(layer "B.SilkS")
			(hide yes)
			(effects
				(font
					(size 1.27 1.27)
				)
				(justify mirror)
			)
		)
		(property "Value" "TPAD28-2-GP"
			(at 0.0127 -1.6637 0)
			(unlocked yes)
			(layer "B.Fab")
			(hide yes)
			(effects
				(font
					(size 1.016 1.016)
					(thickness 0.1524)
				)
				(justify mirror)
			)
		)
		(property "Device Type" "TPAD28"
			(at 0.0127 -3.1877 0)
			(unlocked yes)
			(layer "B.Fab")
			(hide yes)
			(effects
				(font
					(size 1.016 1.016)
					(thickness 0.1524)
				)
				(justify mirror)
			)
		)
		(duplicate_pad_numbers_are_jumpers no)
		(fp_poly
			(pts
				(arc
					(start 0.3556 0)
					(mid -0.3556 0)
					(end 0.3556 0)
				)
			)
			(stroke
				(width 0)
				(type default)
			)
			(fill no)
			(layer "B.CrtYd")
		)
		(fp_poly
			(pts
				(arc
					(start 0.6096 0)
					(mid -0.6096 0)
					(end 0.6096 0)
				)
			)
			(stroke
				(width 0)
				(type default)
			)
			(fill no)
			(layer "B.Fab")
		)
		(pad "1" smd circle
			(at 0 0 180)
			(size 0.7112 0.7112)
			(layers "B.Cu" "B.Mask" "B.Paste")
			(net "XM_CLE")
		)
	)
	(footprint ""
		(layer "B.Cu")
		(at 51.55438 -140.335 90)
		(property "Reference" "C999"
			(at 0 0 90)
			(layer "B.SilkS")
			(hide yes)
			(effects
				(font
					(size 1.27 1.27)
				)
				(justify mirror)
			)
		)
		(property "Value" "SCD1U16V2KX-3GP"
			(at -1.1811 -2.7051 90)
			(unlocked yes)
			(layer "B.Fab")
			(hide yes)
			(effects
				(font
					(size 1.016 1.016)
					(thickness 0.1524)
				)
				(justify mirror)
			)
		)
		(property "Device Type" "C402H22"
			(at -1.1811 -4.2291 90)
			(unlocked yes)
			(layer "B.Fab")
			(hide yes)
			(effects
				(font
					(size 1.016 1.016)
					(thickness 0.1524)
				)
				(justify mirror)
			)
		)
		(duplicate_pad_numbers_are_jumpers no)
		(fp_rect
			(start 0.4318 0.9525)
			(end -0.4318 -0.9525)
			(stroke
				(width 0)
				(type default)
			)
			(fill no)
			(layer "B.CrtYd")
		)
		(fp_rect
			(start 0.4318 0.9525)
			(end -0.4318 -0.9525)
			(stroke
				(width 0)
				(type default)
			)
			(fill no)
			(layer "B.Fab")
		)
		(pad "1" smd custom
			(at 0 -0.4445 270)
			(size 0.1524 0.1524)
			(layers "B.Cu" "B.Mask" "B.Paste")
			(net "P1V8_STBY")
			(options
				(clearance outline)
				(anchor circle)
			)
			(primitives
				(gr_poly
					(pts
						(arc
							(start 0.3048 0.2032)
							(mid 0.275042 0.275042)
							(end 0.2032 0.3048)
						)
						(arc
							(start -0.2032 0.3048)
							(mid -0.275042 0.275042)
							(end -0.3048 0.2032)
						)
						(arc
							(start -0.3048 -0.2032)
							(mid -0.275042 -0.275042)
							(end -0.2032 -0.3048)
						)
						(arc
							(start 0.2032 -0.3048)
							(mid 0.275042 -0.275042)
							(end 0.3048 -0.2032)
						)
					)
					(width 0)
					(fill yes)
				)
			)
		)
		(pad "2" smd custom
			(at 0 0.4445 270)
			(size 0.1524 0.1524)
			(layers "B.Cu" "B.Mask" "B.Paste")
			(net "GND")
			(options
				(clearance outline)
				(anchor circle)
			)
			(primitives
				(gr_poly
					(pts
						(arc
							(start 0.3048 0.2032)
							(mid 0.275042 0.275042)
							(end 0.2032 0.3048)
						)
						(arc
							(start -0.2032 0.3048)
							(mid -0.275042 0.275042)
							(end -0.3048 0.2032)
						)
						(arc
							(start -0.3048 -0.2032)
							(mid -0.275042 -0.275042)
							(end -0.2032 -0.3048)
						)
						(arc
							(start 0.2032 -0.3048)
							(mid 0.275042 -0.275042)
							(end 0.3048 -0.2032)
						)
					)
					(width 0)
					(fill yes)
				)
			)
		)
	)
	(footprint ""
		(layer "B.Cu")
		(at 68.792344 -142.956026)
		(property "Reference" "R194"
			(at 0 0 0)
			(layer "B.SilkS")
			(hide yes)
			(effects
				(font
					(size 1.27 1.27)
				)
				(justify mirror)
			)
		)
		(property "Value" "20KR2F-L-GP"
			(at -0.064008 -3.993896 0)
			(unlocked yes)
			(layer "B.Fab")
			(hide yes)
			(effects
				(font
					(size 1.016 1.016)
					(thickness 0.1524)
				)
				(justify mirror)
			)
		)
		(property "Device Type" "R402H16"
			(at -0.064008 -5.517896 0)
			(unlocked yes)
			(layer "B.Fab")
			(hide yes)
			(effects
				(font
					(size 1.016 1.016)
					(thickness 0.1524)
				)
				(justify mirror)
			)
		)
		(duplicate_pad_numbers_are_jumpers no)
		(fp_line
			(start -0.508 -0.9398)
			(end 0.508 -0.9398)
			(stroke
				(width 0.1524)
				(type default)
			)
			(layer "B.SilkS")
		)
		(fp_line
			(start 0.508 -0.9398)
			(end 0.508 0.9398)
			(stroke
				(width 0.1524)
				(type default)
			)
			(layer "B.SilkS")
		)
		(fp_rect
			(start 0.508 0.9398)
			(end -0.508 -0.9398)
			(stroke
				(width 0)
				(type default)
			)
			(fill no)
			(layer "B.CrtYd")
		)
		(fp_rect
			(start 0.508 0.9398)
			(end -0.508 -0.9398)
			(stroke
				(width 0)
				(type default)
			)
			(fill no)
			(layer "B.Fab")
		)
		(pad "1" smd custom
			(at 0 -0.4445 180)
			(size 0.1397 0.1397)
			(layers "B.Cu" "B.Mask" "B.Paste")
			(net "P3V3_STBY")
			(options
				(clearance outline)
				(anchor circle)
			)
			(primitives
				(gr_poly
					(pts
						(arc
							(start -0.1778 0.2794)
							(mid -0.249642 0.249642)
							(end -0.2794 0.1778)
						)
						(arc
							(start -0.2794 -0.1778)
							(mid -0.249642 -0.249642)
							(end -0.1778 -0.2794)
						)
						(arc
							(start 0.1778 -0.2794)
							(mid 0.249642 -0.249642)
							(end 0.2794 -0.1778)
						)
						(arc
							(start 0.2794 0.1778)
							(mid 0.249642 0.249642)
							(end 0.1778 0.2794)
						)
					)
					(width 0)
					(fill yes)
				)
			)
		)
		(pad "2" smd custom
			(at 0 0.4445 180)
			(size 0.1397 0.1397)
			(layers "B.Cu" "B.Mask" "B.Paste")
			(net "I2C_DEBUG_SDA_L")
			(options
				(clearance outline)
				(anchor circle)
			)
			(primitives
				(gr_poly
					(pts
						(arc
							(start -0.1778 0.2794)
							(mid -0.249642 0.249642)
							(end -0.2794 0.1778)
						)
						(arc
							(start -0.2794 -0.1778)
							(mid -0.249642 -0.249642)
							(end -0.1778 -0.2794)
						)
						(arc
							(start 0.1778 -0.2794)
							(mid 0.249642 -0.249642)
							(end 0.2794 -0.1778)
						)
						(arc
							(start 0.2794 0.1778)
							(mid 0.249642 0.249642)
							(end 0.1778 0.2794)
						)
					)
					(width 0)
					(fill yes)
				)
			)
		)
	)
	(footprint ""
		(layer "B.Cu")
		(at 40.350948 -155.983178)
		(property "Reference" "TP63"
			(at 0 0 0)
			(layer "B.SilkS")
			(hide yes)
			(effects
				(font
					(size 1.27 1.27)
				)
				(justify mirror)
			)
		)
		(property "Value" "TPAD28-2-GP"
			(at 0.0127 -1.6637 0)
			(unlocked yes)
			(layer "B.Fab")
			(hide yes)
			(effects
				(font
					(size 1.016 1.016)
					(thickness 0.1524)
				)
				(justify mirror)
			)
		)
		(property "Device Type" "TPAD28"
			(at 0.0127 -3.1877 0)
			(unlocked yes)
			(layer "B.Fab")
			(hide yes)
			(effects
				(font
					(size 1.016 1.016)
					(thickness 0.1524)
				)
				(justify mirror)
			)
		)
		(duplicate_pad_numbers_are_jumpers no)
		(fp_poly
			(pts
				(arc
					(start 0.3556 0)
					(mid -0.3556 0)
					(end 0.3556 0)
				)
			)
			(stroke
				(width 0)
				(type default)
			)
			(fill no)
			(layer "B.CrtYd")
		)
		(fp_poly
			(pts
				(arc
					(start 0.6096 0)
					(mid -0.6096 0)
					(end 0.6096 0)
				)
			)
			(stroke
				(width 0)
				(type default)
			)
			(fill no)
			(layer "B.Fab")
		)
		(pad "1" smd circle
			(at 0 0 180)
			(size 0.7112 0.7112)
			(layers "B.Cu" "B.Mask" "B.Paste")
			(net "TP_BMC_GPION3")
		)
	)
	(footprint ""
		(layer "B.Cu")
		(at 211.836 -86.106 90)
		(property "Reference" "C351"
			(at 0 0 90)
			(layer "B.SilkS")
			(hide yes)
			(effects
				(font
					(size 1.27 1.27)
				)
				(justify mirror)
			)
		)
		(property "Value" "SC10U6D3V5KX-4GP"
			(at 0.0762 -6.1214 90)
			(unlocked yes)
			(layer "B.Fab")
			(hide yes)
			(effects
				(font
					(size 1.016 1.016)
					(thickness 0.1524)
				)
				(justify mirror)
			)
		)
		(property "Device Type" "C805H58"
			(at 0.0762 -8.1534 90)
			(unlocked yes)
			(layer "B.Fab")
			(hide yes)
			(effects
				(font
					(size 1.016 1.016)
					(thickness 0.1524)
				)
				(justify mirror)
			)
		)
		(duplicate_pad_numbers_are_jumpers no)
		(fp_line
			(start -0.635 0)
			(end 0.635 0)
			(stroke
				(width 0.508)
				(type default)
			)
			(layer "B.SilkS")
		)
		(fp_rect
			(start 0.9652 1.778)
			(end -0.9652 -1.778)
			(stroke
				(width 0)
				(type default)
			)
			(fill no)
			(layer "B.CrtYd")
		)
		(fp_poly
			(pts
				(xy 0.9652 -1.778) (xy -0.9652 -1.778) (xy -0.9652 1.778) (xy 0.9652 1.778)
			)
			(stroke
				(width 0)
				(type default)
			)
			(fill no)
			(layer "B.Fab")
		)
		(pad "1" smd rect
			(at 0 -0.9652 270)
			(size 1.397 1.143)
			(layers "B.Cu" "B.Mask" "B.Paste")
			(net "SAS0_VDDH")
		)
		(pad "2" smd rect
			(at 0 0.9652 270)
			(size 1.397 1.143)
			(layers "B.Cu" "B.Mask" "B.Paste")
			(net "GND")
		)
	)
	(footprint ""
		(layer "B.Cu")
		(at 92.7862 -137.3124 -90)
		(property "Reference" "R275"
			(at 0 0 90)
			(layer "B.SilkS")
			(hide yes)
			(effects
				(font
					(size 1.27 1.27)
				)
				(justify mirror)
			)
		)
		(property "Value" "100KR2F-L1-GP"
			(at -0.064008 -3.993896 270)
			(unlocked yes)
			(layer "B.Fab")
			(hide yes)
			(effects
				(font
					(size 1.016 1.016)
					(thickness 0.1524)
				)
				(justify mirror)
			)
		)
		(property "Device Type" "R402H16"
			(at -0.064008 -5.517896 270)
			(unlocked yes)
			(layer "B.Fab")
			(hide yes)
			(effects
				(font
					(size 1.016 1.016)
					(thickness 0.1524)
				)
				(justify mirror)
			)
		)
		(duplicate_pad_numbers_are_jumpers no)
		(fp_line
			(start -0.508 -0.9398)
			(end 0.508 -0.9398)
			(stroke
				(width 0.1524)
				(type default)
			)
			(layer "B.SilkS")
		)
		(fp_line
			(start 0.508 -0.9398)
			(end 0.508 0.9398)
			(stroke
				(width 0.1524)
				(type default)
			)
			(layer "B.SilkS")
		)
		(fp_rect
			(start 0.508 0.9398)
			(end -0.508 -0.9398)
			(stroke
				(width 0)
				(type default)
			)
			(fill no)
			(layer "B.CrtYd")
		)
		(fp_rect
			(start 0.508 0.9398)
			(end -0.508 -0.9398)
			(stroke
				(width 0)
				(type default)
			)
			(fill no)
			(layer "B.Fab")
		)
		(pad "1" smd custom
			(at 0 -0.4445 90)
			(size 0.1397 0.1397)
			(layers "B.Cu" "B.Mask" "B.Paste")
			(net "DEBUG_CARD_PRSNT")
			(options
				(clearance outline)
				(anchor circle)
			)
			(primitives
				(gr_poly
					(pts
						(arc
							(start -0.1778 0.2794)
							(mid -0.249642 0.249642)
							(end -0.2794 0.1778)
						)
						(arc
							(start -0.2794 -0.1778)
							(mid -0.249642 -0.249642)
							(end -0.1778 -0.2794)
						)
						(arc
							(start 0.1778 -0.2794)
							(mid 0.249642 -0.249642)
							(end 0.2794 -0.1778)
						)
						(arc
							(start 0.2794 0.1778)
							(mid 0.249642 0.249642)
							(end 0.1778 0.2794)
						)
					)
					(width 0)
					(fill yes)
				)
			)
		)
		(pad "2" smd custom
			(at 0 0.4445 90)
			(size 0.1397 0.1397)
			(layers "B.Cu" "B.Mask" "B.Paste")
			(net "GND")
			(options
				(clearance outline)
				(anchor circle)
			)
			(primitives
				(gr_poly
					(pts
						(arc
							(start -0.1778 0.2794)
							(mid -0.249642 0.249642)
							(end -0.2794 0.1778)
						)
						(arc
							(start -0.2794 -0.1778)
							(mid -0.249642 -0.249642)
							(end -0.1778 -0.2794)
						)
						(arc
							(start 0.1778 -0.2794)
							(mid 0.249642 -0.249642)
							(end 0.2794 -0.1778)
						)
						(arc
							(start 0.2794 0.1778)
							(mid 0.249642 0.249642)
							(end 0.1778 0.2794)
						)
					)
					(width 0)
					(fill yes)
				)
			)
		)
	)
	(footprint ""
		(layer "B.Cu")
		(at 183.48706 -81.49844)
		(property "Reference" "C393"
			(at 0 0 0)
			(layer "B.SilkS")
			(hide yes)
			(effects
				(font
					(size 1.27 1.27)
				)
				(justify mirror)
			)
		)
		(property "Value" "SC1U16V2KX-7-GP"
			(at -1.7526 -1.6002 0)
			(unlocked yes)
			(layer "B.Fab")
			(hide yes)
			(effects
				(font
					(size 1.016 1.016)
					(thickness 0.1524)
				)
				(justify mirror)
			)
		)
		(property "Device Type" "C402-TO0D2H24"
			(at -1.7526 -3.1242 0)
			(unlocked yes)
			(layer "B.Fab")
			(hide yes)
			(effects
				(font
					(size 1.016 1.016)
					(thickness 0.1524)
				)
				(justify mirror)
			)
		)
		(duplicate_pad_numbers_are_jumpers no)
		(fp_rect
			(start 0.4826 0.889)
			(end -0.4826 -0.889)
			(stroke
				(width 0)
				(type default)
			)
			(fill no)
			(layer "B.CrtYd")
		)
		(fp_rect
			(start 0.4826 0.889)
			(end -0.4826 -0.889)
			(stroke
				(width 0)
				(type default)
			)
			(fill no)
			(layer "B.Fab")
		)
		(pad "1" smd custom
			(at 0 -0.4572 180)
			(size 0.1524 0.1524)
			(layers "B.Cu" "B.Mask" "B.Paste")
			(net "P0V975")
			(options
				(clearance outline)
				(anchor circle)
			)
			(primitives
				(gr_poly
					(pts
						(arc
							(start -0.254 -0.3048)
							(mid -0.325842 -0.275042)
							(end -0.3556 -0.2032)
						)
						(arc
							(start -0.3556 0.2032)
							(mid -0.325842 0.275042)
							(end -0.254 0.3048)
						)
						(arc
							(start 0.254 0.3048)
							(mid 0.325842 0.275042)
							(end 0.3556 0.2032)
						)
						(arc
							(start 0.3556 -0.2032)
							(mid 0.325842 -0.275042)
							(end 0.254 -0.3048)
						)
					)
					(width 0)
					(fill yes)
				)
			)
		)
		(pad "2" smd custom
			(at 0 0.4572 180)
			(size 0.1524 0.1524)
			(layers "B.Cu" "B.Mask" "B.Paste")
			(net "GND")
			(options
				(clearance outline)
				(anchor circle)
			)
			(primitives
				(gr_poly
					(pts
						(arc
							(start -0.254 -0.3048)
							(mid -0.325842 -0.275042)
							(end -0.3556 -0.2032)
						)
						(arc
							(start -0.3556 0.2032)
							(mid -0.325842 0.275042)
							(end -0.254 0.3048)
						)
						(arc
							(start 0.254 0.3048)
							(mid 0.325842 0.275042)
							(end 0.3556 0.2032)
						)
						(arc
							(start 0.3556 -0.2032)
							(mid 0.325842 -0.275042)
							(end 0.254 -0.3048)
						)
					)
					(width 0)
					(fill yes)
				)
			)
		)
	)
	(footprint ""
		(layer "B.Cu")
		(at 180.675788 -74.726546)
		(property "Reference" "TP112"
			(at 0 0 0)
			(layer "B.SilkS")
			(hide yes)
			(effects
				(font
					(size 1.27 1.27)
				)
				(justify mirror)
			)
		)
		(property "Value" "TPAD28-2-GP"
			(at 0.0127 -1.6637 0)
			(unlocked yes)
			(layer "B.Fab")
			(hide yes)
			(effects
				(font
					(size 1.016 1.016)
					(thickness 0.1524)
				)
				(justify mirror)
			)
		)
		(property "Device Type" "TPAD28"
			(at 0.0127 -3.1877 0)
			(unlocked yes)
			(layer "B.Fab")
			(hide yes)
			(effects
				(font
					(size 1.016 1.016)
					(thickness 0.1524)
				)
				(justify mirror)
			)
		)
		(duplicate_pad_numbers_are_jumpers no)
		(fp_poly
			(pts
				(arc
					(start 0.3556 0)
					(mid -0.3556 0)
					(end 0.3556 0)
				)
			)
			(stroke
				(width 0)
				(type default)
			)
			(fill no)
			(layer "B.CrtYd")
		)
		(fp_poly
			(pts
				(arc
					(start 0.6096 0)
					(mid -0.6096 0)
					(end 0.6096 0)
				)
			)
			(stroke
				(width 0)
				(type default)
			)
			(fill no)
			(layer "B.Fab")
		)
		(pad "1" smd circle
			(at 0 0 180)
			(size 0.7112 0.7112)
			(layers "B.Cu" "B.Mask" "B.Paste")
			(net "IOC_GPIO_26")
		)
	)
	(footprint ""
		(layer "B.Cu")
		(at 111.6838 -9.6012 90)
		(property "Reference" "R461"
			(at 0 0 90)
			(layer "B.SilkS")
			(hide yes)
			(effects
				(font
					(size 1.27 1.27)
				)
				(justify mirror)
			)
		)
		(property "Value" "100KR2J-4-GP"
			(at -0.064008 -3.993896 90)
			(unlocked yes)
			(layer "B.Fab")
			(hide yes)
			(effects
				(font
					(size 1.016 1.016)
					(thickness 0.1524)
				)
				(justify mirror)
			)
		)
		(property "Device Type" "R402H15"
			(at -0.064008 -5.517896 90)
			(unlocked yes)
			(layer "B.Fab")
			(hide yes)
			(effects
				(font
					(size 1.016 1.016)
					(thickness 0.1524)
				)
				(justify mirror)
			)
		)
		(duplicate_pad_numbers_are_jumpers no)
		(fp_line
			(start 0.508 -0.9398)
			(end 0.508 0.9398)
			(stroke
				(width 0.1524)
				(type default)
			)
			(layer "B.SilkS")
		)
		(fp_line
			(start -0.508 -0.9398)
			(end 0.508 -0.9398)
			(stroke
				(width 0.1524)
				(type default)
			)
			(layer "B.SilkS")
		)
		(fp_rect
			(start 0.508 0.9398)
			(end -0.508 -0.9398)
			(stroke
				(width 0)
				(type default)
			)
			(fill no)
			(layer "B.CrtYd")
		)
		(fp_rect
			(start 0.508 0.9398)
			(end -0.508 -0.9398)
			(stroke
				(width 0)
				(type default)
			)
			(fill no)
			(layer "B.Fab")
		)
		(pad "1" smd custom
			(at 0 -0.4445 270)
			(size 0.1397 0.1397)
			(layers "B.Cu" "B.Mask" "B.Paste")
			(net "MB0_VCAP_R")
			(options
				(clearance outline)
				(anchor circle)
			)
			(primitives
				(gr_poly
					(pts
						(arc
							(start -0.1778 0.2794)
							(mid -0.249642 0.249642)
							(end -0.2794 0.1778)
						)
						(arc
							(start -0.2794 -0.1778)
							(mid -0.249642 -0.249642)
							(end -0.1778 -0.2794)
						)
						(arc
							(start 0.1778 -0.2794)
							(mid 0.249642 -0.249642)
							(end 0.2794 -0.1778)
						)
						(arc
							(start 0.2794 0.1778)
							(mid 0.249642 0.249642)
							(end 0.1778 0.2794)
						)
					)
					(width 0)
					(fill yes)
				)
			)
		)
		(pad "2" smd custom
			(at 0 0.4445 270)
			(size 0.1397 0.1397)
			(layers "B.Cu" "B.Mask" "B.Paste")
			(net "MB0_ISTART_R")
			(options
				(clearance outline)
				(anchor circle)
			)
			(primitives
				(gr_poly
					(pts
						(arc
							(start -0.1778 0.2794)
							(mid -0.249642 0.249642)
							(end -0.2794 0.1778)
						)
						(arc
							(start -0.2794 -0.1778)
							(mid -0.249642 -0.249642)
							(end -0.1778 -0.2794)
						)
						(arc
							(start 0.1778 -0.2794)
							(mid 0.249642 -0.249642)
							(end 0.2794 -0.1778)
						)
						(arc
							(start 0.2794 0.1778)
							(mid 0.249642 0.249642)
							(end 0.1778 0.2794)
						)
					)
					(width 0)
					(fill yes)
				)
			)
		)
	)
	(footprint ""
		(layer "B.Cu")
		(at 186.7916 -66.3321 -90)
		(property "Reference" "C387"
			(at 0 0 90)
			(layer "B.SilkS")
			(hide yes)
			(effects
				(font
					(size 1.27 1.27)
				)
				(justify mirror)
			)
		)
		(property "Value" "SC10U6D3V5KX-4GP"
			(at 0.0762 -6.1214 270)
			(unlocked yes)
			(layer "B.Fab")
			(hide yes)
			(effects
				(font
					(size 1.016 1.016)
					(thickness 0.1524)
				)
				(justify mirror)
			)
		)
		(property "Device Type" "C805H58"
			(at 0.0762 -8.1534 270)
			(unlocked yes)
			(layer "B.Fab")
			(hide yes)
			(effects
				(font
					(size 1.016 1.016)
					(thickness 0.1524)
				)
				(justify mirror)
			)
		)
		(duplicate_pad_numbers_are_jumpers no)
		(fp_line
			(start -0.635 0)
			(end 0.635 0)
			(stroke
				(width 0.508)
				(type default)
			)
			(layer "B.SilkS")
		)
		(fp_rect
			(start 0.9652 1.778)
			(end -0.9652 -1.778)
			(stroke
				(width 0)
				(type default)
			)
			(fill no)
			(layer "B.CrtYd")
		)
		(fp_poly
			(pts
				(xy 0.9652 -1.778) (xy -0.9652 -1.778) (xy -0.9652 1.778) (xy 0.9652 1.778)
			)
			(stroke
				(width 0)
				(type default)
			)
			(fill no)
			(layer "B.Fab")
		)
		(pad "1" smd rect
			(at 0 -0.9652 90)
			(size 1.397 1.143)
			(layers "B.Cu" "B.Mask" "B.Paste")
			(net "P0V975")
		)
		(pad "2" smd rect
			(at 0 0.9652 90)
			(size 1.397 1.143)
			(layers "B.Cu" "B.Mask" "B.Paste")
			(net "GND")
		)
	)
	(footprint ""
		(layer "B.Cu")
		(at 168.656 -106.045 -90)
		(property "Reference" "C448"
			(at 0 0 90)
			(layer "B.SilkS")
			(hide yes)
			(effects
				(font
					(size 1.27 1.27)
				)
				(justify mirror)
			)
		)
		(property "Value" "SCD1U16V2KX-3GP"
			(at -1.1811 -2.7051 270)
			(unlocked yes)
			(layer "B.Fab")
			(hide yes)
			(effects
				(font
					(size 1.016 1.016)
					(thickness 0.1524)
				)
				(justify mirror)
			)
		)
		(property "Device Type" "C402H22"
			(at -1.1811 -4.2291 270)
			(unlocked yes)
			(layer "B.Fab")
			(hide yes)
			(effects
				(font
					(size 1.016 1.016)
					(thickness 0.1524)
				)
				(justify mirror)
			)
		)
		(duplicate_pad_numbers_are_jumpers no)
		(fp_rect
			(start 0.4318 0.9525)
			(end -0.4318 -0.9525)
			(stroke
				(width 0)
				(type default)
			)
			(fill no)
			(layer "B.CrtYd")
		)
		(fp_rect
			(start 0.4318 0.9525)
			(end -0.4318 -0.9525)
			(stroke
				(width 0)
				(type default)
			)
			(fill no)
			(layer "B.Fab")
		)
		(pad "1" smd custom
			(at 0 -0.4445 90)
			(size 0.1524 0.1524)
			(layers "B.Cu" "B.Mask" "B.Paste")
			(net "P1V8")
			(options
				(clearance outline)
				(anchor circle)
			)
			(primitives
				(gr_poly
					(pts
						(arc
							(start 0.3048 0.2032)
							(mid 0.275042 0.275042)
							(end 0.2032 0.3048)
						)
						(arc
							(start -0.2032 0.3048)
							(mid -0.275042 0.275042)
							(end -0.3048 0.2032)
						)
						(arc
							(start -0.3048 -0.2032)
							(mid -0.275042 -0.275042)
							(end -0.2032 -0.3048)
						)
						(arc
							(start 0.2032 -0.3048)
							(mid 0.275042 -0.275042)
							(end 0.3048 -0.2032)
						)
					)
					(width 0)
					(fill yes)
				)
			)
		)
		(pad "2" smd custom
			(at 0 0.4445 90)
			(size 0.1524 0.1524)
			(layers "B.Cu" "B.Mask" "B.Paste")
			(net "GND")
			(options
				(clearance outline)
				(anchor circle)
			)
			(primitives
				(gr_poly
					(pts
						(arc
							(start 0.3048 0.2032)
							(mid 0.275042 0.275042)
							(end 0.2032 0.3048)
						)
						(arc
							(start -0.2032 0.3048)
							(mid -0.275042 0.275042)
							(end -0.3048 0.2032)
						)
						(arc
							(start -0.3048 -0.2032)
							(mid -0.275042 -0.275042)
							(end -0.2032 -0.3048)
						)
						(arc
							(start 0.2032 -0.3048)
							(mid 0.275042 -0.275042)
							(end 0.3048 -0.2032)
						)
					)
					(width 0)
					(fill yes)
				)
			)
		)
	)
	(footprint ""
		(layer "B.Cu")
		(at 205.994 -59.5122)
		(property "Reference" "TP122"
			(at 0 0 0)
			(layer "B.SilkS")
			(hide yes)
			(effects
				(font
					(size 1.27 1.27)
				)
				(justify mirror)
			)
		)
		(property "Value" "TPAD28-2-GP"
			(at 0.0127 -1.6637 0)
			(unlocked yes)
			(layer "B.Fab")
			(hide yes)
			(effects
				(font
					(size 1.016 1.016)
					(thickness 0.1524)
				)
				(justify mirror)
			)
		)
		(property "Device Type" "TPAD28"
			(at 0.0127 -3.1877 0)
			(unlocked yes)
			(layer "B.Fab")
			(hide yes)
			(effects
				(font
					(size 1.016 1.016)
					(thickness 0.1524)
				)
				(justify mirror)
			)
		)
		(duplicate_pad_numbers_are_jumpers no)
		(fp_poly
			(pts
				(arc
					(start 0.3556 0)
					(mid -0.3556 0)
					(end 0.3556 0)
				)
			)
			(stroke
				(width 0)
				(type default)
			)
			(fill no)
			(layer "B.CrtYd")
		)
		(fp_poly
			(pts
				(arc
					(start 0.6096 0)
					(mid -0.6096 0)
					(end 0.6096 0)
				)
			)
			(stroke
				(width 0)
				(type default)
			)
			(fill no)
			(layer "B.Fab")
		)
		(pad "1" smd circle
			(at 0 0 180)
			(size 0.7112 0.7112)
			(layers "B.Cu" "B.Mask" "B.Paste")
			(net "SIO_DIN_1")
		)
	)
	(footprint ""
		(layer "B.Cu")
		(at 196.6849 -65.1129 180)
		(property "Reference" "C397"
			(at 0 0 0)
			(layer "B.SilkS")
			(hide yes)
			(effects
				(font
					(size 1.27 1.27)
				)
				(justify mirror)
			)
		)
		(property "Value" "SCD1U6D3V1KX-GP"
			(at 2.8321 -1.7399 180)
			(unlocked yes)
			(layer "B.Fab")
			(hide yes)
			(effects
				(font
					(size 1.016 1.016)
					(thickness 0.1524)
				)
				(justify mirror)
			)
		)
		(property "Device Type" "C0201H13"
			(at 2.8321 -3.2639 180)
			(unlocked yes)
			(layer "B.Fab")
			(hide yes)
			(effects
				(font
					(size 1.016 1.016)
					(thickness 0.1524)
				)
				(justify mirror)
			)
		)
		(duplicate_pad_numbers_are_jumpers no)
		(fp_rect
			(start 0.2794 0.6477)
			(end -0.2794 -0.6477)
			(stroke
				(width 0)
				(type default)
			)
			(fill no)
			(layer "B.CrtYd")
		)
		(fp_rect
			(start 0.2794 0.6477)
			(end -0.2794 -0.6477)
			(stroke
				(width 0)
				(type default)
			)
			(fill no)
			(layer "B.Fab")
		)
		(pad "1" smd custom
			(at 0 -0.2794)
			(size 0.0762 0.0762)
			(layers "B.Cu" "B.Mask" "B.Paste")
			(net "P0V975")
			(options
				(clearance outline)
				(anchor circle)
			)
			(primitives
				(gr_poly
					(pts
						(arc
							(start 0.1524 0.127)
							(mid 0.137521 0.162921)
							(end 0.1016 0.1778)
						)
						(arc
							(start -0.1016 0.1778)
							(mid -0.137521 0.162921)
							(end -0.1524 0.127)
						)
						(arc
							(start -0.1524 -0.127)
							(mid -0.137521 -0.162921)
							(end -0.1016 -0.1778)
						)
						(arc
							(start 0.1016 -0.1778)
							(mid 0.137521 -0.162921)
							(end 0.1524 -0.127)
						)
					)
					(width 0)
					(fill yes)
				)
			)
		)
		(pad "2" smd custom
			(at 0 0.2794)
			(size 0.0762 0.0762)
			(layers "B.Cu" "B.Mask" "B.Paste")
			(net "GND")
			(options
				(clearance outline)
				(anchor circle)
			)
			(primitives
				(gr_poly
					(pts
						(arc
							(start 0.1524 0.127)
							(mid 0.137521 0.162921)
							(end 0.1016 0.1778)
						)
						(arc
							(start -0.1016 0.1778)
							(mid -0.137521 0.162921)
							(end -0.1524 0.127)
						)
						(arc
							(start -0.1524 -0.127)
							(mid -0.137521 -0.162921)
							(end -0.1016 -0.1778)
						)
						(arc
							(start 0.1016 -0.1778)
							(mid 0.137521 -0.162921)
							(end 0.1524 -0.127)
						)
					)
					(width 0)
					(fill yes)
				)
			)
		)
	)
	(footprint ""
		(layer "B.Cu")
		(at 79.8576 -145.542 -90)
		(property "Reference" "R128"
			(at 0 0 90)
			(layer "B.SilkS")
			(hide yes)
			(effects
				(font
					(size 1.27 1.27)
				)
				(justify mirror)
			)
		)
		(property "Value" "0R2J-2-GP"
			(at -0.064008 -3.993896 270)
			(unlocked yes)
			(layer "B.Fab")
			(hide yes)
			(effects
				(font
					(size 1.016 1.016)
					(thickness 0.1524)
				)
				(justify mirror)
			)
		)
		(property "Device Type" "R402H16"
			(at -0.064008 -5.517896 270)
			(unlocked yes)
			(layer "B.Fab")
			(hide yes)
			(effects
				(font
					(size 1.016 1.016)
					(thickness 0.1524)
				)
				(justify mirror)
			)
		)
		(duplicate_pad_numbers_are_jumpers no)
		(fp_line
			(start -0.508 -0.9398)
			(end 0.508 -0.9398)
			(stroke
				(width 0.1524)
				(type default)
			)
			(layer "B.SilkS")
		)
		(fp_line
			(start 0.508 -0.9398)
			(end 0.508 0.9398)
			(stroke
				(width 0.1524)
				(type default)
			)
			(layer "B.SilkS")
		)
		(fp_rect
			(start 0.508 0.9398)
			(end -0.508 -0.9398)
			(stroke
				(width 0)
				(type default)
			)
			(fill no)
			(layer "B.CrtYd")
		)
		(fp_rect
			(start 0.508 0.9398)
			(end -0.508 -0.9398)
			(stroke
				(width 0)
				(type default)
			)
			(fill no)
			(layer "B.Fab")
		)
		(pad "1" smd custom
			(at 0 -0.4445 90)
			(size 0.1397 0.1397)
			(layers "B.Cu" "B.Mask" "B.Paste")
			(net "I2C_EXP_LOC_SDA")
			(options
				(clearance outline)
				(anchor circle)
			)
			(primitives
				(gr_poly
					(pts
						(arc
							(start -0.1778 0.2794)
							(mid -0.249642 0.249642)
							(end -0.2794 0.1778)
						)
						(arc
							(start -0.2794 -0.1778)
							(mid -0.249642 -0.249642)
							(end -0.1778 -0.2794)
						)
						(arc
							(start 0.1778 -0.2794)
							(mid 0.249642 -0.249642)
							(end 0.2794 -0.1778)
						)
						(arc
							(start 0.2794 0.1778)
							(mid 0.249642 0.249642)
							(end 0.1778 0.2794)
						)
					)
					(width 0)
					(fill yes)
				)
			)
		)
		(pad "2" smd custom
			(at 0 0.4445 90)
			(size 0.1397 0.1397)
			(layers "B.Cu" "B.Mask" "B.Paste")
			(net "I2C_EXP_LOC_SDA_R")
			(options
				(clearance outline)
				(anchor circle)
			)
			(primitives
				(gr_poly
					(pts
						(arc
							(start -0.1778 0.2794)
							(mid -0.249642 0.249642)
							(end -0.2794 0.1778)
						)
						(arc
							(start -0.2794 -0.1778)
							(mid -0.249642 -0.249642)
							(end -0.1778 -0.2794)
						)
						(arc
							(start 0.1778 -0.2794)
							(mid 0.249642 -0.249642)
							(end 0.2794 -0.1778)
						)
						(arc
							(start 0.2794 0.1778)
							(mid 0.249642 0.249642)
							(end 0.1778 0.2794)
						)
					)
					(width 0)
					(fill yes)
				)
			)
		)
	)
	(footprint ""
		(layer "B.Cu")
		(at 78.9051 -167.1447 -90)
		(property "Reference" "R651"
			(at 0 0 90)
			(layer "B.SilkS")
			(hide yes)
			(effects
				(font
					(size 1.27 1.27)
				)
				(justify mirror)
			)
		)
		(property "Value" "0R2J-2-GP"
			(at -0.064008 -3.993896 270)
			(unlocked yes)
			(layer "B.Fab")
			(hide yes)
			(effects
				(font
					(size 1.016 1.016)
					(thickness 0.1524)
				)
				(justify mirror)
			)
		)
		(property "Device Type" "R402H16"
			(at -0.064008 -5.517896 270)
			(unlocked yes)
			(layer "B.Fab")
			(hide yes)
			(effects
				(font
					(size 1.016 1.016)
					(thickness 0.1524)
				)
				(justify mirror)
			)
		)
		(duplicate_pad_numbers_are_jumpers no)
		(fp_line
			(start -0.508 -0.9398)
			(end 0.508 -0.9398)
			(stroke
				(width 0.1524)
				(type default)
			)
			(layer "B.SilkS")
		)
		(fp_line
			(start 0.508 -0.9398)
			(end 0.508 0.9398)
			(stroke
				(width 0.1524)
				(type default)
			)
			(layer "B.SilkS")
		)
		(fp_rect
			(start 0.508 0.9398)
			(end -0.508 -0.9398)
			(stroke
				(width 0)
				(type default)
			)
			(fill no)
			(layer "B.CrtYd")
		)
		(fp_rect
			(start 0.508 0.9398)
			(end -0.508 -0.9398)
			(stroke
				(width 0)
				(type default)
			)
			(fill no)
			(layer "B.Fab")
		)
		(pad "1" smd custom
			(at 0 -0.4445 90)
			(size 0.1397 0.1397)
			(layers "B.Cu" "B.Mask" "B.Paste")
			(net "EXP_UART_EN_R")
			(options
				(clearance outline)
				(anchor circle)
			)
			(primitives
				(gr_poly
					(pts
						(arc
							(start -0.1778 0.2794)
							(mid -0.249642 0.249642)
							(end -0.2794 0.1778)
						)
						(arc
							(start -0.2794 -0.1778)
							(mid -0.249642 -0.249642)
							(end -0.1778 -0.2794)
						)
						(arc
							(start 0.1778 -0.2794)
							(mid 0.249642 -0.249642)
							(end 0.2794 -0.1778)
						)
						(arc
							(start 0.2794 0.1778)
							(mid 0.249642 0.249642)
							(end 0.1778 0.2794)
						)
					)
					(width 0)
					(fill yes)
				)
			)
		)
		(pad "2" smd custom
			(at 0 0.4445 90)
			(size 0.1397 0.1397)
			(layers "B.Cu" "B.Mask" "B.Paste")
			(net "EXP_UART_EN")
			(options
				(clearance outline)
				(anchor circle)
			)
			(primitives
				(gr_poly
					(pts
						(arc
							(start -0.1778 0.2794)
							(mid -0.249642 0.249642)
							(end -0.2794 0.1778)
						)
						(arc
							(start -0.2794 -0.1778)
							(mid -0.249642 -0.249642)
							(end -0.1778 -0.2794)
						)
						(arc
							(start 0.1778 -0.2794)
							(mid 0.249642 -0.249642)
							(end 0.2794 -0.1778)
						)
						(arc
							(start 0.2794 0.1778)
							(mid 0.249642 0.249642)
							(end 0.1778 0.2794)
						)
					)
					(width 0)
					(fill yes)
				)
			)
		)
	)
	(footprint ""
		(layer "B.Cu")
		(at 195.5292 -65.3669 90)
		(property "Reference" "C405"
			(at 0 0 90)
			(layer "B.SilkS")
			(hide yes)
			(effects
				(font
					(size 1.27 1.27)
				)
				(justify mirror)
			)
		)
		(property "Value" "SCD1U6D3V1KX-GP"
			(at 2.8321 -1.7399 90)
			(unlocked yes)
			(layer "B.Fab")
			(hide yes)
			(effects
				(font
					(size 1.016 1.016)
					(thickness 0.1524)
				)
				(justify mirror)
			)
		)
		(property "Device Type" "C0201H13"
			(at 2.8321 -3.2639 90)
			(unlocked yes)
			(layer "B.Fab")
			(hide yes)
			(effects
				(font
					(size 1.016 1.016)
					(thickness 0.1524)
				)
				(justify mirror)
			)
		)
		(duplicate_pad_numbers_are_jumpers no)
		(fp_rect
			(start 0.2794 0.6477)
			(end -0.2794 -0.6477)
			(stroke
				(width 0)
				(type default)
			)
			(fill no)
			(layer "B.CrtYd")
		)
		(fp_rect
			(start 0.2794 0.6477)
			(end -0.2794 -0.6477)
			(stroke
				(width 0)
				(type default)
			)
			(fill no)
			(layer "B.Fab")
		)
		(pad "1" smd custom
			(at 0 -0.2794 270)
			(size 0.0762 0.0762)
			(layers "B.Cu" "B.Mask" "B.Paste")
			(net "P0V975")
			(options
				(clearance outline)
				(anchor circle)
			)
			(primitives
				(gr_poly
					(pts
						(arc
							(start 0.1524 0.127)
							(mid 0.137521 0.162921)
							(end 0.1016 0.1778)
						)
						(arc
							(start -0.1016 0.1778)
							(mid -0.137521 0.162921)
							(end -0.1524 0.127)
						)
						(arc
							(start -0.1524 -0.127)
							(mid -0.137521 -0.162921)
							(end -0.1016 -0.1778)
						)
						(arc
							(start 0.1016 -0.1778)
							(mid 0.137521 -0.162921)
							(end 0.1524 -0.127)
						)
					)
					(width 0)
					(fill yes)
				)
			)
		)
		(pad "2" smd custom
			(at 0 0.2794 270)
			(size 0.0762 0.0762)
			(layers "B.Cu" "B.Mask" "B.Paste")
			(net "GND")
			(options
				(clearance outline)
				(anchor circle)
			)
			(primitives
				(gr_poly
					(pts
						(arc
							(start 0.1524 0.127)
							(mid 0.137521 0.162921)
							(end 0.1016 0.1778)
						)
						(arc
							(start -0.1016 0.1778)
							(mid -0.137521 0.162921)
							(end -0.1524 0.127)
						)
						(arc
							(start -0.1524 -0.127)
							(mid -0.137521 -0.162921)
							(end -0.1016 -0.1778)
						)
						(arc
							(start 0.1016 -0.1778)
							(mid 0.137521 -0.162921)
							(end 0.1524 -0.127)
						)
					)
					(width 0)
					(fill yes)
				)
			)
		)
	)
	(footprint ""
		(layer "B.Cu")
		(at 42.382694 -125.12548)
		(property "Reference" "R364"
			(at 0 0 0)
			(layer "B.SilkS")
			(hide yes)
			(effects
				(font
					(size 1.27 1.27)
				)
				(justify mirror)
			)
		)
		(property "Value" "4K7R2F-GP"
			(at -0.064008 -3.993896 0)
			(unlocked yes)
			(layer "B.Fab")
			(hide yes)
			(effects
				(font
					(size 1.016 1.016)
					(thickness 0.1524)
				)
				(justify mirror)
			)
		)
		(property "Device Type" "R402H16"
			(at -0.064008 -5.517896 0)
			(unlocked yes)
			(layer "B.Fab")
			(hide yes)
			(effects
				(font
					(size 1.016 1.016)
					(thickness 0.1524)
				)
				(justify mirror)
			)
		)
		(duplicate_pad_numbers_are_jumpers no)
		(fp_line
			(start -0.508 -0.9398)
			(end 0.508 -0.9398)
			(stroke
				(width 0.1524)
				(type default)
			)
			(layer "B.SilkS")
		)
		(fp_line
			(start 0.508 -0.9398)
			(end 0.508 0.9398)
			(stroke
				(width 0.1524)
				(type default)
			)
			(layer "B.SilkS")
		)
		(fp_rect
			(start 0.508 0.9398)
			(end -0.508 -0.9398)
			(stroke
				(width 0)
				(type default)
			)
			(fill no)
			(layer "B.CrtYd")
		)
		(fp_rect
			(start 0.508 0.9398)
			(end -0.508 -0.9398)
			(stroke
				(width 0)
				(type default)
			)
			(fill no)
			(layer "B.Fab")
		)
		(pad "1" smd custom
			(at 0 -0.4445 180)
			(size 0.1397 0.1397)
			(layers "B.Cu" "B.Mask" "B.Paste")
			(net "FM_BMC_RESET_N")
			(options
				(clearance outline)
				(anchor circle)
			)
			(primitives
				(gr_poly
					(pts
						(arc
							(start -0.1778 0.2794)
							(mid -0.249642 0.249642)
							(end -0.2794 0.1778)
						)
						(arc
							(start -0.2794 -0.1778)
							(mid -0.249642 -0.249642)
							(end -0.1778 -0.2794)
						)
						(arc
							(start 0.1778 -0.2794)
							(mid 0.249642 -0.249642)
							(end 0.2794 -0.1778)
						)
						(arc
							(start 0.2794 0.1778)
							(mid 0.249642 0.249642)
							(end 0.1778 0.2794)
						)
					)
					(width 0)
					(fill yes)
				)
			)
		)
		(pad "2" smd custom
			(at 0 0.4445 180)
			(size 0.1397 0.1397)
			(layers "B.Cu" "B.Mask" "B.Paste")
			(net "GND")
			(options
				(clearance outline)
				(anchor circle)
			)
			(primitives
				(gr_poly
					(pts
						(arc
							(start -0.1778 0.2794)
							(mid -0.249642 0.249642)
							(end -0.2794 0.1778)
						)
						(arc
							(start -0.2794 -0.1778)
							(mid -0.249642 -0.249642)
							(end -0.1778 -0.2794)
						)
						(arc
							(start 0.1778 -0.2794)
							(mid 0.249642 -0.249642)
							(end 0.2794 -0.1778)
						)
						(arc
							(start 0.2794 0.1778)
							(mid 0.249642 0.249642)
							(end 0.1778 0.2794)
						)
					)
					(width 0)
					(fill yes)
				)
			)
		)
	)
	(footprint ""
		(layer "B.Cu")
		(at 174.5742 -68.3768 90)
		(property "Reference" "R583"
			(at 0 0 90)
			(layer "B.SilkS")
			(hide yes)
			(effects
				(font
					(size 1.27 1.27)
				)
				(justify mirror)
			)
		)
		(property "Value" "2K2R2F-GP"
			(at -0.064008 -3.993896 90)
			(unlocked yes)
			(layer "B.Fab")
			(hide yes)
			(effects
				(font
					(size 1.016 1.016)
					(thickness 0.1524)
				)
				(justify mirror)
			)
		)
		(property "Device Type" "R402H16"
			(at -0.064008 -5.517896 90)
			(unlocked yes)
			(layer "B.Fab")
			(hide yes)
			(effects
				(font
					(size 1.016 1.016)
					(thickness 0.1524)
				)
				(justify mirror)
			)
		)
		(duplicate_pad_numbers_are_jumpers no)
		(fp_line
			(start 0.508 -0.9398)
			(end 0.508 0.9398)
			(stroke
				(width 0.1524)
				(type default)
			)
			(layer "B.SilkS")
		)
		(fp_line
			(start -0.508 -0.9398)
			(end 0.508 -0.9398)
			(stroke
				(width 0.1524)
				(type default)
			)
			(layer "B.SilkS")
		)
		(fp_rect
			(start 0.508 0.9398)
			(end -0.508 -0.9398)
			(stroke
				(width 0)
				(type default)
			)
			(fill no)
			(layer "B.CrtYd")
		)
		(fp_rect
			(start 0.508 0.9398)
			(end -0.508 -0.9398)
			(stroke
				(width 0)
				(type default)
			)
			(fill no)
			(layer "B.Fab")
		)
		(pad "1" smd custom
			(at 0 -0.4445 270)
			(size 0.1397 0.1397)
			(layers "B.Cu" "B.Mask" "B.Paste")
			(net "P1V8")
			(options
				(clearance outline)
				(anchor circle)
			)
			(primitives
				(gr_poly
					(pts
						(arc
							(start -0.1778 0.2794)
							(mid -0.249642 0.249642)
							(end -0.2794 0.1778)
						)
						(arc
							(start -0.2794 -0.1778)
							(mid -0.249642 -0.249642)
							(end -0.1778 -0.2794)
						)
						(arc
							(start 0.1778 -0.2794)
							(mid 0.249642 -0.249642)
							(end 0.2794 -0.1778)
						)
						(arc
							(start 0.2794 0.1778)
							(mid 0.249642 0.249642)
							(end 0.1778 0.2794)
						)
					)
					(width 0)
					(fill yes)
				)
			)
		)
		(pad "2" smd custom
			(at 0 0.4445 270)
			(size 0.1397 0.1397)
			(layers "B.Cu" "B.Mask" "B.Paste")
			(net "IOC_SCL_2")
			(options
				(clearance outline)
				(anchor circle)
			)
			(primitives
				(gr_poly
					(pts
						(arc
							(start -0.1778 0.2794)
							(mid -0.249642 0.249642)
							(end -0.2794 0.1778)
						)
						(arc
							(start -0.2794 -0.1778)
							(mid -0.249642 -0.249642)
							(end -0.1778 -0.2794)
						)
						(arc
							(start 0.1778 -0.2794)
							(mid 0.249642 -0.249642)
							(end 0.2794 -0.1778)
						)
						(arc
							(start 0.2794 0.1778)
							(mid 0.249642 0.249642)
							(end 0.1778 0.2794)
						)
					)
					(width 0)
					(fill yes)
				)
			)
		)
	)
	(footprint ""
		(layer "B.Cu")
		(at 50.1396 -139.446)
		(property "Reference" "TP72"
			(at 0 0 0)
			(layer "B.SilkS")
			(hide yes)
			(effects
				(font
					(size 1.27 1.27)
				)
				(justify mirror)
			)
		)
		(property "Value" "TPAD28-2-GP"
			(at 0.0127 -1.6637 0)
			(unlocked yes)
			(layer "B.Fab")
			(hide yes)
			(effects
				(font
					(size 1.016 1.016)
					(thickness 0.1524)
				)
				(justify mirror)
			)
		)
		(property "Device Type" "TPAD28"
			(at 0.0127 -3.1877 0)
			(unlocked yes)
			(layer "B.Fab")
			(hide yes)
			(effects
				(font
					(size 1.016 1.016)
					(thickness 0.1524)
				)
				(justify mirror)
			)
		)
		(duplicate_pad_numbers_are_jumpers no)
		(fp_poly
			(pts
				(arc
					(start 0.3556 0)
					(mid -0.3556 0)
					(end 0.3556 0)
				)
			)
			(stroke
				(width 0)
				(type default)
			)
			(fill no)
			(layer "B.CrtYd")
		)
		(fp_poly
			(pts
				(arc
					(start 0.6096 0)
					(mid -0.6096 0)
					(end 0.6096 0)
				)
			)
			(stroke
				(width 0)
				(type default)
			)
			(fill no)
			(layer "B.Fab")
		)
		(pad "1" smd circle
			(at 0 0 180)
			(size 0.7112 0.7112)
			(layers "B.Cu" "B.Mask" "B.Paste")
			(net "TP_BMC_GPIOI1")
		)
	)
	(footprint ""
		(layer "B.Cu")
		(at 169.7736 -76.5302 -90)
		(property "Reference" "L16"
			(at 0 0 90)
			(layer "B.SilkS")
			(hide yes)
			(effects
				(font
					(size 1.27 1.27)
				)
				(justify mirror)
			)
		)
		(property "Value" "MPZ2012S601AT-GP"
			(at 0 -4.2418 270)
			(unlocked yes)
			(layer "B.Fab")
			(hide yes)
			(effects
				(font
					(size 1.016 1.016)
					(thickness 0.1524)
				)
				(justify mirror)
			)
		)
		(property "Device Type" "L805H42"
			(at 0 -5.7912 270)
			(unlocked yes)
			(layer "B.Fab")
			(hide yes)
			(effects
				(font
					(size 1.016 1.016)
					(thickness 0.1524)
				)
				(justify mirror)
			)
		)
		(duplicate_pad_numbers_are_jumpers no)
		(fp_line
			(start -0.889 1.7018)
			(end 0.889 1.7018)
			(stroke
				(width 0.1524)
				(type default)
			)
			(layer "B.SilkS")
		)
		(fp_line
			(start 0.889 1.7018)
			(end 0.889 -1.7018)
			(stroke
				(width 0.1524)
				(type default)
			)
			(layer "B.SilkS")
		)
		(fp_line
			(start -0.889 -1.7018)
			(end -0.889 1.7018)
			(stroke
				(width 0.1524)
				(type default)
			)
			(layer "B.SilkS")
		)
		(fp_line
			(start 0.889 -1.7018)
			(end -0.889 -1.7018)
			(stroke
				(width 0.1524)
				(type default)
			)
			(layer "B.SilkS")
		)
		(fp_rect
			(start 0.9652 1.778)
			(end -0.9652 -1.778)
			(stroke
				(width 0)
				(type default)
			)
			(fill no)
			(layer "B.CrtYd")
		)
		(fp_rect
			(start 0.9652 1.778)
			(end -0.9652 -1.778)
			(stroke
				(width 0)
				(type default)
			)
			(fill no)
			(layer "B.Fab")
		)
		(pad "1" smd rect
			(at 0 -0.9652 90)
			(size 1.397 1.143)
			(layers "B.Cu" "B.Mask" "B.Paste")
			(net "PLL_VDD")
		)
		(pad "2" smd rect
			(at 0 0.9652 90)
			(size 1.397 1.143)
			(layers "B.Cu" "B.Mask" "B.Paste")
			(net "P1V8")
		)
	)
	(footprint ""
		(layer "B.Cu")
		(at 80.08366 -172.76318 180)
		(property "Reference" "R451"
			(at 0 0 0)
			(layer "B.SilkS")
			(hide yes)
			(effects
				(font
					(size 1.27 1.27)
				)
				(justify mirror)
			)
		)
		(property "Value" "10KR2F-2-GP"
			(at -0.064008 -3.993896 180)
			(unlocked yes)
			(layer "B.Fab")
			(hide yes)
			(effects
				(font
					(size 1.016 1.016)
					(thickness 0.1524)
				)
				(justify mirror)
			)
		)
		(property "Device Type" "R402H16"
			(at -0.064008 -5.517896 180)
			(unlocked yes)
			(layer "B.Fab")
			(hide yes)
			(effects
				(font
					(size 1.016 1.016)
					(thickness 0.1524)
				)
				(justify mirror)
			)
		)
		(duplicate_pad_numbers_are_jumpers no)
		(fp_line
			(start 0.508 -0.9398)
			(end 0.508 0.9398)
			(stroke
				(width 0.1524)
				(type default)
			)
			(layer "B.SilkS")
		)
		(fp_line
			(start -0.508 -0.9398)
			(end 0.508 -0.9398)
			(stroke
				(width 0.1524)
				(type default)
			)
			(layer "B.SilkS")
		)
		(fp_rect
			(start 0.508 0.9398)
			(end -0.508 -0.9398)
			(stroke
				(width 0)
				(type default)
			)
			(fill no)
			(layer "B.CrtYd")
		)
		(fp_rect
			(start 0.508 0.9398)
			(end -0.508 -0.9398)
			(stroke
				(width 0)
				(type default)
			)
			(fill no)
			(layer "B.Fab")
		)
		(pad "1" smd custom
			(at 0 -0.4445)
			(size 0.1397 0.1397)
			(layers "B.Cu" "B.Mask" "B.Paste")
			(net "EXP_UART_EN_R")
			(options
				(clearance outline)
				(anchor circle)
			)
			(primitives
				(gr_poly
					(pts
						(arc
							(start -0.1778 0.2794)
							(mid -0.249642 0.249642)
							(end -0.2794 0.1778)
						)
						(arc
							(start -0.2794 -0.1778)
							(mid -0.249642 -0.249642)
							(end -0.1778 -0.2794)
						)
						(arc
							(start 0.1778 -0.2794)
							(mid 0.249642 -0.249642)
							(end 0.2794 -0.1778)
						)
						(arc
							(start 0.2794 0.1778)
							(mid 0.249642 0.249642)
							(end 0.1778 0.2794)
						)
					)
					(width 0)
					(fill yes)
				)
			)
		)
		(pad "2" smd custom
			(at 0 0.4445)
			(size 0.1397 0.1397)
			(layers "B.Cu" "B.Mask" "B.Paste")
			(net "GND")
			(options
				(clearance outline)
				(anchor circle)
			)
			(primitives
				(gr_poly
					(pts
						(arc
							(start -0.1778 0.2794)
							(mid -0.249642 0.249642)
							(end -0.2794 0.1778)
						)
						(arc
							(start -0.2794 -0.1778)
							(mid -0.249642 -0.249642)
							(end -0.1778 -0.2794)
						)
						(arc
							(start 0.1778 -0.2794)
							(mid 0.249642 -0.249642)
							(end 0.2794 -0.1778)
						)
						(arc
							(start 0.2794 0.1778)
							(mid 0.249642 0.249642)
							(end 0.1778 0.2794)
						)
					)
					(width 0)
					(fill yes)
				)
			)
		)
	)
	(footprint ""
		(layer "B.Cu")
		(at 58.900568 -138.905234 -90)
		(property "Reference" "TP69"
			(at 0 0 90)
			(layer "B.SilkS")
			(hide yes)
			(effects
				(font
					(size 1.27 1.27)
				)
				(justify mirror)
			)
		)
		(property "Value" "TPAD28-2-GP"
			(at 0.0127 -1.6637 270)
			(unlocked yes)
			(layer "B.Fab")
			(hide yes)
			(effects
				(font
					(size 1.016 1.016)
					(thickness 0.1524)
				)
				(justify mirror)
			)
		)
		(property "Device Type" "TPAD28"
			(at 0.0127 -3.1877 270)
			(unlocked yes)
			(layer "B.Fab")
			(hide yes)
			(effects
				(font
					(size 1.016 1.016)
					(thickness 0.1524)
				)
				(justify mirror)
			)
		)
		(duplicate_pad_numbers_are_jumpers no)
		(fp_poly
			(pts
				(arc
					(start 0 -0.3556)
					(mid 0 0.3556)
					(end 0 -0.3556)
				)
			)
			(stroke
				(width 0)
				(type default)
			)
			(fill no)
			(layer "B.CrtYd")
		)
		(fp_poly
			(pts
				(arc
					(start 0 -0.6096)
					(mid 0 0.6096)
					(end 0 -0.6096)
				)
			)
			(stroke
				(width 0)
				(type default)
			)
			(fill no)
			(layer "B.Fab")
		)
		(pad "1" smd circle
			(at 0 0 90)
			(size 0.7112 0.7112)
			(layers "B.Cu" "B.Mask" "B.Paste")
			(net "TP_BMC_GPIOG6")
		)
	)
	(footprint ""
		(layer "B.Cu")
		(at 10.20191 -135.290052 90)
		(property "Reference" "R256"
			(at 0 0 90)
			(layer "B.SilkS")
			(hide yes)
			(effects
				(font
					(size 1.27 1.27)
				)
				(justify mirror)
			)
		)
		(property "Value" "120R2F-GP"
			(at -0.064008 -3.993896 90)
			(unlocked yes)
			(layer "B.Fab")
			(hide yes)
			(effects
				(font
					(size 1.016 1.016)
					(thickness 0.1524)
				)
				(justify mirror)
			)
		)
		(property "Device Type" "R402H16"
			(at -0.064008 -5.517896 90)
			(unlocked yes)
			(layer "B.Fab")
			(hide yes)
			(effects
				(font
					(size 1.016 1.016)
					(thickness 0.1524)
				)
				(justify mirror)
			)
		)
		(duplicate_pad_numbers_are_jumpers no)
		(fp_line
			(start 0.508 -0.9398)
			(end 0.508 0.9398)
			(stroke
				(width 0.1524)
				(type default)
			)
			(layer "B.SilkS")
		)
		(fp_line
			(start -0.508 -0.9398)
			(end 0.508 -0.9398)
			(stroke
				(width 0.1524)
				(type default)
			)
			(layer "B.SilkS")
		)
		(fp_rect
			(start 0.508 0.9398)
			(end -0.508 -0.9398)
			(stroke
				(width 0)
				(type default)
			)
			(fill no)
			(layer "B.CrtYd")
		)
		(fp_rect
			(start 0.508 0.9398)
			(end -0.508 -0.9398)
			(stroke
				(width 0)
				(type default)
			)
			(fill no)
			(layer "B.Fab")
		)
		(pad "1" smd custom
			(at 0 -0.4445 270)
			(size 0.1397 0.1397)
			(layers "B.Cu" "B.Mask" "B.Paste")
			(net "GND")
			(options
				(clearance outline)
				(anchor circle)
			)
			(primitives
				(gr_poly
					(pts
						(arc
							(start -0.1778 0.2794)
							(mid -0.249642 0.249642)
							(end -0.2794 0.1778)
						)
						(arc
							(start -0.2794 -0.1778)
							(mid -0.249642 -0.249642)
							(end -0.1778 -0.2794)
						)
						(arc
							(start 0.1778 -0.2794)
							(mid 0.249642 -0.249642)
							(end 0.2794 -0.1778)
						)
						(arc
							(start 0.2794 0.1778)
							(mid 0.249642 0.249642)
							(end 0.1778 0.2794)
						)
					)
					(width 0)
					(fill yes)
				)
			)
		)
		(pad "2" smd custom
			(at 0 0.4445 270)
			(size 0.1397 0.1397)
			(layers "B.Cu" "B.Mask" "B.Paste")
			(net "MEMA_11")
			(options
				(clearance outline)
				(anchor circle)
			)
			(primitives
				(gr_poly
					(pts
						(arc
							(start -0.1778 0.2794)
							(mid -0.249642 0.249642)
							(end -0.2794 0.1778)
						)
						(arc
							(start -0.2794 -0.1778)
							(mid -0.249642 -0.249642)
							(end -0.1778 -0.2794)
						)
						(arc
							(start 0.1778 -0.2794)
							(mid 0.249642 -0.249642)
							(end 0.2794 -0.1778)
						)
						(arc
							(start 0.2794 0.1778)
							(mid 0.249642 0.249642)
							(end 0.1778 0.2794)
						)
					)
					(width 0)
					(fill yes)
				)
			)
		)
	)
	(footprint ""
		(layer "B.Cu")
		(at 59.563 -163.1442 -90)
		(property "Reference" "R403"
			(at 0 0 90)
			(layer "B.SilkS")
			(hide yes)
			(effects
				(font
					(size 1.27 1.27)
				)
				(justify mirror)
			)
		)
		(property "Value" "330R2F-GP"
			(at -0.064008 -3.993896 270)
			(unlocked yes)
			(layer "B.Fab")
			(hide yes)
			(effects
				(font
					(size 1.016 1.016)
					(thickness 0.1524)
				)
				(justify mirror)
			)
		)
		(property "Device Type" "R402H16"
			(at -0.064008 -5.517896 270)
			(unlocked yes)
			(layer "B.Fab")
			(hide yes)
			(effects
				(font
					(size 1.016 1.016)
					(thickness 0.1524)
				)
				(justify mirror)
			)
		)
		(duplicate_pad_numbers_are_jumpers no)
		(fp_line
			(start -0.508 -0.9398)
			(end 0.508 -0.9398)
			(stroke
				(width 0.1524)
				(type default)
			)
			(layer "B.SilkS")
		)
		(fp_line
			(start 0.508 -0.9398)
			(end 0.508 0.9398)
			(stroke
				(width 0.1524)
				(type default)
			)
			(layer "B.SilkS")
		)
		(fp_rect
			(start 0.508 0.9398)
			(end -0.508 -0.9398)
			(stroke
				(width 0)
				(type default)
			)
			(fill no)
			(layer "B.CrtYd")
		)
		(fp_rect
			(start 0.508 0.9398)
			(end -0.508 -0.9398)
			(stroke
				(width 0)
				(type default)
			)
			(fill no)
			(layer "B.Fab")
		)
		(pad "1" smd custom
			(at 0 -0.4445 90)
			(size 0.1397 0.1397)
			(layers "B.Cu" "B.Mask" "B.Paste")
			(net "P1V8")
			(options
				(clearance outline)
				(anchor circle)
			)
			(primitives
				(gr_poly
					(pts
						(arc
							(start -0.1778 0.2794)
							(mid -0.249642 0.249642)
							(end -0.2794 0.1778)
						)
						(arc
							(start -0.2794 -0.1778)
							(mid -0.249642 -0.249642)
							(end -0.1778 -0.2794)
						)
						(arc
							(start 0.1778 -0.2794)
							(mid 0.249642 -0.249642)
							(end 0.2794 -0.1778)
						)
						(arc
							(start 0.2794 0.1778)
							(mid 0.249642 0.249642)
							(end 0.1778 0.2794)
						)
					)
					(width 0)
					(fill yes)
				)
			)
		)
		(pad "2" smd custom
			(at 0 0.4445 90)
			(size 0.1397 0.1397)
			(layers "B.Cu" "B.Mask" "B.Paste")
			(net "ADC_P1V8")
			(options
				(clearance outline)
				(anchor circle)
			)
			(primitives
				(gr_poly
					(pts
						(arc
							(start -0.1778 0.2794)
							(mid -0.249642 0.249642)
							(end -0.2794 0.1778)
						)
						(arc
							(start -0.2794 -0.1778)
							(mid -0.249642 -0.249642)
							(end -0.1778 -0.2794)
						)
						(arc
							(start 0.1778 -0.2794)
							(mid 0.249642 -0.249642)
							(end 0.2794 -0.1778)
						)
						(arc
							(start 0.2794 0.1778)
							(mid 0.249642 0.249642)
							(end 0.1778 0.2794)
						)
					)
					(width 0)
					(fill yes)
				)
			)
		)
	)
	(footprint ""
		(layer "B.Cu")
		(at 190.199518 -81.153 180)
		(property "Reference" "C301"
			(at 0 0 0)
			(layer "B.SilkS")
			(hide yes)
			(effects
				(font
					(size 1.27 1.27)
				)
				(justify mirror)
			)
		)
		(property "Value" "SCD22U10V1KX-GP"
			(at 2.8321 -1.7399 180)
			(unlocked yes)
			(layer "B.Fab")
			(hide yes)
			(effects
				(font
					(size 1.016 1.016)
					(thickness 0.1524)
				)
				(justify mirror)
			)
		)
		(property "Device Type" "C0201H13"
			(at 2.8321 -3.2639 180)
			(unlocked yes)
			(layer "B.Fab")
			(hide yes)
			(effects
				(font
					(size 1.016 1.016)
					(thickness 0.1524)
				)
				(justify mirror)
			)
		)
		(duplicate_pad_numbers_are_jumpers no)
		(fp_rect
			(start 0.2794 0.6477)
			(end -0.2794 -0.6477)
			(stroke
				(width 0)
				(type default)
			)
			(fill no)
			(layer "B.CrtYd")
		)
		(fp_rect
			(start 0.2794 0.6477)
			(end -0.2794 -0.6477)
			(stroke
				(width 0)
				(type default)
			)
			(fill no)
			(layer "B.Fab")
		)
		(pad "1" smd custom
			(at 0 -0.2794)
			(size 0.0762 0.0762)
			(layers "B.Cu" "B.Mask" "B.Paste")
			(net "PCIE_IOM_TO_COMP_14_DP_C")
			(options
				(clearance outline)
				(anchor circle)
			)
			(primitives
				(gr_poly
					(pts
						(arc
							(start 0.1524 0.127)
							(mid 0.137521 0.162921)
							(end 0.1016 0.1778)
						)
						(arc
							(start -0.1016 0.1778)
							(mid -0.137521 0.162921)
							(end -0.1524 0.127)
						)
						(arc
							(start -0.1524 -0.127)
							(mid -0.137521 -0.162921)
							(end -0.1016 -0.1778)
						)
						(arc
							(start 0.1016 -0.1778)
							(mid 0.137521 -0.162921)
							(end 0.1524 -0.127)
						)
					)
					(width 0)
					(fill yes)
				)
			)
		)
		(pad "2" smd custom
			(at 0 0.2794)
			(size 0.0762 0.0762)
			(layers "B.Cu" "B.Mask" "B.Paste")
			(net "PCIE_IOM_TO_COMP_14_DP")
			(options
				(clearance outline)
				(anchor circle)
			)
			(primitives
				(gr_poly
					(pts
						(arc
							(start 0.1524 0.127)
							(mid 0.137521 0.162921)
							(end 0.1016 0.1778)
						)
						(arc
							(start -0.1016 0.1778)
							(mid -0.137521 0.162921)
							(end -0.1524 0.127)
						)
						(arc
							(start -0.1524 -0.127)
							(mid -0.137521 -0.162921)
							(end -0.1016 -0.1778)
						)
						(arc
							(start 0.1016 -0.1778)
							(mid 0.137521 -0.162921)
							(end 0.1524 -0.127)
						)
					)
					(width 0)
					(fill yes)
				)
			)
		)
	)
	(footprint ""
		(layer "B.Cu")
		(at 199.76846 -67.56654 90)
		(property "Reference" "C380"
			(at 0 0 90)
			(layer "B.SilkS")
			(hide yes)
			(effects
				(font
					(size 1.27 1.27)
				)
				(justify mirror)
			)
		)
		(property "Value" "SCD1U6D3V1KX-GP"
			(at 2.8321 -1.7399 90)
			(unlocked yes)
			(layer "B.Fab")
			(hide yes)
			(effects
				(font
					(size 1.016 1.016)
					(thickness 0.1524)
				)
				(justify mirror)
			)
		)
		(property "Device Type" "C0201H13"
			(at 2.8321 -3.2639 90)
			(unlocked yes)
			(layer "B.Fab")
			(hide yes)
			(effects
				(font
					(size 1.016 1.016)
					(thickness 0.1524)
				)
				(justify mirror)
			)
		)
		(duplicate_pad_numbers_are_jumpers no)
		(fp_rect
			(start 0.2794 0.6477)
			(end -0.2794 -0.6477)
			(stroke
				(width 0)
				(type default)
			)
			(fill no)
			(layer "B.CrtYd")
		)
		(fp_rect
			(start 0.2794 0.6477)
			(end -0.2794 -0.6477)
			(stroke
				(width 0)
				(type default)
			)
			(fill no)
			(layer "B.Fab")
		)
		(pad "1" smd custom
			(at 0 -0.2794 270)
			(size 0.0762 0.0762)
			(layers "B.Cu" "B.Mask" "B.Paste")
			(net "SAS0_AVDD")
			(options
				(clearance outline)
				(anchor circle)
			)
			(primitives
				(gr_poly
					(pts
						(arc
							(start 0.1524 0.127)
							(mid 0.137521 0.162921)
							(end 0.1016 0.1778)
						)
						(arc
							(start -0.1016 0.1778)
							(mid -0.137521 0.162921)
							(end -0.1524 0.127)
						)
						(arc
							(start -0.1524 -0.127)
							(mid -0.137521 -0.162921)
							(end -0.1016 -0.1778)
						)
						(arc
							(start 0.1016 -0.1778)
							(mid 0.137521 -0.162921)
							(end 0.1524 -0.127)
						)
					)
					(width 0)
					(fill yes)
				)
			)
		)
		(pad "2" smd custom
			(at 0 0.2794 270)
			(size 0.0762 0.0762)
			(layers "B.Cu" "B.Mask" "B.Paste")
			(net "GND")
			(options
				(clearance outline)
				(anchor circle)
			)
			(primitives
				(gr_poly
					(pts
						(arc
							(start 0.1524 0.127)
							(mid 0.137521 0.162921)
							(end 0.1016 0.1778)
						)
						(arc
							(start -0.1016 0.1778)
							(mid -0.137521 0.162921)
							(end -0.1524 0.127)
						)
						(arc
							(start -0.1524 -0.127)
							(mid -0.137521 -0.162921)
							(end -0.1016 -0.1778)
						)
						(arc
							(start 0.1016 -0.1778)
							(mid 0.137521 -0.162921)
							(end 0.1524 -0.127)
						)
					)
					(width 0)
					(fill yes)
				)
			)
		)
	)
	(footprint ""
		(layer "B.Cu")
		(at 13.2207 -147.3835 -90)
		(property "Reference" "C61"
			(at 0 0 90)
			(layer "B.SilkS")
			(hide yes)
			(effects
				(font
					(size 1.27 1.27)
				)
				(justify mirror)
			)
		)
		(property "Value" "SC1U16V3KX-5GP"
			(at 0 -2.8194 270)
			(unlocked yes)
			(layer "B.Fab")
			(hide yes)
			(effects
				(font
					(size 1.016 1.016)
					(thickness 0.1524)
				)
				(justify mirror)
			)
		)
		(property "Device Type" "C603H36"
			(at 0 -4.3434 270)
			(unlocked yes)
			(layer "B.Fab")
			(hide yes)
			(effects
				(font
					(size 1.016 1.016)
					(thickness 0.1524)
				)
				(justify mirror)
			)
		)
		(duplicate_pad_numbers_are_jumpers no)
		(fp_line
			(start -0.508 0)
			(end 0.508 0)
			(stroke
				(width 0.2032)
				(type default)
			)
			(layer "B.SilkS")
		)
		(fp_rect
			(start 0.5842 1.3335)
			(end -0.5842 -1.3335)
			(stroke
				(width 0)
				(type default)
			)
			(fill no)
			(layer "B.CrtYd")
		)
		(fp_rect
			(start 0.5842 1.3335)
			(end -0.5842 -1.3335)
			(stroke
				(width 0)
				(type default)
			)
			(fill no)
			(layer "B.Fab")
		)
		(pad "1" smd custom
			(at 0 -0.762 90)
			(size 0.2159 0.2159)
			(layers "B.Cu" "B.Mask" "B.Paste")
			(net "P1V2_STBY")
			(options
				(clearance outline)
				(anchor circle)
			)
			(primitives
				(gr_poly
					(pts
						(arc
							(start -0.3302 0.4318)
							(mid -0.402042 0.402042)
							(end -0.4318 0.3302)
						)
						(arc
							(start -0.4318 -0.3302)
							(mid -0.402042 -0.402042)
							(end -0.3302 -0.4318)
						)
						(arc
							(start 0.3302 -0.4318)
							(mid 0.402042 -0.402042)
							(end 0.4318 -0.3302)
						)
						(arc
							(start 0.4318 0.3302)
							(mid 0.402042 0.402042)
							(end 0.3302 0.4318)
						)
					)
					(width 0)
					(fill yes)
				)
			)
		)
		(pad "2" smd custom
			(at 0 0.762 90)
			(size 0.2159 0.2159)
			(layers "B.Cu" "B.Mask" "B.Paste")
			(net "GND")
			(options
				(clearance outline)
				(anchor circle)
			)
			(primitives
				(gr_poly
					(pts
						(arc
							(start -0.3302 0.4318)
							(mid -0.402042 0.402042)
							(end -0.4318 0.3302)
						)
						(arc
							(start -0.4318 -0.3302)
							(mid -0.402042 -0.402042)
							(end -0.3302 -0.4318)
						)
						(arc
							(start 0.3302 -0.4318)
							(mid 0.402042 -0.402042)
							(end 0.4318 -0.3302)
						)
						(arc
							(start 0.4318 0.3302)
							(mid 0.402042 0.402042)
							(end 0.3302 0.4318)
						)
					)
					(width 0)
					(fill yes)
				)
			)
		)
	)
	(footprint ""
		(layer "B.Cu")
		(at 61.468 -150.495 180)
		(property "Reference" "R398"
			(at 0 0 0)
			(layer "B.SilkS")
			(hide yes)
			(effects
				(font
					(size 1.27 1.27)
				)
				(justify mirror)
			)
		)
		(property "Value" "4K7R2F-GP"
			(at -0.064008 -3.993896 180)
			(unlocked yes)
			(layer "B.Fab")
			(hide yes)
			(effects
				(font
					(size 1.016 1.016)
					(thickness 0.1524)
				)
				(justify mirror)
			)
		)
		(property "Device Type" "R402H16"
			(at -0.064008 -5.517896 180)
			(unlocked yes)
			(layer "B.Fab")
			(hide yes)
			(effects
				(font
					(size 1.016 1.016)
					(thickness 0.1524)
				)
				(justify mirror)
			)
		)
		(duplicate_pad_numbers_are_jumpers no)
		(fp_line
			(start 0.508 -0.9398)
			(end 0.508 0.9398)
			(stroke
				(width 0.1524)
				(type default)
			)
			(layer "B.SilkS")
		)
		(fp_line
			(start -0.508 -0.9398)
			(end 0.508 -0.9398)
			(stroke
				(width 0.1524)
				(type default)
			)
			(layer "B.SilkS")
		)
		(fp_rect
			(start 0.508 0.9398)
			(end -0.508 -0.9398)
			(stroke
				(width 0)
				(type default)
			)
			(fill no)
			(layer "B.CrtYd")
		)
		(fp_rect
			(start 0.508 0.9398)
			(end -0.508 -0.9398)
			(stroke
				(width 0)
				(type default)
			)
			(fill no)
			(layer "B.Fab")
		)
		(pad "1" smd custom
			(at 0 -0.4445)
			(size 0.1397 0.1397)
			(layers "B.Cu" "B.Mask" "B.Paste")
			(net "GND")
			(options
				(clearance outline)
				(anchor circle)
			)
			(primitives
				(gr_poly
					(pts
						(arc
							(start -0.1778 0.2794)
							(mid -0.249642 0.249642)
							(end -0.2794 0.1778)
						)
						(arc
							(start -0.2794 -0.1778)
							(mid -0.249642 -0.249642)
							(end -0.1778 -0.2794)
						)
						(arc
							(start 0.1778 -0.2794)
							(mid 0.249642 -0.249642)
							(end 0.2794 -0.1778)
						)
						(arc
							(start 0.2794 0.1778)
							(mid 0.249642 0.249642)
							(end 0.1778 0.2794)
						)
					)
					(width 0)
					(fill yes)
				)
			)
		)
		(pad "2" smd custom
			(at 0 0.4445)
			(size 0.1397 0.1397)
			(layers "B.Cu" "B.Mask" "B.Paste")
			(net "MAC2_TXD2")
			(options
				(clearance outline)
				(anchor circle)
			)
			(primitives
				(gr_poly
					(pts
						(arc
							(start -0.1778 0.2794)
							(mid -0.249642 0.249642)
							(end -0.2794 0.1778)
						)
						(arc
							(start -0.2794 -0.1778)
							(mid -0.249642 -0.249642)
							(end -0.1778 -0.2794)
						)
						(arc
							(start 0.1778 -0.2794)
							(mid 0.249642 -0.249642)
							(end 0.2794 -0.1778)
						)
						(arc
							(start 0.2794 0.1778)
							(mid 0.249642 0.249642)
							(end 0.1778 0.2794)
						)
					)
					(width 0)
					(fill yes)
				)
			)
		)
	)
	(footprint ""
		(layer "B.Cu")
		(at 51.40452 -144.26438)
		(property "Reference" "TP78"
			(at 0 0 0)
			(layer "B.SilkS")
			(hide yes)
			(effects
				(font
					(size 1.27 1.27)
				)
				(justify mirror)
			)
		)
		(property "Value" "TPAD28-2-GP"
			(at 0.0127 -1.6637 0)
			(unlocked yes)
			(layer "B.Fab")
			(hide yes)
			(effects
				(font
					(size 1.016 1.016)
					(thickness 0.1524)
				)
				(justify mirror)
			)
		)
		(property "Device Type" "TPAD28"
			(at 0.0127 -3.1877 0)
			(unlocked yes)
			(layer "B.Fab")
			(hide yes)
			(effects
				(font
					(size 1.016 1.016)
					(thickness 0.1524)
				)
				(justify mirror)
			)
		)
		(duplicate_pad_numbers_are_jumpers no)
		(fp_poly
			(pts
				(arc
					(start 0.3556 0)
					(mid -0.3556 0)
					(end 0.3556 0)
				)
			)
			(stroke
				(width 0)
				(type default)
			)
			(fill no)
			(layer "B.CrtYd")
		)
		(fp_poly
			(pts
				(arc
					(start 0.6096 0)
					(mid -0.6096 0)
					(end 0.6096 0)
				)
			)
			(stroke
				(width 0)
				(type default)
			)
			(fill no)
			(layer "B.Fab")
		)
		(pad "1" smd circle
			(at 0 0 180)
			(size 0.7112 0.7112)
			(layers "B.Cu" "B.Mask" "B.Paste")
			(net "JTAG_BMC_TRST_N")
		)
	)
	(footprint ""
		(layer "B.Cu")
		(at 193.501518 -81.153 180)
		(property "Reference" "C297"
			(at 0 0 0)
			(layer "B.SilkS")
			(hide yes)
			(effects
				(font
					(size 1.27 1.27)
				)
				(justify mirror)
			)
		)
		(property "Value" "SCD22U10V1KX-GP"
			(at 2.8321 -1.7399 180)
			(unlocked yes)
			(layer "B.Fab")
			(hide yes)
			(effects
				(font
					(size 1.016 1.016)
					(thickness 0.1524)
				)
				(justify mirror)
			)
		)
		(property "Device Type" "C0201H13"
			(at 2.8321 -3.2639 180)
			(unlocked yes)
			(layer "B.Fab")
			(hide yes)
			(effects
				(font
					(size 1.016 1.016)
					(thickness 0.1524)
				)
				(justify mirror)
			)
		)
		(duplicate_pad_numbers_are_jumpers no)
		(fp_rect
			(start 0.2794 0.6477)
			(end -0.2794 -0.6477)
			(stroke
				(width 0)
				(type default)
			)
			(fill no)
			(layer "B.CrtYd")
		)
		(fp_rect
			(start 0.2794 0.6477)
			(end -0.2794 -0.6477)
			(stroke
				(width 0)
				(type default)
			)
			(fill no)
			(layer "B.Fab")
		)
		(pad "1" smd custom
			(at 0 -0.2794)
			(size 0.0762 0.0762)
			(layers "B.Cu" "B.Mask" "B.Paste")
			(net "PCIE_IOM_TO_COMP_12_DP_C")
			(options
				(clearance outline)
				(anchor circle)
			)
			(primitives
				(gr_poly
					(pts
						(arc
							(start 0.1524 0.127)
							(mid 0.137521 0.162921)
							(end 0.1016 0.1778)
						)
						(arc
							(start -0.1016 0.1778)
							(mid -0.137521 0.162921)
							(end -0.1524 0.127)
						)
						(arc
							(start -0.1524 -0.127)
							(mid -0.137521 -0.162921)
							(end -0.1016 -0.1778)
						)
						(arc
							(start 0.1016 -0.1778)
							(mid 0.137521 -0.162921)
							(end 0.1524 -0.127)
						)
					)
					(width 0)
					(fill yes)
				)
			)
		)
		(pad "2" smd custom
			(at 0 0.2794)
			(size 0.0762 0.0762)
			(layers "B.Cu" "B.Mask" "B.Paste")
			(net "PCIE_IOM_TO_COMP_12_DP")
			(options
				(clearance outline)
				(anchor circle)
			)
			(primitives
				(gr_poly
					(pts
						(arc
							(start 0.1524 0.127)
							(mid 0.137521 0.162921)
							(end 0.1016 0.1778)
						)
						(arc
							(start -0.1016 0.1778)
							(mid -0.137521 0.162921)
							(end -0.1524 0.127)
						)
						(arc
							(start -0.1524 -0.127)
							(mid -0.137521 -0.162921)
							(end -0.1016 -0.1778)
						)
						(arc
							(start 0.1016 -0.1778)
							(mid 0.137521 -0.162921)
							(end 0.1524 -0.127)
						)
					)
					(width 0)
					(fill yes)
				)
			)
		)
	)
	(footprint ""
		(layer "B.Cu")
		(at 52.78628 -144.99844)
		(property "Reference" "TP52"
			(at 0 0 0)
			(layer "B.SilkS")
			(hide yes)
			(effects
				(font
					(size 1.27 1.27)
				)
				(justify mirror)
			)
		)
		(property "Value" "TPAD28-2-GP"
			(at 0.0127 -1.6637 0)
			(unlocked yes)
			(layer "B.Fab")
			(hide yes)
			(effects
				(font
					(size 1.016 1.016)
					(thickness 0.1524)
				)
				(justify mirror)
			)
		)
		(property "Device Type" "TPAD28"
			(at 0.0127 -3.1877 0)
			(unlocked yes)
			(layer "B.Fab")
			(hide yes)
			(effects
				(font
					(size 1.016 1.016)
					(thickness 0.1524)
				)
				(justify mirror)
			)
		)
		(duplicate_pad_numbers_are_jumpers no)
		(fp_poly
			(pts
				(arc
					(start 0.3556 0)
					(mid -0.3556 0)
					(end 0.3556 0)
				)
			)
			(stroke
				(width 0)
				(type default)
			)
			(fill no)
			(layer "B.CrtYd")
		)
		(fp_poly
			(pts
				(arc
					(start 0.6096 0)
					(mid -0.6096 0)
					(end 0.6096 0)
				)
			)
			(stroke
				(width 0)
				(type default)
			)
			(fill no)
			(layer "B.Fab")
		)
		(pad "1" smd circle
			(at 0 0 180)
			(size 0.7112 0.7112)
			(layers "B.Cu" "B.Mask" "B.Paste")
			(net "RMII_BMC_MDIO_R")
		)
	)
	(footprint ""
		(layer "B.Cu")
		(at 199.997822 -72.5932 90)
		(property "Reference" "C361"
			(at 0 0 90)
			(layer "B.SilkS")
			(hide yes)
			(effects
				(font
					(size 1.27 1.27)
				)
				(justify mirror)
			)
		)
		(property "Value" "SCD1U6D3V1KX-GP"
			(at 2.8321 -1.7399 90)
			(unlocked yes)
			(layer "B.Fab")
			(hide yes)
			(effects
				(font
					(size 1.016 1.016)
					(thickness 0.1524)
				)
				(justify mirror)
			)
		)
		(property "Device Type" "C0201H13"
			(at 2.8321 -3.2639 90)
			(unlocked yes)
			(layer "B.Fab")
			(hide yes)
			(effects
				(font
					(size 1.016 1.016)
					(thickness 0.1524)
				)
				(justify mirror)
			)
		)
		(duplicate_pad_numbers_are_jumpers no)
		(fp_rect
			(start 0.2794 0.6477)
			(end -0.2794 -0.6477)
			(stroke
				(width 0)
				(type default)
			)
			(fill no)
			(layer "B.CrtYd")
		)
		(fp_rect
			(start 0.2794 0.6477)
			(end -0.2794 -0.6477)
			(stroke
				(width 0)
				(type default)
			)
			(fill no)
			(layer "B.Fab")
		)
		(pad "1" smd custom
			(at 0 -0.2794 270)
			(size 0.0762 0.0762)
			(layers "B.Cu" "B.Mask" "B.Paste")
			(net "PCE_VDDH")
			(options
				(clearance outline)
				(anchor circle)
			)
			(primitives
				(gr_poly
					(pts
						(arc
							(start 0.1524 0.127)
							(mid 0.137521 0.162921)
							(end 0.1016 0.1778)
						)
						(arc
							(start -0.1016 0.1778)
							(mid -0.137521 0.162921)
							(end -0.1524 0.127)
						)
						(arc
							(start -0.1524 -0.127)
							(mid -0.137521 -0.162921)
							(end -0.1016 -0.1778)
						)
						(arc
							(start 0.1016 -0.1778)
							(mid 0.137521 -0.162921)
							(end 0.1524 -0.127)
						)
					)
					(width 0)
					(fill yes)
				)
			)
		)
		(pad "2" smd custom
			(at 0 0.2794 270)
			(size 0.0762 0.0762)
			(layers "B.Cu" "B.Mask" "B.Paste")
			(net "GND")
			(options
				(clearance outline)
				(anchor circle)
			)
			(primitives
				(gr_poly
					(pts
						(arc
							(start 0.1524 0.127)
							(mid 0.137521 0.162921)
							(end 0.1016 0.1778)
						)
						(arc
							(start -0.1016 0.1778)
							(mid -0.137521 0.162921)
							(end -0.1524 0.127)
						)
						(arc
							(start -0.1524 -0.127)
							(mid -0.137521 -0.162921)
							(end -0.1016 -0.1778)
						)
						(arc
							(start 0.1016 -0.1778)
							(mid 0.137521 -0.162921)
							(end 0.1524 -0.127)
						)
					)
					(width 0)
					(fill yes)
				)
			)
		)
	)
	(footprint ""
		(layer "B.Cu")
		(at 201.236326 -54.938676)
		(property "Reference" "C458"
			(at 0 0 0)
			(layer "B.SilkS")
			(hide yes)
			(effects
				(font
					(size 1.27 1.27)
				)
				(justify mirror)
			)
		)
		(property "Value" "SCD1U16V2KX-3GP"
			(at -1.1811 -2.7051 0)
			(unlocked yes)
			(layer "B.Fab")
			(hide yes)
			(effects
				(font
					(size 1.016 1.016)
					(thickness 0.1524)
				)
				(justify mirror)
			)
		)
		(property "Device Type" "C402H22"
			(at -1.1811 -4.2291 0)
			(unlocked yes)
			(layer "B.Fab")
			(hide yes)
			(effects
				(font
					(size 1.016 1.016)
					(thickness 0.1524)
				)
				(justify mirror)
			)
		)
		(duplicate_pad_numbers_are_jumpers no)
		(fp_rect
			(start 0.4318 0.9525)
			(end -0.4318 -0.9525)
			(stroke
				(width 0)
				(type default)
			)
			(fill no)
			(layer "B.CrtYd")
		)
		(fp_rect
			(start 0.4318 0.9525)
			(end -0.4318 -0.9525)
			(stroke
				(width 0)
				(type default)
			)
			(fill no)
			(layer "B.Fab")
		)
		(pad "1" smd custom
			(at 0 -0.4445 180)
			(size 0.1524 0.1524)
			(layers "B.Cu" "B.Mask" "B.Paste")
			(net "P1V8")
			(options
				(clearance outline)
				(anchor circle)
			)
			(primitives
				(gr_poly
					(pts
						(arc
							(start 0.3048 0.2032)
							(mid 0.275042 0.275042)
							(end 0.2032 0.3048)
						)
						(arc
							(start -0.2032 0.3048)
							(mid -0.275042 0.275042)
							(end -0.3048 0.2032)
						)
						(arc
							(start -0.3048 -0.2032)
							(mid -0.275042 -0.275042)
							(end -0.2032 -0.3048)
						)
						(arc
							(start 0.2032 -0.3048)
							(mid 0.275042 -0.275042)
							(end 0.3048 -0.2032)
						)
					)
					(width 0)
					(fill yes)
				)
			)
		)
		(pad "2" smd custom
			(at 0 0.4445 180)
			(size 0.1524 0.1524)
			(layers "B.Cu" "B.Mask" "B.Paste")
			(net "GND")
			(options
				(clearance outline)
				(anchor circle)
			)
			(primitives
				(gr_poly
					(pts
						(arc
							(start 0.3048 0.2032)
							(mid 0.275042 0.275042)
							(end 0.2032 0.3048)
						)
						(arc
							(start -0.2032 0.3048)
							(mid -0.275042 0.275042)
							(end -0.3048 0.2032)
						)
						(arc
							(start -0.3048 -0.2032)
							(mid -0.275042 -0.275042)
							(end -0.2032 -0.3048)
						)
						(arc
							(start 0.2032 -0.3048)
							(mid 0.275042 -0.275042)
							(end 0.3048 -0.2032)
						)
					)
					(width 0)
					(fill yes)
				)
			)
		)
	)
	(footprint ""
		(layer "B.Cu")
		(at 189.2681 -62.1919 90)
		(property "Reference" "C404"
			(at 0 0 90)
			(layer "B.SilkS")
			(hide yes)
			(effects
				(font
					(size 1.27 1.27)
				)
				(justify mirror)
			)
		)
		(property "Value" "SCD1U6D3V1KX-GP"
			(at 2.8321 -1.7399 90)
			(unlocked yes)
			(layer "B.Fab")
			(hide yes)
			(effects
				(font
					(size 1.016 1.016)
					(thickness 0.1524)
				)
				(justify mirror)
			)
		)
		(property "Device Type" "C0201H13"
			(at 2.8321 -3.2639 90)
			(unlocked yes)
			(layer "B.Fab")
			(hide yes)
			(effects
				(font
					(size 1.016 1.016)
					(thickness 0.1524)
				)
				(justify mirror)
			)
		)
		(duplicate_pad_numbers_are_jumpers no)
		(fp_rect
			(start 0.2794 0.6477)
			(end -0.2794 -0.6477)
			(stroke
				(width 0)
				(type default)
			)
			(fill no)
			(layer "B.CrtYd")
		)
		(fp_rect
			(start 0.2794 0.6477)
			(end -0.2794 -0.6477)
			(stroke
				(width 0)
				(type default)
			)
			(fill no)
			(layer "B.Fab")
		)
		(pad "1" smd custom
			(at 0 -0.2794 270)
			(size 0.0762 0.0762)
			(layers "B.Cu" "B.Mask" "B.Paste")
			(net "P0V975")
			(options
				(clearance outline)
				(anchor circle)
			)
			(primitives
				(gr_poly
					(pts
						(arc
							(start 0.1524 0.127)
							(mid 0.137521 0.162921)
							(end 0.1016 0.1778)
						)
						(arc
							(start -0.1016 0.1778)
							(mid -0.137521 0.162921)
							(end -0.1524 0.127)
						)
						(arc
							(start -0.1524 -0.127)
							(mid -0.137521 -0.162921)
							(end -0.1016 -0.1778)
						)
						(arc
							(start 0.1016 -0.1778)
							(mid 0.137521 -0.162921)
							(end 0.1524 -0.127)
						)
					)
					(width 0)
					(fill yes)
				)
			)
		)
		(pad "2" smd custom
			(at 0 0.2794 270)
			(size 0.0762 0.0762)
			(layers "B.Cu" "B.Mask" "B.Paste")
			(net "GND")
			(options
				(clearance outline)
				(anchor circle)
			)
			(primitives
				(gr_poly
					(pts
						(arc
							(start 0.1524 0.127)
							(mid 0.137521 0.162921)
							(end 0.1016 0.1778)
						)
						(arc
							(start -0.1016 0.1778)
							(mid -0.137521 0.162921)
							(end -0.1524 0.127)
						)
						(arc
							(start -0.1524 -0.127)
							(mid -0.137521 -0.162921)
							(end -0.1016 -0.1778)
						)
						(arc
							(start 0.1016 -0.1778)
							(mid 0.137521 -0.162921)
							(end 0.1524 -0.127)
						)
					)
					(width 0)
					(fill yes)
				)
			)
		)
	)
	(footprint ""
		(layer "B.Cu")
		(at 43.4848 -133.1214 180)
		(property "Reference" "R374"
			(at 0 0 0)
			(layer "B.SilkS")
			(hide yes)
			(effects
				(font
					(size 1.27 1.27)
				)
				(justify mirror)
			)
		)
		(property "Value" "4K7R2F-GP"
			(at -0.064008 -3.993896 180)
			(unlocked yes)
			(layer "B.Fab")
			(hide yes)
			(effects
				(font
					(size 1.016 1.016)
					(thickness 0.1524)
				)
				(justify mirror)
			)
		)
		(property "Device Type" "R402H16"
			(at -0.064008 -5.517896 180)
			(unlocked yes)
			(layer "B.Fab")
			(hide yes)
			(effects
				(font
					(size 1.016 1.016)
					(thickness 0.1524)
				)
				(justify mirror)
			)
		)
		(duplicate_pad_numbers_are_jumpers no)
		(fp_line
			(start 0.508 -0.9398)
			(end 0.508 0.9398)
			(stroke
				(width 0.1524)
				(type default)
			)
			(layer "B.SilkS")
		)
		(fp_line
			(start -0.508 -0.9398)
			(end 0.508 -0.9398)
			(stroke
				(width 0.1524)
				(type default)
			)
			(layer "B.SilkS")
		)
		(fp_rect
			(start 0.508 0.9398)
			(end -0.508 -0.9398)
			(stroke
				(width 0)
				(type default)
			)
			(fill no)
			(layer "B.CrtYd")
		)
		(fp_rect
			(start 0.508 0.9398)
			(end -0.508 -0.9398)
			(stroke
				(width 0)
				(type default)
			)
			(fill no)
			(layer "B.Fab")
		)
		(pad "1" smd custom
			(at 0 -0.4445)
			(size 0.1397 0.1397)
			(layers "B.Cu" "B.Mask" "B.Paste")
			(net "P3V3_STBY")
			(options
				(clearance outline)
				(anchor circle)
			)
			(primitives
				(gr_poly
					(pts
						(arc
							(start -0.1778 0.2794)
							(mid -0.249642 0.249642)
							(end -0.2794 0.1778)
						)
						(arc
							(start -0.2794 -0.1778)
							(mid -0.249642 -0.249642)
							(end -0.1778 -0.2794)
						)
						(arc
							(start 0.1778 -0.2794)
							(mid 0.249642 -0.249642)
							(end 0.2794 -0.1778)
						)
						(arc
							(start 0.2794 0.1778)
							(mid 0.249642 0.249642)
							(end 0.1778 0.2794)
						)
					)
					(width 0)
					(fill yes)
				)
			)
		)
		(pad "2" smd custom
			(at 0 0.4445)
			(size 0.1397 0.1397)
			(layers "B.Cu" "B.Mask" "B.Paste")
			(net "BMC_GPIOS6")
			(options
				(clearance outline)
				(anchor circle)
			)
			(primitives
				(gr_poly
					(pts
						(arc
							(start -0.1778 0.2794)
							(mid -0.249642 0.249642)
							(end -0.2794 0.1778)
						)
						(arc
							(start -0.2794 -0.1778)
							(mid -0.249642 -0.249642)
							(end -0.1778 -0.2794)
						)
						(arc
							(start 0.1778 -0.2794)
							(mid 0.249642 -0.249642)
							(end 0.2794 -0.1778)
						)
						(arc
							(start 0.2794 0.1778)
							(mid 0.249642 0.249642)
							(end 0.1778 0.2794)
						)
					)
					(width 0)
					(fill yes)
				)
			)
		)
	)
	(footprint ""
		(layer "B.Cu")
		(at 167.966136 -38.442138)
		(property "Reference" "C495"
			(at 0 0 0)
			(layer "B.SilkS")
			(hide yes)
			(effects
				(font
					(size 1.27 1.27)
				)
				(justify mirror)
			)
		)
		(property "Value" "SCD01U16V1KX-GP"
			(at 2.8321 -1.7399 0)
			(unlocked yes)
			(layer "B.Fab")
			(hide yes)
			(effects
				(font
					(size 1.016 1.016)
					(thickness 0.1524)
				)
				(justify mirror)
			)
		)
		(property "Device Type" "C0201H13"
			(at 2.8321 -3.2639 0)
			(unlocked yes)
			(layer "B.Fab")
			(hide yes)
			(effects
				(font
					(size 1.016 1.016)
					(thickness 0.1524)
				)
				(justify mirror)
			)
		)
		(duplicate_pad_numbers_are_jumpers no)
		(fp_rect
			(start 0.2794 0.6477)
			(end -0.2794 -0.6477)
			(stroke
				(width 0)
				(type default)
			)
			(fill no)
			(layer "B.CrtYd")
		)
		(fp_rect
			(start 0.2794 0.6477)
			(end -0.2794 -0.6477)
			(stroke
				(width 0)
				(type default)
			)
			(fill no)
			(layer "B.Fab")
		)
		(pad "1" smd custom
			(at 0 -0.2794 180)
			(size 0.0762 0.0762)
			(layers "B.Cu" "B.Mask" "B.Paste")
			(net "PHY_CON_B_TO_IOC_1_DP")
			(options
				(clearance outline)
				(anchor circle)
			)
			(primitives
				(gr_poly
					(pts
						(arc
							(start 0.1524 0.127)
							(mid 0.137521 0.162921)
							(end 0.1016 0.1778)
						)
						(arc
							(start -0.1016 0.1778)
							(mid -0.137521 0.162921)
							(end -0.1524 0.127)
						)
						(arc
							(start -0.1524 -0.127)
							(mid -0.137521 -0.162921)
							(end -0.1016 -0.1778)
						)
						(arc
							(start 0.1016 -0.1778)
							(mid 0.137521 -0.162921)
							(end 0.1524 -0.127)
						)
					)
					(width 0)
					(fill yes)
				)
			)
		)
		(pad "2" smd custom
			(at 0 0.2794 180)
			(size 0.0762 0.0762)
			(layers "B.Cu" "B.Mask" "B.Paste")
			(net "PHY_CON_B_TO_IOC_1_DP_C")
			(options
				(clearance outline)
				(anchor circle)
			)
			(primitives
				(gr_poly
					(pts
						(arc
							(start 0.1524 0.127)
							(mid 0.137521 0.162921)
							(end 0.1016 0.1778)
						)
						(arc
							(start -0.1016 0.1778)
							(mid -0.137521 0.162921)
							(end -0.1524 0.127)
						)
						(arc
							(start -0.1524 -0.127)
							(mid -0.137521 -0.162921)
							(end -0.1016 -0.1778)
						)
						(arc
							(start 0.1016 -0.1778)
							(mid 0.137521 -0.162921)
							(end 0.1524 -0.127)
						)
					)
					(width 0)
					(fill yes)
				)
			)
		)
	)
	(footprint ""
		(layer "B.Cu")
		(at 47.72152 -156.34716 90)
		(property "Reference" "C90"
			(at 0 0 90)
			(layer "B.SilkS")
			(hide yes)
			(effects
				(font
					(size 1.27 1.27)
				)
				(justify mirror)
			)
		)
		(property "Value" "SC1U16V3KX-5GP"
			(at 0 -2.8194 90)
			(unlocked yes)
			(layer "B.Fab")
			(hide yes)
			(effects
				(font
					(size 1.016 1.016)
					(thickness 0.1524)
				)
				(justify mirror)
			)
		)
		(property "Device Type" "C603H36"
			(at 0 -4.3434 90)
			(unlocked yes)
			(layer "B.Fab")
			(hide yes)
			(effects
				(font
					(size 1.016 1.016)
					(thickness 0.1524)
				)
				(justify mirror)
			)
		)
		(duplicate_pad_numbers_are_jumpers no)
		(fp_line
			(start -0.508 0)
			(end 0.508 0)
			(stroke
				(width 0.2032)
				(type default)
			)
			(layer "B.SilkS")
		)
		(fp_rect
			(start 0.5842 1.3335)
			(end -0.5842 -1.3335)
			(stroke
				(width 0)
				(type default)
			)
			(fill no)
			(layer "B.CrtYd")
		)
		(fp_rect
			(start 0.5842 1.3335)
			(end -0.5842 -1.3335)
			(stroke
				(width 0)
				(type default)
			)
			(fill no)
			(layer "B.Fab")
		)
		(pad "1" smd custom
			(at 0 -0.762 270)
			(size 0.2159 0.2159)
			(layers "B.Cu" "B.Mask" "B.Paste")
			(net "DACAV33")
			(options
				(clearance outline)
				(anchor circle)
			)
			(primitives
				(gr_poly
					(pts
						(arc
							(start -0.3302 0.4318)
							(mid -0.402042 0.402042)
							(end -0.4318 0.3302)
						)
						(arc
							(start -0.4318 -0.3302)
							(mid -0.402042 -0.402042)
							(end -0.3302 -0.4318)
						)
						(arc
							(start 0.3302 -0.4318)
							(mid 0.402042 -0.402042)
							(end 0.4318 -0.3302)
						)
						(arc
							(start 0.4318 0.3302)
							(mid 0.402042 0.402042)
							(end 0.3302 0.4318)
						)
					)
					(width 0)
					(fill yes)
				)
			)
		)
		(pad "2" smd custom
			(at 0 0.762 270)
			(size 0.2159 0.2159)
			(layers "B.Cu" "B.Mask" "B.Paste")
			(net "GND")
			(options
				(clearance outline)
				(anchor circle)
			)
			(primitives
				(gr_poly
					(pts
						(arc
							(start -0.3302 0.4318)
							(mid -0.402042 0.402042)
							(end -0.4318 0.3302)
						)
						(arc
							(start -0.4318 -0.3302)
							(mid -0.402042 -0.402042)
							(end -0.3302 -0.4318)
						)
						(arc
							(start 0.3302 -0.4318)
							(mid 0.402042 -0.402042)
							(end 0.4318 -0.3302)
						)
						(arc
							(start 0.4318 0.3302)
							(mid 0.402042 0.402042)
							(end 0.3302 0.4318)
						)
					)
					(width 0)
					(fill yes)
				)
			)
		)
	)
	(footprint ""
		(layer "B.Cu")
		(at 47.73422 -140.208 -90)
		(property "Reference" "C998"
			(at 0 0 90)
			(layer "B.SilkS")
			(hide yes)
			(effects
				(font
					(size 1.27 1.27)
				)
				(justify mirror)
			)
		)
		(property "Value" "SC1U16V3KX-5GP"
			(at 0 -2.8194 270)
			(unlocked yes)
			(layer "B.Fab")
			(hide yes)
			(effects
				(font
					(size 1.016 1.016)
					(thickness 0.1524)
				)
				(justify mirror)
			)
		)
		(property "Device Type" "C603H36"
			(at 0 -4.3434 270)
			(unlocked yes)
			(layer "B.Fab")
			(hide yes)
			(effects
				(font
					(size 1.016 1.016)
					(thickness 0.1524)
				)
				(justify mirror)
			)
		)
		(duplicate_pad_numbers_are_jumpers no)
		(fp_line
			(start -0.508 0)
			(end 0.508 0)
			(stroke
				(width 0.2032)
				(type default)
			)
			(layer "B.SilkS")
		)
		(fp_rect
			(start 0.5842 1.3335)
			(end -0.5842 -1.3335)
			(stroke
				(width 0)
				(type default)
			)
			(fill no)
			(layer "B.CrtYd")
		)
		(fp_rect
			(start 0.5842 1.3335)
			(end -0.5842 -1.3335)
			(stroke
				(width 0)
				(type default)
			)
			(fill no)
			(layer "B.Fab")
		)
		(pad "1" smd custom
			(at 0 -0.762 90)
			(size 0.2159 0.2159)
			(layers "B.Cu" "B.Mask" "B.Paste")
			(net "P1V8_STBY")
			(options
				(clearance outline)
				(anchor circle)
			)
			(primitives
				(gr_poly
					(pts
						(arc
							(start -0.3302 0.4318)
							(mid -0.402042 0.402042)
							(end -0.4318 0.3302)
						)
						(arc
							(start -0.4318 -0.3302)
							(mid -0.402042 -0.402042)
							(end -0.3302 -0.4318)
						)
						(arc
							(start 0.3302 -0.4318)
							(mid 0.402042 -0.402042)
							(end 0.4318 -0.3302)
						)
						(arc
							(start 0.4318 0.3302)
							(mid 0.402042 0.402042)
							(end 0.3302 0.4318)
						)
					)
					(width 0)
					(fill yes)
				)
			)
		)
		(pad "2" smd custom
			(at 0 0.762 90)
			(size 0.2159 0.2159)
			(layers "B.Cu" "B.Mask" "B.Paste")
			(net "GND")
			(options
				(clearance outline)
				(anchor circle)
			)
			(primitives
				(gr_poly
					(pts
						(arc
							(start -0.3302 0.4318)
							(mid -0.402042 0.402042)
							(end -0.4318 0.3302)
						)
						(arc
							(start -0.4318 -0.3302)
							(mid -0.402042 -0.402042)
							(end -0.3302 -0.4318)
						)
						(arc
							(start 0.3302 -0.4318)
							(mid 0.402042 -0.402042)
							(end 0.4318 -0.3302)
						)
						(arc
							(start 0.4318 0.3302)
							(mid 0.402042 0.402042)
							(end 0.3302 0.4318)
						)
					)
					(width 0)
					(fill yes)
				)
			)
		)
	)
	(footprint ""
		(layer "B.Cu")
		(at 91.421966 -159.160718 90)
		(property "Reference" "TP4"
			(at 0 0 90)
			(layer "B.SilkS")
			(hide yes)
			(effects
				(font
					(size 1.27 1.27)
				)
				(justify mirror)
			)
		)
		(property "Value" "TPAD28-2-GP"
			(at 0.0127 -1.6637 90)
			(unlocked yes)
			(layer "B.Fab")
			(hide yes)
			(effects
				(font
					(size 1.016 1.016)
					(thickness 0.1524)
				)
				(justify mirror)
			)
		)
		(property "Device Type" "TPAD28"
			(at 0.0127 -3.1877 90)
			(unlocked yes)
			(layer "B.Fab")
			(hide yes)
			(effects
				(font
					(size 1.016 1.016)
					(thickness 0.1524)
				)
				(justify mirror)
			)
		)
		(duplicate_pad_numbers_are_jumpers no)
		(fp_poly
			(pts
				(arc
					(start 0 0.3556)
					(mid 0 -0.3556)
					(end 0 0.3556)
				)
			)
			(stroke
				(width 0)
				(type default)
			)
			(fill no)
			(layer "B.CrtYd")
		)
		(fp_poly
			(pts
				(arc
					(start 0 0.6096)
					(mid 0 -0.6096)
					(end 0 0.6096)
				)
			)
			(stroke
				(width 0)
				(type default)
			)
			(fill no)
			(layer "B.Fab")
		)
		(pad "1" smd circle
			(at 0 0 270)
			(size 0.7112 0.7112)
			(layers "B.Cu" "B.Mask" "B.Paste")
			(net "PLLFILT")
		)
	)
	(footprint ""
		(layer "B.Cu")
		(at 57.431686 -141.745462 -90)
		(property "Reference" "R175"
			(at 0 0 90)
			(layer "B.SilkS")
			(hide yes)
			(effects
				(font
					(size 1.27 1.27)
				)
				(justify mirror)
			)
		)
		(property "Value" "0R2J-2-GP"
			(at -0.064008 -3.993896 270)
			(unlocked yes)
			(layer "B.Fab")
			(hide yes)
			(effects
				(font
					(size 1.016 1.016)
					(thickness 0.1524)
				)
				(justify mirror)
			)
		)
		(property "Device Type" "R402H16"
			(at -0.064008 -5.517896 270)
			(unlocked yes)
			(layer "B.Fab")
			(hide yes)
			(effects
				(font
					(size 1.016 1.016)
					(thickness 0.1524)
				)
				(justify mirror)
			)
		)
		(duplicate_pad_numbers_are_jumpers no)
		(fp_line
			(start -0.508 -0.9398)
			(end 0.508 -0.9398)
			(stroke
				(width 0.1524)
				(type default)
			)
			(layer "B.SilkS")
		)
		(fp_line
			(start 0.508 -0.9398)
			(end 0.508 0.9398)
			(stroke
				(width 0.1524)
				(type default)
			)
			(layer "B.SilkS")
		)
		(fp_rect
			(start 0.508 0.9398)
			(end -0.508 -0.9398)
			(stroke
				(width 0)
				(type default)
			)
			(fill no)
			(layer "B.CrtYd")
		)
		(fp_rect
			(start 0.508 0.9398)
			(end -0.508 -0.9398)
			(stroke
				(width 0)
				(type default)
			)
			(fill no)
			(layer "B.Fab")
		)
		(pad "1" smd custom
			(at 0 -0.4445 90)
			(size 0.1397 0.1397)
			(layers "B.Cu" "B.Mask" "B.Paste")
			(net "I2C_M2_2_SCL")
			(options
				(clearance outline)
				(anchor circle)
			)
			(primitives
				(gr_poly
					(pts
						(arc
							(start -0.1778 0.2794)
							(mid -0.249642 0.249642)
							(end -0.2794 0.1778)
						)
						(arc
							(start -0.2794 -0.1778)
							(mid -0.249642 -0.249642)
							(end -0.1778 -0.2794)
						)
						(arc
							(start 0.1778 -0.2794)
							(mid 0.249642 -0.249642)
							(end 0.2794 -0.1778)
						)
						(arc
							(start 0.2794 0.1778)
							(mid 0.249642 0.249642)
							(end 0.1778 0.2794)
						)
					)
					(width 0)
					(fill yes)
				)
			)
		)
		(pad "2" smd custom
			(at 0 0.4445 90)
			(size 0.1397 0.1397)
			(layers "B.Cu" "B.Mask" "B.Paste")
			(net "BMC_SMB9_CLK")
			(options
				(clearance outline)
				(anchor circle)
			)
			(primitives
				(gr_poly
					(pts
						(arc
							(start -0.1778 0.2794)
							(mid -0.249642 0.249642)
							(end -0.2794 0.1778)
						)
						(arc
							(start -0.2794 -0.1778)
							(mid -0.249642 -0.249642)
							(end -0.1778 -0.2794)
						)
						(arc
							(start 0.1778 -0.2794)
							(mid 0.249642 -0.249642)
							(end 0.2794 -0.1778)
						)
						(arc
							(start 0.2794 0.1778)
							(mid 0.249642 0.249642)
							(end 0.1778 0.2794)
						)
					)
					(width 0)
					(fill yes)
				)
			)
		)
	)
	(footprint ""
		(layer "B.Cu")
		(at 38.419278 -143.058642)
		(property "Reference" "C58"
			(at 0 0 0)
			(layer "B.SilkS")
			(hide yes)
			(effects
				(font
					(size 1.27 1.27)
				)
				(justify mirror)
			)
		)
		(property "Value" "SC1U16V3KX-5GP"
			(at 0 -2.8194 0)
			(unlocked yes)
			(layer "B.Fab")
			(hide yes)
			(effects
				(font
					(size 1.016 1.016)
					(thickness 0.1524)
				)
				(justify mirror)
			)
		)
		(property "Device Type" "C603H36"
			(at 0 -4.3434 0)
			(unlocked yes)
			(layer "B.Fab")
			(hide yes)
			(effects
				(font
					(size 1.016 1.016)
					(thickness 0.1524)
				)
				(justify mirror)
			)
		)
		(duplicate_pad_numbers_are_jumpers no)
		(fp_line
			(start -0.508 0)
			(end 0.508 0)
			(stroke
				(width 0.2032)
				(type default)
			)
			(layer "B.SilkS")
		)
		(fp_rect
			(start 0.5842 1.3335)
			(end -0.5842 -1.3335)
			(stroke
				(width 0)
				(type default)
			)
			(fill no)
			(layer "B.CrtYd")
		)
		(fp_rect
			(start 0.5842 1.3335)
			(end -0.5842 -1.3335)
			(stroke
				(width 0)
				(type default)
			)
			(fill no)
			(layer "B.Fab")
		)
		(pad "1" smd custom
			(at 0 -0.762 180)
			(size 0.2159 0.2159)
			(layers "B.Cu" "B.Mask" "B.Paste")
			(net "P1V2_STBY")
			(options
				(clearance outline)
				(anchor circle)
			)
			(primitives
				(gr_poly
					(pts
						(arc
							(start -0.3302 0.4318)
							(mid -0.402042 0.402042)
							(end -0.4318 0.3302)
						)
						(arc
							(start -0.4318 -0.3302)
							(mid -0.402042 -0.402042)
							(end -0.3302 -0.4318)
						)
						(arc
							(start 0.3302 -0.4318)
							(mid 0.402042 -0.402042)
							(end 0.4318 -0.3302)
						)
						(arc
							(start 0.4318 0.3302)
							(mid 0.402042 0.402042)
							(end 0.3302 0.4318)
						)
					)
					(width 0)
					(fill yes)
				)
			)
		)
		(pad "2" smd custom
			(at 0 0.762 180)
			(size 0.2159 0.2159)
			(layers "B.Cu" "B.Mask" "B.Paste")
			(net "GND")
			(options
				(clearance outline)
				(anchor circle)
			)
			(primitives
				(gr_poly
					(pts
						(arc
							(start -0.3302 0.4318)
							(mid -0.402042 0.402042)
							(end -0.4318 0.3302)
						)
						(arc
							(start -0.4318 -0.3302)
							(mid -0.402042 -0.402042)
							(end -0.3302 -0.4318)
						)
						(arc
							(start 0.3302 -0.4318)
							(mid 0.402042 -0.402042)
							(end 0.4318 -0.3302)
						)
						(arc
							(start 0.4318 0.3302)
							(mid 0.402042 0.402042)
							(end 0.3302 0.4318)
						)
					)
					(width 0)
					(fill yes)
				)
			)
		)
	)
	(footprint ""
		(layer "B.Cu")
		(at 90.54592 -149.51456)
		(property "Reference" "C14"
			(at 0 0 0)
			(layer "B.SilkS")
			(hide yes)
			(effects
				(font
					(size 1.27 1.27)
				)
				(justify mirror)
			)
		)
		(property "Value" "SC1KP50V2KX-1GP"
			(at -1.1811 -2.7051 0)
			(unlocked yes)
			(layer "B.Fab")
			(hide yes)
			(effects
				(font
					(size 1.016 1.016)
					(thickness 0.1524)
				)
				(justify mirror)
			)
		)
		(property "Device Type" "C402H22"
			(at -1.1811 -4.2291 0)
			(unlocked yes)
			(layer "B.Fab")
			(hide yes)
			(effects
				(font
					(size 1.016 1.016)
					(thickness 0.1524)
				)
				(justify mirror)
			)
		)
		(duplicate_pad_numbers_are_jumpers no)
		(fp_rect
			(start 0.4318 0.9525)
			(end -0.4318 -0.9525)
			(stroke
				(width 0)
				(type default)
			)
			(fill no)
			(layer "B.CrtYd")
		)
		(fp_rect
			(start 0.4318 0.9525)
			(end -0.4318 -0.9525)
			(stroke
				(width 0)
				(type default)
			)
			(fill no)
			(layer "B.Fab")
		)
		(pad "1" smd custom
			(at 0 -0.4445 180)
			(size 0.1524 0.1524)
			(layers "B.Cu" "B.Mask" "B.Paste")
			(net "USB_OCS_N1")
			(options
				(clearance outline)
				(anchor circle)
			)
			(primitives
				(gr_poly
					(pts
						(arc
							(start 0.3048 0.2032)
							(mid 0.275042 0.275042)
							(end 0.2032 0.3048)
						)
						(arc
							(start -0.2032 0.3048)
							(mid -0.275042 0.275042)
							(end -0.3048 0.2032)
						)
						(arc
							(start -0.3048 -0.2032)
							(mid -0.275042 -0.275042)
							(end -0.2032 -0.3048)
						)
						(arc
							(start 0.2032 -0.3048)
							(mid 0.275042 -0.275042)
							(end 0.3048 -0.2032)
						)
					)
					(width 0)
					(fill yes)
				)
			)
		)
		(pad "2" smd custom
			(at 0 0.4445 180)
			(size 0.1524 0.1524)
			(layers "B.Cu" "B.Mask" "B.Paste")
			(net "GND")
			(options
				(clearance outline)
				(anchor circle)
			)
			(primitives
				(gr_poly
					(pts
						(arc
							(start 0.3048 0.2032)
							(mid 0.275042 0.275042)
							(end 0.2032 0.3048)
						)
						(arc
							(start -0.2032 0.3048)
							(mid -0.275042 0.275042)
							(end -0.3048 0.2032)
						)
						(arc
							(start -0.3048 -0.2032)
							(mid -0.275042 -0.275042)
							(end -0.2032 -0.3048)
						)
						(arc
							(start 0.2032 -0.3048)
							(mid 0.275042 -0.275042)
							(end 0.3048 -0.2032)
						)
					)
					(width 0)
					(fill yes)
				)
			)
		)
	)
	(footprint ""
		(layer "B.Cu")
		(at 20.582128 -131.007358 180)
		(property "Reference" "R253"
			(at 0 0 0)
			(layer "B.SilkS")
			(hide yes)
			(effects
				(font
					(size 1.27 1.27)
				)
				(justify mirror)
			)
		)
		(property "Value" "120R2F-GP"
			(at -0.064008 -3.993896 180)
			(unlocked yes)
			(layer "B.Fab")
			(hide yes)
			(effects
				(font
					(size 1.016 1.016)
					(thickness 0.1524)
				)
				(justify mirror)
			)
		)
		(property "Device Type" "R402H16"
			(at -0.064008 -5.517896 180)
			(unlocked yes)
			(layer "B.Fab")
			(hide yes)
			(effects
				(font
					(size 1.016 1.016)
					(thickness 0.1524)
				)
				(justify mirror)
			)
		)
		(duplicate_pad_numbers_are_jumpers no)
		(fp_line
			(start 0.508 -0.9398)
			(end 0.508 0.9398)
			(stroke
				(width 0.1524)
				(type default)
			)
			(layer "B.SilkS")
		)
		(fp_line
			(start -0.508 -0.9398)
			(end 0.508 -0.9398)
			(stroke
				(width 0.1524)
				(type default)
			)
			(layer "B.SilkS")
		)
		(fp_rect
			(start 0.508 0.9398)
			(end -0.508 -0.9398)
			(stroke
				(width 0)
				(type default)
			)
			(fill no)
			(layer "B.CrtYd")
		)
		(fp_rect
			(start 0.508 0.9398)
			(end -0.508 -0.9398)
			(stroke
				(width 0)
				(type default)
			)
			(fill no)
			(layer "B.Fab")
		)
		(pad "1" smd custom
			(at 0 -0.4445)
			(size 0.1397 0.1397)
			(layers "B.Cu" "B.Mask" "B.Paste")
			(net "MEMA_9")
			(options
				(clearance outline)
				(anchor circle)
			)
			(primitives
				(gr_poly
					(pts
						(arc
							(start -0.1778 0.2794)
							(mid -0.249642 0.249642)
							(end -0.2794 0.1778)
						)
						(arc
							(start -0.2794 -0.1778)
							(mid -0.249642 -0.249642)
							(end -0.1778 -0.2794)
						)
						(arc
							(start 0.1778 -0.2794)
							(mid 0.249642 -0.249642)
							(end 0.2794 -0.1778)
						)
						(arc
							(start 0.2794 0.1778)
							(mid 0.249642 0.249642)
							(end 0.1778 0.2794)
						)
					)
					(width 0)
					(fill yes)
				)
			)
		)
		(pad "2" smd custom
			(at 0 0.4445)
			(size 0.1397 0.1397)
			(layers "B.Cu" "B.Mask" "B.Paste")
			(net "P1V2_STBY")
			(options
				(clearance outline)
				(anchor circle)
			)
			(primitives
				(gr_poly
					(pts
						(arc
							(start -0.1778 0.2794)
							(mid -0.249642 0.249642)
							(end -0.2794 0.1778)
						)
						(arc
							(start -0.2794 -0.1778)
							(mid -0.249642 -0.249642)
							(end -0.1778 -0.2794)
						)
						(arc
							(start 0.1778 -0.2794)
							(mid 0.249642 -0.249642)
							(end 0.2794 -0.1778)
						)
						(arc
							(start 0.2794 0.1778)
							(mid 0.249642 0.249642)
							(end 0.1778 0.2794)
						)
					)
					(width 0)
					(fill yes)
				)
			)
		)
	)
	(footprint ""
		(layer "B.Cu")
		(at 32.713168 -153.124916 90)
		(property "Reference" "R336"
			(at 0 0 90)
			(layer "B.SilkS")
			(hide yes)
			(effects
				(font
					(size 1.27 1.27)
				)
				(justify mirror)
			)
		)
		(property "Value" "4K7R2F-GP"
			(at -0.064008 -3.993896 90)
			(unlocked yes)
			(layer "B.Fab")
			(hide yes)
			(effects
				(font
					(size 1.016 1.016)
					(thickness 0.1524)
				)
				(justify mirror)
			)
		)
		(property "Device Type" "R402H16"
			(at -0.064008 -5.517896 90)
			(unlocked yes)
			(layer "B.Fab")
			(hide yes)
			(effects
				(font
					(size 1.016 1.016)
					(thickness 0.1524)
				)
				(justify mirror)
			)
		)
		(duplicate_pad_numbers_are_jumpers no)
		(fp_line
			(start 0.508 -0.9398)
			(end 0.508 0.9398)
			(stroke
				(width 0.1524)
				(type default)
			)
			(layer "B.SilkS")
		)
		(fp_line
			(start -0.508 -0.9398)
			(end 0.508 -0.9398)
			(stroke
				(width 0.1524)
				(type default)
			)
			(layer "B.SilkS")
		)
		(fp_rect
			(start 0.508 0.9398)
			(end -0.508 -0.9398)
			(stroke
				(width 0)
				(type default)
			)
			(fill no)
			(layer "B.CrtYd")
		)
		(fp_rect
			(start 0.508 0.9398)
			(end -0.508 -0.9398)
			(stroke
				(width 0)
				(type default)
			)
			(fill no)
			(layer "B.Fab")
		)
		(pad "1" smd custom
			(at 0 -0.4445 270)
			(size 0.1397 0.1397)
			(layers "B.Cu" "B.Mask" "B.Paste")
			(net "P3V3_STBY")
			(options
				(clearance outline)
				(anchor circle)
			)
			(primitives
				(gr_poly
					(pts
						(arc
							(start -0.1778 0.2794)
							(mid -0.249642 0.249642)
							(end -0.2794 0.1778)
						)
						(arc
							(start -0.2794 -0.1778)
							(mid -0.249642 -0.249642)
							(end -0.1778 -0.2794)
						)
						(arc
							(start 0.1778 -0.2794)
							(mid 0.249642 -0.249642)
							(end 0.2794 -0.1778)
						)
						(arc
							(start 0.2794 0.1778)
							(mid 0.249642 0.249642)
							(end 0.1778 0.2794)
						)
					)
					(width 0)
					(fill yes)
				)
			)
		)
		(pad "2" smd custom
			(at 0 0.4445 270)
			(size 0.1397 0.1397)
			(layers "B.Cu" "B.Mask" "B.Paste")
			(net "ENCL_FAULT_LED")
			(options
				(clearance outline)
				(anchor circle)
			)
			(primitives
				(gr_poly
					(pts
						(arc
							(start -0.1778 0.2794)
							(mid -0.249642 0.249642)
							(end -0.2794 0.1778)
						)
						(arc
							(start -0.2794 -0.1778)
							(mid -0.249642 -0.249642)
							(end -0.1778 -0.2794)
						)
						(arc
							(start 0.1778 -0.2794)
							(mid 0.249642 -0.249642)
							(end 0.2794 -0.1778)
						)
						(arc
							(start 0.2794 0.1778)
							(mid 0.249642 0.249642)
							(end 0.1778 0.2794)
						)
					)
					(width 0)
					(fill yes)
				)
			)
		)
	)
	(footprint ""
		(layer "B.Cu")
		(at 52.1716 -162.88258 90)
		(property "Reference" "R408"
			(at 0 0 90)
			(layer "B.SilkS")
			(hide yes)
			(effects
				(font
					(size 1.27 1.27)
				)
				(justify mirror)
			)
		)
		(property "Value" "1KR2F-3-GP"
			(at -0.064008 -3.993896 90)
			(unlocked yes)
			(layer "B.Fab")
			(hide yes)
			(effects
				(font
					(size 1.016 1.016)
					(thickness 0.1524)
				)
				(justify mirror)
			)
		)
		(property "Device Type" "R402H16"
			(at -0.064008 -5.517896 90)
			(unlocked yes)
			(layer "B.Fab")
			(hide yes)
			(effects
				(font
					(size 1.016 1.016)
					(thickness 0.1524)
				)
				(justify mirror)
			)
		)
		(duplicate_pad_numbers_are_jumpers no)
		(fp_line
			(start 0.508 -0.9398)
			(end 0.508 0.9398)
			(stroke
				(width 0.1524)
				(type default)
			)
			(layer "B.SilkS")
		)
		(fp_line
			(start -0.508 -0.9398)
			(end 0.508 -0.9398)
			(stroke
				(width 0.1524)
				(type default)
			)
			(layer "B.SilkS")
		)
		(fp_rect
			(start 0.508 0.9398)
			(end -0.508 -0.9398)
			(stroke
				(width 0)
				(type default)
			)
			(fill no)
			(layer "B.CrtYd")
		)
		(fp_rect
			(start 0.508 0.9398)
			(end -0.508 -0.9398)
			(stroke
				(width 0)
				(type default)
			)
			(fill no)
			(layer "B.Fab")
		)
		(pad "1" smd custom
			(at 0 -0.4445 270)
			(size 0.1397 0.1397)
			(layers "B.Cu" "B.Mask" "B.Paste")
			(net "P1V5")
			(options
				(clearance outline)
				(anchor circle)
			)
			(primitives
				(gr_poly
					(pts
						(arc
							(start -0.1778 0.2794)
							(mid -0.249642 0.249642)
							(end -0.2794 0.1778)
						)
						(arc
							(start -0.2794 -0.1778)
							(mid -0.249642 -0.249642)
							(end -0.1778 -0.2794)
						)
						(arc
							(start 0.1778 -0.2794)
							(mid 0.249642 -0.249642)
							(end 0.2794 -0.1778)
						)
						(arc
							(start 0.2794 0.1778)
							(mid 0.249642 0.249642)
							(end 0.1778 0.2794)
						)
					)
					(width 0)
					(fill yes)
				)
			)
		)
		(pad "2" smd custom
			(at 0 0.4445 270)
			(size 0.1397 0.1397)
			(layers "B.Cu" "B.Mask" "B.Paste")
			(net "ADC_P1V5")
			(options
				(clearance outline)
				(anchor circle)
			)
			(primitives
				(gr_poly
					(pts
						(arc
							(start -0.1778 0.2794)
							(mid -0.249642 0.249642)
							(end -0.2794 0.1778)
						)
						(arc
							(start -0.2794 -0.1778)
							(mid -0.249642 -0.249642)
							(end -0.1778 -0.2794)
						)
						(arc
							(start 0.1778 -0.2794)
							(mid 0.249642 -0.249642)
							(end 0.2794 -0.1778)
						)
						(arc
							(start 0.2794 0.1778)
							(mid 0.249642 0.249642)
							(end 0.1778 0.2794)
						)
					)
					(width 0)
					(fill yes)
				)
			)
		)
	)
	(footprint ""
		(layer "B.Cu")
		(at 55.74919 -147.916392)
		(property "Reference" "TP82"
			(at 0 0 0)
			(layer "B.SilkS")
			(hide yes)
			(effects
				(font
					(size 1.27 1.27)
				)
				(justify mirror)
			)
		)
		(property "Value" "TPAD28-2-GP"
			(at 0.0127 -1.6637 0)
			(unlocked yes)
			(layer "B.Fab")
			(hide yes)
			(effects
				(font
					(size 1.016 1.016)
					(thickness 0.1524)
				)
				(justify mirror)
			)
		)
		(property "Device Type" "TPAD28"
			(at 0.0127 -3.1877 0)
			(unlocked yes)
			(layer "B.Fab")
			(hide yes)
			(effects
				(font
					(size 1.016 1.016)
					(thickness 0.1524)
				)
				(justify mirror)
			)
		)
		(duplicate_pad_numbers_are_jumpers no)
		(fp_poly
			(pts
				(arc
					(start 0.3556 0)
					(mid -0.3556 0)
					(end 0.3556 0)
				)
			)
			(stroke
				(width 0)
				(type default)
			)
			(fill no)
			(layer "B.CrtYd")
		)
		(fp_poly
			(pts
				(arc
					(start 0.6096 0)
					(mid -0.6096 0)
					(end 0.6096 0)
				)
			)
			(stroke
				(width 0)
				(type default)
			)
			(fill no)
			(layer "B.Fab")
		)
		(pad "1" smd circle
			(at 0 0 180)
			(size 0.7112 0.7112)
			(layers "B.Cu" "B.Mask" "B.Paste")
			(net "BMC0_JTAG_RTCK")
		)
	)
	(footprint ""
		(layer "B.Cu")
		(at 202.9968 -54.9529)
		(property "Reference" "C437"
			(at 0 0 0)
			(layer "B.SilkS")
			(hide yes)
			(effects
				(font
					(size 1.27 1.27)
				)
				(justify mirror)
			)
		)
		(property "Value" "SCD1U16V2KX-3GP"
			(at -1.1811 -2.7051 0)
			(unlocked yes)
			(layer "B.Fab")
			(hide yes)
			(effects
				(font
					(size 1.016 1.016)
					(thickness 0.1524)
				)
				(justify mirror)
			)
		)
		(property "Device Type" "C402H22"
			(at -1.1811 -4.2291 0)
			(unlocked yes)
			(layer "B.Fab")
			(hide yes)
			(effects
				(font
					(size 1.016 1.016)
					(thickness 0.1524)
				)
				(justify mirror)
			)
		)
		(duplicate_pad_numbers_are_jumpers no)
		(fp_rect
			(start 0.4318 0.9525)
			(end -0.4318 -0.9525)
			(stroke
				(width 0)
				(type default)
			)
			(fill no)
			(layer "B.CrtYd")
		)
		(fp_rect
			(start 0.4318 0.9525)
			(end -0.4318 -0.9525)
			(stroke
				(width 0)
				(type default)
			)
			(fill no)
			(layer "B.Fab")
		)
		(pad "1" smd custom
			(at 0 -0.4445 180)
			(size 0.1524 0.1524)
			(layers "B.Cu" "B.Mask" "B.Paste")
			(net "P1V8")
			(options
				(clearance outline)
				(anchor circle)
			)
			(primitives
				(gr_poly
					(pts
						(arc
							(start 0.3048 0.2032)
							(mid 0.275042 0.275042)
							(end 0.2032 0.3048)
						)
						(arc
							(start -0.2032 0.3048)
							(mid -0.275042 0.275042)
							(end -0.3048 0.2032)
						)
						(arc
							(start -0.3048 -0.2032)
							(mid -0.275042 -0.275042)
							(end -0.2032 -0.3048)
						)
						(arc
							(start 0.2032 -0.3048)
							(mid 0.275042 -0.275042)
							(end 0.3048 -0.2032)
						)
					)
					(width 0)
					(fill yes)
				)
			)
		)
		(pad "2" smd custom
			(at 0 0.4445 180)
			(size 0.1524 0.1524)
			(layers "B.Cu" "B.Mask" "B.Paste")
			(net "GND")
			(options
				(clearance outline)
				(anchor circle)
			)
			(primitives
				(gr_poly
					(pts
						(arc
							(start 0.3048 0.2032)
							(mid 0.275042 0.275042)
							(end 0.2032 0.3048)
						)
						(arc
							(start -0.2032 0.3048)
							(mid -0.275042 0.275042)
							(end -0.3048 0.2032)
						)
						(arc
							(start -0.3048 -0.2032)
							(mid -0.275042 -0.275042)
							(end -0.2032 -0.3048)
						)
						(arc
							(start 0.2032 -0.3048)
							(mid 0.275042 -0.275042)
							(end 0.3048 -0.2032)
						)
					)
					(width 0)
					(fill yes)
				)
			)
		)
	)
	(footprint ""
		(layer "B.Cu")
		(at 187.1472 -70.6882)
		(property "Reference" "TP148"
			(at 0 0 0)
			(layer "B.SilkS")
			(hide yes)
			(effects
				(font
					(size 1.27 1.27)
				)
				(justify mirror)
			)
		)
		(property "Value" "TPAD28-2-GP"
			(at 0.0127 -1.6637 0)
			(unlocked yes)
			(layer "B.Fab")
			(hide yes)
			(effects
				(font
					(size 1.016 1.016)
					(thickness 0.1524)
				)
				(justify mirror)
			)
		)
		(property "Device Type" "TPAD28"
			(at 0.0127 -3.1877 0)
			(unlocked yes)
			(layer "B.Fab")
			(hide yes)
			(effects
				(font
					(size 1.016 1.016)
					(thickness 0.1524)
				)
				(justify mirror)
			)
		)
		(duplicate_pad_numbers_are_jumpers no)
		(fp_poly
			(pts
				(arc
					(start 0.3556 0)
					(mid -0.3556 0)
					(end 0.3556 0)
				)
			)
			(stroke
				(width 0)
				(type default)
			)
			(fill no)
			(layer "B.CrtYd")
		)
		(fp_poly
			(pts
				(arc
					(start 0.6096 0)
					(mid -0.6096 0)
					(end 0.6096 0)
				)
			)
			(stroke
				(width 0)
				(type default)
			)
			(fill no)
			(layer "B.Fab")
		)
		(pad "1" smd circle
			(at 0 0 180)
			(size 0.7112 0.7112)
			(layers "B.Cu" "B.Mask" "B.Paste")
			(net "SYS_DBMODE0")
		)
	)
	(footprint ""
		(layer "B.Cu")
		(at 195.193666 -53.457856)
		(property "Reference" "C459"
			(at 0 0 0)
			(layer "B.SilkS")
			(hide yes)
			(effects
				(font
					(size 1.27 1.27)
				)
				(justify mirror)
			)
		)
		(property "Value" "SCD1U16V2KX-3GP"
			(at -1.1811 -2.7051 0)
			(unlocked yes)
			(layer "B.Fab")
			(hide yes)
			(effects
				(font
					(size 1.016 1.016)
					(thickness 0.1524)
				)
				(justify mirror)
			)
		)
		(property "Device Type" "C402H22"
			(at -1.1811 -4.2291 0)
			(unlocked yes)
			(layer "B.Fab")
			(hide yes)
			(effects
				(font
					(size 1.016 1.016)
					(thickness 0.1524)
				)
				(justify mirror)
			)
		)
		(duplicate_pad_numbers_are_jumpers no)
		(fp_rect
			(start 0.4318 0.9525)
			(end -0.4318 -0.9525)
			(stroke
				(width 0)
				(type default)
			)
			(fill no)
			(layer "B.CrtYd")
		)
		(fp_rect
			(start 0.4318 0.9525)
			(end -0.4318 -0.9525)
			(stroke
				(width 0)
				(type default)
			)
			(fill no)
			(layer "B.Fab")
		)
		(pad "1" smd custom
			(at 0 -0.4445 180)
			(size 0.1524 0.1524)
			(layers "B.Cu" "B.Mask" "B.Paste")
			(net "P1V8")
			(options
				(clearance outline)
				(anchor circle)
			)
			(primitives
				(gr_poly
					(pts
						(arc
							(start 0.3048 0.2032)
							(mid 0.275042 0.275042)
							(end 0.2032 0.3048)
						)
						(arc
							(start -0.2032 0.3048)
							(mid -0.275042 0.275042)
							(end -0.3048 0.2032)
						)
						(arc
							(start -0.3048 -0.2032)
							(mid -0.275042 -0.275042)
							(end -0.2032 -0.3048)
						)
						(arc
							(start 0.2032 -0.3048)
							(mid 0.275042 -0.275042)
							(end 0.3048 -0.2032)
						)
					)
					(width 0)
					(fill yes)
				)
			)
		)
		(pad "2" smd custom
			(at 0 0.4445 180)
			(size 0.1524 0.1524)
			(layers "B.Cu" "B.Mask" "B.Paste")
			(net "GND")
			(options
				(clearance outline)
				(anchor circle)
			)
			(primitives
				(gr_poly
					(pts
						(arc
							(start 0.3048 0.2032)
							(mid 0.275042 0.275042)
							(end 0.2032 0.3048)
						)
						(arc
							(start -0.2032 0.3048)
							(mid -0.275042 0.275042)
							(end -0.3048 0.2032)
						)
						(arc
							(start -0.3048 -0.2032)
							(mid -0.275042 -0.275042)
							(end -0.2032 -0.3048)
						)
						(arc
							(start 0.2032 -0.3048)
							(mid 0.275042 -0.275042)
							(end 0.3048 -0.2032)
						)
					)
					(width 0)
					(fill yes)
				)
			)
		)
	)
	(footprint ""
		(layer "B.Cu")
		(at 194.2846 -53.848)
		(property "Reference" "C434"
			(at 0 0 0)
			(layer "B.SilkS")
			(hide yes)
			(effects
				(font
					(size 1.27 1.27)
				)
				(justify mirror)
			)
		)
		(property "Value" "SCD1U16V2KX-3GP"
			(at -1.1811 -2.7051 0)
			(unlocked yes)
			(layer "B.Fab")
			(hide yes)
			(effects
				(font
					(size 1.016 1.016)
					(thickness 0.1524)
				)
				(justify mirror)
			)
		)
		(property "Device Type" "C402H22"
			(at -1.1811 -4.2291 0)
			(unlocked yes)
			(layer "B.Fab")
			(hide yes)
			(effects
				(font
					(size 1.016 1.016)
					(thickness 0.1524)
				)
				(justify mirror)
			)
		)
		(duplicate_pad_numbers_are_jumpers no)
		(fp_rect
			(start 0.4318 0.9525)
			(end -0.4318 -0.9525)
			(stroke
				(width 0)
				(type default)
			)
			(fill no)
			(layer "B.CrtYd")
		)
		(fp_rect
			(start 0.4318 0.9525)
			(end -0.4318 -0.9525)
			(stroke
				(width 0)
				(type default)
			)
			(fill no)
			(layer "B.Fab")
		)
		(pad "1" smd custom
			(at 0 -0.4445 180)
			(size 0.1524 0.1524)
			(layers "B.Cu" "B.Mask" "B.Paste")
			(net "P1V8")
			(options
				(clearance outline)
				(anchor circle)
			)
			(primitives
				(gr_poly
					(pts
						(arc
							(start 0.3048 0.2032)
							(mid 0.275042 0.275042)
							(end 0.2032 0.3048)
						)
						(arc
							(start -0.2032 0.3048)
							(mid -0.275042 0.275042)
							(end -0.3048 0.2032)
						)
						(arc
							(start -0.3048 -0.2032)
							(mid -0.275042 -0.275042)
							(end -0.2032 -0.3048)
						)
						(arc
							(start 0.2032 -0.3048)
							(mid 0.275042 -0.275042)
							(end 0.3048 -0.2032)
						)
					)
					(width 0)
					(fill yes)
				)
			)
		)
		(pad "2" smd custom
			(at 0 0.4445 180)
			(size 0.1524 0.1524)
			(layers "B.Cu" "B.Mask" "B.Paste")
			(net "GND")
			(options
				(clearance outline)
				(anchor circle)
			)
			(primitives
				(gr_poly
					(pts
						(arc
							(start 0.3048 0.2032)
							(mid 0.275042 0.275042)
							(end 0.2032 0.3048)
						)
						(arc
							(start -0.2032 0.3048)
							(mid -0.275042 0.275042)
							(end -0.3048 0.2032)
						)
						(arc
							(start -0.3048 -0.2032)
							(mid -0.275042 -0.275042)
							(end -0.2032 -0.3048)
						)
						(arc
							(start 0.2032 -0.3048)
							(mid 0.275042 -0.275042)
							(end 0.3048 -0.2032)
						)
					)
					(width 0)
					(fill yes)
				)
			)
		)
	)
	(footprint ""
		(layer "B.Cu")
		(at 49.81321 -120.888252 90)
		(property "Reference" "R342"
			(at 0 0 90)
			(layer "B.SilkS")
			(hide yes)
			(effects
				(font
					(size 1.27 1.27)
				)
				(justify mirror)
			)
		)
		(property "Value" "0R2J-2-GP"
			(at -0.064008 -3.993896 90)
			(unlocked yes)
			(layer "B.Fab")
			(hide yes)
			(effects
				(font
					(size 1.016 1.016)
					(thickness 0.1524)
				)
				(justify mirror)
			)
		)
		(property "Device Type" "R402H16"
			(at -0.064008 -5.517896 90)
			(unlocked yes)
			(layer "B.Fab")
			(hide yes)
			(effects
				(font
					(size 1.016 1.016)
					(thickness 0.1524)
				)
				(justify mirror)
			)
		)
		(duplicate_pad_numbers_are_jumpers no)
		(fp_line
			(start 0.508 -0.9398)
			(end 0.508 0.9398)
			(stroke
				(width 0.1524)
				(type default)
			)
			(layer "B.SilkS")
		)
		(fp_line
			(start -0.508 -0.9398)
			(end 0.508 -0.9398)
			(stroke
				(width 0.1524)
				(type default)
			)
			(layer "B.SilkS")
		)
		(fp_rect
			(start 0.508 0.9398)
			(end -0.508 -0.9398)
			(stroke
				(width 0)
				(type default)
			)
			(fill no)
			(layer "B.CrtYd")
		)
		(fp_rect
			(start 0.508 0.9398)
			(end -0.508 -0.9398)
			(stroke
				(width 0)
				(type default)
			)
			(fill no)
			(layer "B.Fab")
		)
		(pad "1" smd custom
			(at 0 -0.4445 270)
			(size 0.1397 0.1397)
			(layers "B.Cu" "B.Mask" "B.Paste")
			(net "TEMP_3_SDA")
			(options
				(clearance outline)
				(anchor circle)
			)
			(primitives
				(gr_poly
					(pts
						(arc
							(start -0.1778 0.2794)
							(mid -0.249642 0.249642)
							(end -0.2794 0.1778)
						)
						(arc
							(start -0.2794 -0.1778)
							(mid -0.249642 -0.249642)
							(end -0.1778 -0.2794)
						)
						(arc
							(start 0.1778 -0.2794)
							(mid 0.249642 -0.249642)
							(end 0.2794 -0.1778)
						)
						(arc
							(start 0.2794 0.1778)
							(mid 0.249642 0.249642)
							(end 0.1778 0.2794)
						)
					)
					(width 0)
					(fill yes)
				)
			)
		)
		(pad "2" smd custom
			(at 0 0.4445 270)
			(size 0.1397 0.1397)
			(layers "B.Cu" "B.Mask" "B.Paste")
			(net "I2C_IOM_SDA")
			(options
				(clearance outline)
				(anchor circle)
			)
			(primitives
				(gr_poly
					(pts
						(arc
							(start -0.1778 0.2794)
							(mid -0.249642 0.249642)
							(end -0.2794 0.1778)
						)
						(arc
							(start -0.2794 -0.1778)
							(mid -0.249642 -0.249642)
							(end -0.1778 -0.2794)
						)
						(arc
							(start 0.1778 -0.2794)
							(mid 0.249642 -0.249642)
							(end 0.2794 -0.1778)
						)
						(arc
							(start 0.2794 0.1778)
							(mid 0.249642 0.249642)
							(end 0.1778 0.2794)
						)
					)
					(width 0)
					(fill yes)
				)
			)
		)
	)
	(footprint ""
		(layer "B.Cu")
		(at 177.28184 -74.2696)
		(property "Reference" "TP119"
			(at 0 0 0)
			(layer "B.SilkS")
			(hide yes)
			(effects
				(font
					(size 1.27 1.27)
				)
				(justify mirror)
			)
		)
		(property "Value" "TPAD28-2-GP"
			(at 0.0127 -1.6637 0)
			(unlocked yes)
			(layer "B.Fab")
			(hide yes)
			(effects
				(font
					(size 1.016 1.016)
					(thickness 0.1524)
				)
				(justify mirror)
			)
		)
		(property "Device Type" "TPAD28"
			(at 0.0127 -3.1877 0)
			(unlocked yes)
			(layer "B.Fab")
			(hide yes)
			(effects
				(font
					(size 1.016 1.016)
					(thickness 0.1524)
				)
				(justify mirror)
			)
		)
		(duplicate_pad_numbers_are_jumpers no)
		(fp_poly
			(pts
				(arc
					(start 0.3556 0)
					(mid -0.3556 0)
					(end 0.3556 0)
				)
			)
			(stroke
				(width 0)
				(type default)
			)
			(fill no)
			(layer "B.CrtYd")
		)
		(fp_poly
			(pts
				(arc
					(start 0.6096 0)
					(mid -0.6096 0)
					(end 0.6096 0)
				)
			)
			(stroke
				(width 0)
				(type default)
			)
			(fill no)
			(layer "B.Fab")
		)
		(pad "1" smd circle
			(at 0 0 180)
			(size 0.7112 0.7112)
			(layers "B.Cu" "B.Mask" "B.Paste")
			(net "IOC_GPIO_30")
		)
	)
	(footprint ""
		(layer "B.Cu")
		(at 193.9798 -64.8208 90)
		(property "Reference" "C400"
			(at 0 0 90)
			(layer "B.SilkS")
			(hide yes)
			(effects
				(font
					(size 1.27 1.27)
				)
				(justify mirror)
			)
		)
		(property "Value" "SCD1U6D3V1KX-GP"
			(at 2.8321 -1.7399 90)
			(unlocked yes)
			(layer "B.Fab")
			(hide yes)
			(effects
				(font
					(size 1.016 1.016)
					(thickness 0.1524)
				)
				(justify mirror)
			)
		)
		(property "Device Type" "C0201H13"
			(at 2.8321 -3.2639 90)
			(unlocked yes)
			(layer "B.Fab")
			(hide yes)
			(effects
				(font
					(size 1.016 1.016)
					(thickness 0.1524)
				)
				(justify mirror)
			)
		)
		(duplicate_pad_numbers_are_jumpers no)
		(fp_rect
			(start 0.2794 0.6477)
			(end -0.2794 -0.6477)
			(stroke
				(width 0)
				(type default)
			)
			(fill no)
			(layer "B.CrtYd")
		)
		(fp_rect
			(start 0.2794 0.6477)
			(end -0.2794 -0.6477)
			(stroke
				(width 0)
				(type default)
			)
			(fill no)
			(layer "B.Fab")
		)
		(pad "1" smd custom
			(at 0 -0.2794 270)
			(size 0.0762 0.0762)
			(layers "B.Cu" "B.Mask" "B.Paste")
			(net "P0V975")
			(options
				(clearance outline)
				(anchor circle)
			)
			(primitives
				(gr_poly
					(pts
						(arc
							(start 0.1524 0.127)
							(mid 0.137521 0.162921)
							(end 0.1016 0.1778)
						)
						(arc
							(start -0.1016 0.1778)
							(mid -0.137521 0.162921)
							(end -0.1524 0.127)
						)
						(arc
							(start -0.1524 -0.127)
							(mid -0.137521 -0.162921)
							(end -0.1016 -0.1778)
						)
						(arc
							(start 0.1016 -0.1778)
							(mid 0.137521 -0.162921)
							(end 0.1524 -0.127)
						)
					)
					(width 0)
					(fill yes)
				)
			)
		)
		(pad "2" smd custom
			(at 0 0.2794 270)
			(size 0.0762 0.0762)
			(layers "B.Cu" "B.Mask" "B.Paste")
			(net "GND")
			(options
				(clearance outline)
				(anchor circle)
			)
			(primitives
				(gr_poly
					(pts
						(arc
							(start 0.1524 0.127)
							(mid 0.137521 0.162921)
							(end 0.1016 0.1778)
						)
						(arc
							(start -0.1016 0.1778)
							(mid -0.137521 0.162921)
							(end -0.1524 0.127)
						)
						(arc
							(start -0.1524 -0.127)
							(mid -0.137521 -0.162921)
							(end -0.1016 -0.1778)
						)
						(arc
							(start 0.1016 -0.1778)
							(mid 0.137521 -0.162921)
							(end 0.1524 -0.127)
						)
					)
					(width 0)
					(fill yes)
				)
			)
		)
	)
	(footprint ""
		(layer "B.Cu")
		(at 188.078872 -74.793856 -90)
		(property "Reference" "C472"
			(at 0 0 90)
			(layer "B.SilkS")
			(hide yes)
			(effects
				(font
					(size 1.27 1.27)
				)
				(justify mirror)
			)
		)
		(property "Value" "SCD1U16V2KX-3GP"
			(at -1.1811 -2.7051 270)
			(unlocked yes)
			(layer "B.Fab")
			(hide yes)
			(effects
				(font
					(size 1.016 1.016)
					(thickness 0.1524)
				)
				(justify mirror)
			)
		)
		(property "Device Type" "C402H22"
			(at -1.1811 -4.2291 270)
			(unlocked yes)
			(layer "B.Fab")
			(hide yes)
			(effects
				(font
					(size 1.016 1.016)
					(thickness 0.1524)
				)
				(justify mirror)
			)
		)
		(duplicate_pad_numbers_are_jumpers no)
		(fp_rect
			(start 0.4318 0.9525)
			(end -0.4318 -0.9525)
			(stroke
				(width 0)
				(type default)
			)
			(fill no)
			(layer "B.CrtYd")
		)
		(fp_rect
			(start 0.4318 0.9525)
			(end -0.4318 -0.9525)
			(stroke
				(width 0)
				(type default)
			)
			(fill no)
			(layer "B.Fab")
		)
		(pad "1" smd custom
			(at 0 -0.4445 90)
			(size 0.1524 0.1524)
			(layers "B.Cu" "B.Mask" "B.Paste")
			(net "P1V8")
			(options
				(clearance outline)
				(anchor circle)
			)
			(primitives
				(gr_poly
					(pts
						(arc
							(start 0.3048 0.2032)
							(mid 0.275042 0.275042)
							(end 0.2032 0.3048)
						)
						(arc
							(start -0.2032 0.3048)
							(mid -0.275042 0.275042)
							(end -0.3048 0.2032)
						)
						(arc
							(start -0.3048 -0.2032)
							(mid -0.275042 -0.275042)
							(end -0.2032 -0.3048)
						)
						(arc
							(start 0.2032 -0.3048)
							(mid 0.275042 -0.275042)
							(end 0.3048 -0.2032)
						)
					)
					(width 0)
					(fill yes)
				)
			)
		)
		(pad "2" smd custom
			(at 0 0.4445 90)
			(size 0.1524 0.1524)
			(layers "B.Cu" "B.Mask" "B.Paste")
			(net "GND")
			(options
				(clearance outline)
				(anchor circle)
			)
			(primitives
				(gr_poly
					(pts
						(arc
							(start 0.3048 0.2032)
							(mid 0.275042 0.275042)
							(end 0.2032 0.3048)
						)
						(arc
							(start -0.2032 0.3048)
							(mid -0.275042 0.275042)
							(end -0.3048 0.2032)
						)
						(arc
							(start -0.3048 -0.2032)
							(mid -0.275042 -0.275042)
							(end -0.2032 -0.3048)
						)
						(arc
							(start 0.2032 -0.3048)
							(mid 0.275042 -0.275042)
							(end 0.3048 -0.2032)
						)
					)
					(width 0)
					(fill yes)
				)
			)
		)
	)
	(footprint ""
		(layer "B.Cu")
		(at 190.831978 -62.18047 90)
		(property "Reference" "C414"
			(at 0 0 90)
			(layer "B.SilkS")
			(hide yes)
			(effects
				(font
					(size 1.27 1.27)
				)
				(justify mirror)
			)
		)
		(property "Value" "SCD1U6D3V1KX-GP"
			(at 2.8321 -1.7399 90)
			(unlocked yes)
			(layer "B.Fab")
			(hide yes)
			(effects
				(font
					(size 1.016 1.016)
					(thickness 0.1524)
				)
				(justify mirror)
			)
		)
		(property "Device Type" "C0201H13"
			(at 2.8321 -3.2639 90)
			(unlocked yes)
			(layer "B.Fab")
			(hide yes)
			(effects
				(font
					(size 1.016 1.016)
					(thickness 0.1524)
				)
				(justify mirror)
			)
		)
		(duplicate_pad_numbers_are_jumpers no)
		(fp_rect
			(start 0.2794 0.6477)
			(end -0.2794 -0.6477)
			(stroke
				(width 0)
				(type default)
			)
			(fill no)
			(layer "B.CrtYd")
		)
		(fp_rect
			(start 0.2794 0.6477)
			(end -0.2794 -0.6477)
			(stroke
				(width 0)
				(type default)
			)
			(fill no)
			(layer "B.Fab")
		)
		(pad "1" smd custom
			(at 0 -0.2794 270)
			(size 0.0762 0.0762)
			(layers "B.Cu" "B.Mask" "B.Paste")
			(net "P0V975")
			(options
				(clearance outline)
				(anchor circle)
			)
			(primitives
				(gr_poly
					(pts
						(arc
							(start 0.1524 0.127)
							(mid 0.137521 0.162921)
							(end 0.1016 0.1778)
						)
						(arc
							(start -0.1016 0.1778)
							(mid -0.137521 0.162921)
							(end -0.1524 0.127)
						)
						(arc
							(start -0.1524 -0.127)
							(mid -0.137521 -0.162921)
							(end -0.1016 -0.1778)
						)
						(arc
							(start 0.1016 -0.1778)
							(mid 0.137521 -0.162921)
							(end 0.1524 -0.127)
						)
					)
					(width 0)
					(fill yes)
				)
			)
		)
		(pad "2" smd custom
			(at 0 0.2794 270)
			(size 0.0762 0.0762)
			(layers "B.Cu" "B.Mask" "B.Paste")
			(net "GND")
			(options
				(clearance outline)
				(anchor circle)
			)
			(primitives
				(gr_poly
					(pts
						(arc
							(start 0.1524 0.127)
							(mid 0.137521 0.162921)
							(end 0.1016 0.1778)
						)
						(arc
							(start -0.1016 0.1778)
							(mid -0.137521 0.162921)
							(end -0.1524 0.127)
						)
						(arc
							(start -0.1524 -0.127)
							(mid -0.137521 -0.162921)
							(end -0.1016 -0.1778)
						)
						(arc
							(start 0.1016 -0.1778)
							(mid 0.137521 -0.162921)
							(end 0.1524 -0.127)
						)
					)
					(width 0)
					(fill yes)
				)
			)
		)
	)
	(footprint ""
		(layer "B.Cu")
		(at 191.8462 -66.6369 -90)
		(property "Reference" "C425"
			(at 0 0 90)
			(layer "B.SilkS")
			(hide yes)
			(effects
				(font
					(size 1.27 1.27)
				)
				(justify mirror)
			)
		)
		(property "Value" "SC1KP50V2KX-1GP"
			(at -1.1811 -2.7051 270)
			(unlocked yes)
			(layer "B.Fab")
			(hide yes)
			(effects
				(font
					(size 1.016 1.016)
					(thickness 0.1524)
				)
				(justify mirror)
			)
		)
		(property "Device Type" "C402H22"
			(at -1.1811 -4.2291 270)
			(unlocked yes)
			(layer "B.Fab")
			(hide yes)
			(effects
				(font
					(size 1.016 1.016)
					(thickness 0.1524)
				)
				(justify mirror)
			)
		)
		(duplicate_pad_numbers_are_jumpers no)
		(fp_rect
			(start 0.4318 0.9525)
			(end -0.4318 -0.9525)
			(stroke
				(width 0)
				(type default)
			)
			(fill no)
			(layer "B.CrtYd")
		)
		(fp_rect
			(start 0.4318 0.9525)
			(end -0.4318 -0.9525)
			(stroke
				(width 0)
				(type default)
			)
			(fill no)
			(layer "B.Fab")
		)
		(pad "1" smd custom
			(at 0 -0.4445 90)
			(size 0.1524 0.1524)
			(layers "B.Cu" "B.Mask" "B.Paste")
			(net "P0V975")
			(options
				(clearance outline)
				(anchor circle)
			)
			(primitives
				(gr_poly
					(pts
						(arc
							(start 0.3048 0.2032)
							(mid 0.275042 0.275042)
							(end 0.2032 0.3048)
						)
						(arc
							(start -0.2032 0.3048)
							(mid -0.275042 0.275042)
							(end -0.3048 0.2032)
						)
						(arc
							(start -0.3048 -0.2032)
							(mid -0.275042 -0.275042)
							(end -0.2032 -0.3048)
						)
						(arc
							(start 0.2032 -0.3048)
							(mid 0.275042 -0.275042)
							(end 0.3048 -0.2032)
						)
					)
					(width 0)
					(fill yes)
				)
			)
		)
		(pad "2" smd custom
			(at 0 0.4445 90)
			(size 0.1524 0.1524)
			(layers "B.Cu" "B.Mask" "B.Paste")
			(net "GND")
			(options
				(clearance outline)
				(anchor circle)
			)
			(primitives
				(gr_poly
					(pts
						(arc
							(start 0.3048 0.2032)
							(mid 0.275042 0.275042)
							(end 0.2032 0.3048)
						)
						(arc
							(start -0.2032 0.3048)
							(mid -0.275042 0.275042)
							(end -0.3048 0.2032)
						)
						(arc
							(start -0.3048 -0.2032)
							(mid -0.275042 -0.275042)
							(end -0.2032 -0.3048)
						)
						(arc
							(start 0.2032 -0.3048)
							(mid 0.275042 -0.275042)
							(end 0.3048 -0.2032)
						)
					)
					(width 0)
					(fill yes)
				)
			)
		)
	)
	(footprint ""
		(layer "B.Cu")
		(at 41.91762 -136.94918)
		(property "Reference" "TP29"
			(at 0 0 0)
			(layer "B.SilkS")
			(hide yes)
			(effects
				(font
					(size 1.27 1.27)
				)
				(justify mirror)
			)
		)
		(property "Value" "TPAD28-2-GP"
			(at 0.0127 -1.6637 0)
			(unlocked yes)
			(layer "B.Fab")
			(hide yes)
			(effects
				(font
					(size 1.016 1.016)
					(thickness 0.1524)
				)
				(justify mirror)
			)
		)
		(property "Device Type" "TPAD28"
			(at 0.0127 -3.1877 0)
			(unlocked yes)
			(layer "B.Fab")
			(hide yes)
			(effects
				(font
					(size 1.016 1.016)
					(thickness 0.1524)
				)
				(justify mirror)
			)
		)
		(duplicate_pad_numbers_are_jumpers no)
		(fp_poly
			(pts
				(arc
					(start 0.3556 0)
					(mid -0.3556 0)
					(end 0.3556 0)
				)
			)
			(stroke
				(width 0)
				(type default)
			)
			(fill no)
			(layer "B.CrtYd")
		)
		(fp_poly
			(pts
				(arc
					(start 0.6096 0)
					(mid -0.6096 0)
					(end 0.6096 0)
				)
			)
			(stroke
				(width 0)
				(type default)
			)
			(fill no)
			(layer "B.Fab")
		)
		(pad "1" smd circle
			(at 0 0 180)
			(size 0.7112 0.7112)
			(layers "B.Cu" "B.Mask" "B.Paste")
			(net "TP_BMC_GPIOR5")
		)
	)
	(footprint ""
		(layer "B.Cu")
		(at 12.11199 -141.008862 90)
		(property "Reference" "R255"
			(at 0 0 90)
			(layer "B.SilkS")
			(hide yes)
			(effects
				(font
					(size 1.27 1.27)
				)
				(justify mirror)
			)
		)
		(property "Value" "120R2F-GP"
			(at -0.064008 -3.993896 90)
			(unlocked yes)
			(layer "B.Fab")
			(hide yes)
			(effects
				(font
					(size 1.016 1.016)
					(thickness 0.1524)
				)
				(justify mirror)
			)
		)
		(property "Device Type" "R402H16"
			(at -0.064008 -5.517896 90)
			(unlocked yes)
			(layer "B.Fab")
			(hide yes)
			(effects
				(font
					(size 1.016 1.016)
					(thickness 0.1524)
				)
				(justify mirror)
			)
		)
		(duplicate_pad_numbers_are_jumpers no)
		(fp_line
			(start 0.508 -0.9398)
			(end 0.508 0.9398)
			(stroke
				(width 0.1524)
				(type default)
			)
			(layer "B.SilkS")
		)
		(fp_line
			(start -0.508 -0.9398)
			(end 0.508 -0.9398)
			(stroke
				(width 0.1524)
				(type default)
			)
			(layer "B.SilkS")
		)
		(fp_rect
			(start 0.508 0.9398)
			(end -0.508 -0.9398)
			(stroke
				(width 0)
				(type default)
			)
			(fill no)
			(layer "B.CrtYd")
		)
		(fp_rect
			(start 0.508 0.9398)
			(end -0.508 -0.9398)
			(stroke
				(width 0)
				(type default)
			)
			(fill no)
			(layer "B.Fab")
		)
		(pad "1" smd custom
			(at 0 -0.4445 270)
			(size 0.1397 0.1397)
			(layers "B.Cu" "B.Mask" "B.Paste")
			(net "MEMA_10")
			(options
				(clearance outline)
				(anchor circle)
			)
			(primitives
				(gr_poly
					(pts
						(arc
							(start -0.1778 0.2794)
							(mid -0.249642 0.249642)
							(end -0.2794 0.1778)
						)
						(arc
							(start -0.2794 -0.1778)
							(mid -0.249642 -0.249642)
							(end -0.1778 -0.2794)
						)
						(arc
							(start 0.1778 -0.2794)
							(mid 0.249642 -0.249642)
							(end 0.2794 -0.1778)
						)
						(arc
							(start 0.2794 0.1778)
							(mid 0.249642 0.249642)
							(end 0.1778 0.2794)
						)
					)
					(width 0)
					(fill yes)
				)
			)
		)
		(pad "2" smd custom
			(at 0 0.4445 270)
			(size 0.1397 0.1397)
			(layers "B.Cu" "B.Mask" "B.Paste")
			(net "P1V2_STBY")
			(options
				(clearance outline)
				(anchor circle)
			)
			(primitives
				(gr_poly
					(pts
						(arc
							(start -0.1778 0.2794)
							(mid -0.249642 0.249642)
							(end -0.2794 0.1778)
						)
						(arc
							(start -0.2794 -0.1778)
							(mid -0.249642 -0.249642)
							(end -0.1778 -0.2794)
						)
						(arc
							(start 0.1778 -0.2794)
							(mid 0.249642 -0.249642)
							(end 0.2794 -0.1778)
						)
						(arc
							(start 0.2794 0.1778)
							(mid 0.249642 0.249642)
							(end 0.1778 0.2794)
						)
					)
					(width 0)
					(fill yes)
				)
			)
		)
	)
	(footprint ""
		(layer "B.Cu")
		(at 50.01006 -143.6624 180)
		(property "Reference" "R363"
			(at 0 0 0)
			(layer "B.SilkS")
			(hide yes)
			(effects
				(font
					(size 1.27 1.27)
				)
				(justify mirror)
			)
		)
		(property "Value" "4K7R2F-GP"
			(at -0.064008 -3.993896 180)
			(unlocked yes)
			(layer "B.Fab")
			(hide yes)
			(effects
				(font
					(size 1.016 1.016)
					(thickness 0.1524)
				)
				(justify mirror)
			)
		)
		(property "Device Type" "R402H16"
			(at -0.064008 -5.517896 180)
			(unlocked yes)
			(layer "B.Fab")
			(hide yes)
			(effects
				(font
					(size 1.016 1.016)
					(thickness 0.1524)
				)
				(justify mirror)
			)
		)
		(duplicate_pad_numbers_are_jumpers no)
		(fp_line
			(start 0.508 -0.9398)
			(end 0.508 0.9398)
			(stroke
				(width 0.1524)
				(type default)
			)
			(layer "B.SilkS")
		)
		(fp_line
			(start -0.508 -0.9398)
			(end 0.508 -0.9398)
			(stroke
				(width 0.1524)
				(type default)
			)
			(layer "B.SilkS")
		)
		(fp_rect
			(start 0.508 0.9398)
			(end -0.508 -0.9398)
			(stroke
				(width 0)
				(type default)
			)
			(fill no)
			(layer "B.CrtYd")
		)
		(fp_rect
			(start 0.508 0.9398)
			(end -0.508 -0.9398)
			(stroke
				(width 0)
				(type default)
			)
			(fill no)
			(layer "B.Fab")
		)
		(pad "1" smd custom
			(at 0 -0.4445)
			(size 0.1397 0.1397)
			(layers "B.Cu" "B.Mask" "B.Paste")
			(net "JTAG_BMC_TRST_N")
			(options
				(clearance outline)
				(anchor circle)
			)
			(primitives
				(gr_poly
					(pts
						(arc
							(start -0.1778 0.2794)
							(mid -0.249642 0.249642)
							(end -0.2794 0.1778)
						)
						(arc
							(start -0.2794 -0.1778)
							(mid -0.249642 -0.249642)
							(end -0.1778 -0.2794)
						)
						(arc
							(start 0.1778 -0.2794)
							(mid 0.249642 -0.249642)
							(end 0.2794 -0.1778)
						)
						(arc
							(start 0.2794 0.1778)
							(mid 0.249642 0.249642)
							(end 0.1778 0.2794)
						)
					)
					(width 0)
					(fill yes)
				)
			)
		)
		(pad "2" smd custom
			(at 0 0.4445)
			(size 0.1397 0.1397)
			(layers "B.Cu" "B.Mask" "B.Paste")
			(net "GND")
			(options
				(clearance outline)
				(anchor circle)
			)
			(primitives
				(gr_poly
					(pts
						(arc
							(start -0.1778 0.2794)
							(mid -0.249642 0.249642)
							(end -0.2794 0.1778)
						)
						(arc
							(start -0.2794 -0.1778)
							(mid -0.249642 -0.249642)
							(end -0.1778 -0.2794)
						)
						(arc
							(start 0.1778 -0.2794)
							(mid 0.249642 -0.249642)
							(end 0.2794 -0.1778)
						)
						(arc
							(start 0.2794 0.1778)
							(mid 0.249642 0.249642)
							(end 0.1778 0.2794)
						)
					)
					(width 0)
					(fill yes)
				)
			)
		)
	)
	(footprint ""
		(layer "B.Cu")
		(at 193.1162 -47.0408 -90)
		(property "Reference" "C330"
			(at 0 0 90)
			(layer "B.SilkS")
			(hide yes)
			(effects
				(font
					(size 1.27 1.27)
				)
				(justify mirror)
			)
		)
		(property "Value" "SC22U6D3V3MX-9-GP-U"
			(at 0 -2.8194 270)
			(unlocked yes)
			(layer "B.Fab")
			(hide yes)
			(effects
				(font
					(size 1.016 1.016)
					(thickness 0.1524)
				)
				(justify mirror)
			)
		)
		(property "Device Type" "C603H40"
			(at 0 -4.3434 270)
			(unlocked yes)
			(layer "B.Fab")
			(hide yes)
			(effects
				(font
					(size 1.016 1.016)
					(thickness 0.1524)
				)
				(justify mirror)
			)
		)
		(duplicate_pad_numbers_are_jumpers no)
		(fp_line
			(start -0.508 0)
			(end 0.508 0)
			(stroke
				(width 0.2032)
				(type default)
			)
			(layer "B.SilkS")
		)
		(fp_rect
			(start 0.5842 1.3335)
			(end -0.5842 -1.3335)
			(stroke
				(width 0)
				(type default)
			)
			(fill no)
			(layer "B.CrtYd")
		)
		(fp_rect
			(start 0.5842 1.3335)
			(end -0.5842 -1.3335)
			(stroke
				(width 0)
				(type default)
			)
			(fill no)
			(layer "B.Fab")
		)
		(pad "1" smd custom
			(at 0 -0.762 90)
			(size 0.2159 0.2159)
			(layers "B.Cu" "B.Mask" "B.Paste")
			(net "HM40ADC_VDDA")
			(options
				(clearance outline)
				(anchor circle)
			)
			(primitives
				(gr_poly
					(pts
						(arc
							(start -0.3302 0.4318)
							(mid -0.402042 0.402042)
							(end -0.4318 0.3302)
						)
						(arc
							(start -0.4318 -0.3302)
							(mid -0.402042 -0.402042)
							(end -0.3302 -0.4318)
						)
						(arc
							(start 0.3302 -0.4318)
							(mid 0.402042 -0.402042)
							(end 0.4318 -0.3302)
						)
						(arc
							(start 0.4318 0.3302)
							(mid 0.402042 0.402042)
							(end 0.3302 0.4318)
						)
					)
					(width 0)
					(fill yes)
				)
			)
		)
		(pad "2" smd custom
			(at 0 0.762 90)
			(size 0.2159 0.2159)
			(layers "B.Cu" "B.Mask" "B.Paste")
			(net "GND")
			(options
				(clearance outline)
				(anchor circle)
			)
			(primitives
				(gr_poly
					(pts
						(arc
							(start -0.3302 0.4318)
							(mid -0.402042 0.402042)
							(end -0.4318 0.3302)
						)
						(arc
							(start -0.4318 -0.3302)
							(mid -0.402042 -0.402042)
							(end -0.3302 -0.4318)
						)
						(arc
							(start 0.3302 -0.4318)
							(mid 0.402042 -0.402042)
							(end 0.4318 -0.3302)
						)
						(arc
							(start 0.4318 0.3302)
							(mid 0.402042 0.402042)
							(end 0.3302 0.4318)
						)
					)
					(width 0)
					(fill yes)
				)
			)
		)
	)
	(footprint ""
		(layer "B.Cu")
		(at 199.86752 -66.29146)
		(property "Reference" "C381"
			(at 0 0 0)
			(layer "B.SilkS")
			(hide yes)
			(effects
				(font
					(size 1.27 1.27)
				)
				(justify mirror)
			)
		)
		(property "Value" "SCD1U6D3V1KX-GP"
			(at 2.8321 -1.7399 0)
			(unlocked yes)
			(layer "B.Fab")
			(hide yes)
			(effects
				(font
					(size 1.016 1.016)
					(thickness 0.1524)
				)
				(justify mirror)
			)
		)
		(property "Device Type" "C0201H13"
			(at 2.8321 -3.2639 0)
			(unlocked yes)
			(layer "B.Fab")
			(hide yes)
			(effects
				(font
					(size 1.016 1.016)
					(thickness 0.1524)
				)
				(justify mirror)
			)
		)
		(duplicate_pad_numbers_are_jumpers no)
		(fp_rect
			(start 0.2794 0.6477)
			(end -0.2794 -0.6477)
			(stroke
				(width 0)
				(type default)
			)
			(fill no)
			(layer "B.CrtYd")
		)
		(fp_rect
			(start 0.2794 0.6477)
			(end -0.2794 -0.6477)
			(stroke
				(width 0)
				(type default)
			)
			(fill no)
			(layer "B.Fab")
		)
		(pad "1" smd custom
			(at 0 -0.2794 180)
			(size 0.0762 0.0762)
			(layers "B.Cu" "B.Mask" "B.Paste")
			(net "SAS0_AVDD")
			(options
				(clearance outline)
				(anchor circle)
			)
			(primitives
				(gr_poly
					(pts
						(arc
							(start 0.1524 0.127)
							(mid 0.137521 0.162921)
							(end 0.1016 0.1778)
						)
						(arc
							(start -0.1016 0.1778)
							(mid -0.137521 0.162921)
							(end -0.1524 0.127)
						)
						(arc
							(start -0.1524 -0.127)
							(mid -0.137521 -0.162921)
							(end -0.1016 -0.1778)
						)
						(arc
							(start 0.1016 -0.1778)
							(mid 0.137521 -0.162921)
							(end 0.1524 -0.127)
						)
					)
					(width 0)
					(fill yes)
				)
			)
		)
		(pad "2" smd custom
			(at 0 0.2794 180)
			(size 0.0762 0.0762)
			(layers "B.Cu" "B.Mask" "B.Paste")
			(net "GND")
			(options
				(clearance outline)
				(anchor circle)
			)
			(primitives
				(gr_poly
					(pts
						(arc
							(start 0.1524 0.127)
							(mid 0.137521 0.162921)
							(end 0.1016 0.1778)
						)
						(arc
							(start -0.1016 0.1778)
							(mid -0.137521 0.162921)
							(end -0.1524 0.127)
						)
						(arc
							(start -0.1524 -0.127)
							(mid -0.137521 -0.162921)
							(end -0.1016 -0.1778)
						)
						(arc
							(start 0.1016 -0.1778)
							(mid 0.137521 -0.162921)
							(end 0.1524 -0.127)
						)
					)
					(width 0)
					(fill yes)
				)
			)
		)
	)
	(footprint ""
		(layer "B.Cu")
		(at 98.9584 -177.9778 90)
		(property "Reference" "C41"
			(at 0 0 90)
			(layer "B.SilkS")
			(hide yes)
			(effects
				(font
					(size 1.27 1.27)
				)
				(justify mirror)
			)
		)
		(property "Value" "SCD1U16V2KX-3GP"
			(at -1.1811 -2.7051 90)
			(unlocked yes)
			(layer "B.Fab")
			(hide yes)
			(effects
				(font
					(size 1.016 1.016)
					(thickness 0.1524)
				)
				(justify mirror)
			)
		)
		(property "Device Type" "C402H22"
			(at -1.1811 -4.2291 90)
			(unlocked yes)
			(layer "B.Fab")
			(hide yes)
			(effects
				(font
					(size 1.016 1.016)
					(thickness 0.1524)
				)
				(justify mirror)
			)
		)
		(duplicate_pad_numbers_are_jumpers no)
		(fp_rect
			(start 0.4318 0.9525)
			(end -0.4318 -0.9525)
			(stroke
				(width 0)
				(type default)
			)
			(fill no)
			(layer "B.CrtYd")
		)
		(fp_rect
			(start 0.4318 0.9525)
			(end -0.4318 -0.9525)
			(stroke
				(width 0)
				(type default)
			)
			(fill no)
			(layer "B.Fab")
		)
		(pad "1" smd custom
			(at 0 -0.4445 270)
			(size 0.1524 0.1524)
			(layers "B.Cu" "B.Mask" "B.Paste")
			(net "P3V3_STBY")
			(options
				(clearance outline)
				(anchor circle)
			)
			(primitives
				(gr_poly
					(pts
						(arc
							(start 0.3048 0.2032)
							(mid 0.275042 0.275042)
							(end 0.2032 0.3048)
						)
						(arc
							(start -0.2032 0.3048)
							(mid -0.275042 0.275042)
							(end -0.3048 0.2032)
						)
						(arc
							(start -0.3048 -0.2032)
							(mid -0.275042 -0.275042)
							(end -0.2032 -0.3048)
						)
						(arc
							(start 0.2032 -0.3048)
							(mid 0.275042 -0.275042)
							(end 0.3048 -0.2032)
						)
					)
					(width 0)
					(fill yes)
				)
			)
		)
		(pad "2" smd custom
			(at 0 0.4445 270)
			(size 0.1524 0.1524)
			(layers "B.Cu" "B.Mask" "B.Paste")
			(net "GND")
			(options
				(clearance outline)
				(anchor circle)
			)
			(primitives
				(gr_poly
					(pts
						(arc
							(start 0.3048 0.2032)
							(mid 0.275042 0.275042)
							(end 0.2032 0.3048)
						)
						(arc
							(start -0.2032 0.3048)
							(mid -0.275042 0.275042)
							(end -0.3048 0.2032)
						)
						(arc
							(start -0.3048 -0.2032)
							(mid -0.275042 -0.275042)
							(end -0.2032 -0.3048)
						)
						(arc
							(start 0.2032 -0.3048)
							(mid 0.275042 -0.275042)
							(end 0.3048 -0.2032)
						)
					)
					(width 0)
					(fill yes)
				)
			)
		)
	)
	(footprint ""
		(layer "B.Cu")
		(at 50.086514 -161.261552)
		(property "Reference" "R323"
			(at 0 0 0)
			(layer "B.SilkS")
			(hide yes)
			(effects
				(font
					(size 1.27 1.27)
				)
				(justify mirror)
			)
		)
		(property "Value" "4K7R2F-GP"
			(at -0.064008 -3.993896 0)
			(unlocked yes)
			(layer "B.Fab")
			(hide yes)
			(effects
				(font
					(size 1.016 1.016)
					(thickness 0.1524)
				)
				(justify mirror)
			)
		)
		(property "Device Type" "R402H16"
			(at -0.064008 -5.517896 0)
			(unlocked yes)
			(layer "B.Fab")
			(hide yes)
			(effects
				(font
					(size 1.016 1.016)
					(thickness 0.1524)
				)
				(justify mirror)
			)
		)
		(duplicate_pad_numbers_are_jumpers no)
		(fp_line
			(start -0.508 -0.9398)
			(end 0.508 -0.9398)
			(stroke
				(width 0.1524)
				(type default)
			)
			(layer "B.SilkS")
		)
		(fp_line
			(start 0.508 -0.9398)
			(end 0.508 0.9398)
			(stroke
				(width 0.1524)
				(type default)
			)
			(layer "B.SilkS")
		)
		(fp_rect
			(start 0.508 0.9398)
			(end -0.508 -0.9398)
			(stroke
				(width 0)
				(type default)
			)
			(fill no)
			(layer "B.CrtYd")
		)
		(fp_rect
			(start 0.508 0.9398)
			(end -0.508 -0.9398)
			(stroke
				(width 0)
				(type default)
			)
			(fill no)
			(layer "B.Fab")
		)
		(pad "1" smd custom
			(at 0 -0.4445 180)
			(size 0.1397 0.1397)
			(layers "B.Cu" "B.Mask" "B.Paste")
			(net "GND")
			(options
				(clearance outline)
				(anchor circle)
			)
			(primitives
				(gr_poly
					(pts
						(arc
							(start -0.1778 0.2794)
							(mid -0.249642 0.249642)
							(end -0.2794 0.1778)
						)
						(arc
							(start -0.2794 -0.1778)
							(mid -0.249642 -0.249642)
							(end -0.1778 -0.2794)
						)
						(arc
							(start 0.1778 -0.2794)
							(mid 0.249642 -0.249642)
							(end 0.2794 -0.1778)
						)
						(arc
							(start 0.2794 0.1778)
							(mid 0.249642 0.249642)
							(end 0.1778 0.2794)
						)
					)
					(width 0)
					(fill yes)
				)
			)
		)
		(pad "2" smd custom
			(at 0 0.4445 180)
			(size 0.1397 0.1397)
			(layers "B.Cu" "B.Mask" "B.Paste")
			(net "BOARD_REV_1")
			(options
				(clearance outline)
				(anchor circle)
			)
			(primitives
				(gr_poly
					(pts
						(arc
							(start -0.1778 0.2794)
							(mid -0.249642 0.249642)
							(end -0.2794 0.1778)
						)
						(arc
							(start -0.2794 -0.1778)
							(mid -0.249642 -0.249642)
							(end -0.1778 -0.2794)
						)
						(arc
							(start 0.1778 -0.2794)
							(mid 0.249642 -0.249642)
							(end 0.2794 -0.1778)
						)
						(arc
							(start 0.2794 0.1778)
							(mid 0.249642 0.249642)
							(end 0.1778 0.2794)
						)
					)
					(width 0)
					(fill yes)
				)
			)
		)
	)
	(footprint ""
		(layer "B.Cu")
		(at 62.992 -143.7386 90)
		(property "Reference" "R196"
			(at 0 0 90)
			(layer "B.SilkS")
			(hide yes)
			(effects
				(font
					(size 1.27 1.27)
				)
				(justify mirror)
			)
		)
		(property "Value" "2K2R2F-GP"
			(at -0.064008 -3.993896 90)
			(unlocked yes)
			(layer "B.Fab")
			(hide yes)
			(effects
				(font
					(size 1.016 1.016)
					(thickness 0.1524)
				)
				(justify mirror)
			)
		)
		(property "Device Type" "R402H16"
			(at -0.064008 -5.517896 90)
			(unlocked yes)
			(layer "B.Fab")
			(hide yes)
			(effects
				(font
					(size 1.016 1.016)
					(thickness 0.1524)
				)
				(justify mirror)
			)
		)
		(duplicate_pad_numbers_are_jumpers no)
		(fp_line
			(start 0.508 -0.9398)
			(end 0.508 0.9398)
			(stroke
				(width 0.1524)
				(type default)
			)
			(layer "B.SilkS")
		)
		(fp_line
			(start -0.508 -0.9398)
			(end 0.508 -0.9398)
			(stroke
				(width 0.1524)
				(type default)
			)
			(layer "B.SilkS")
		)
		(fp_rect
			(start 0.508 0.9398)
			(end -0.508 -0.9398)
			(stroke
				(width 0)
				(type default)
			)
			(fill no)
			(layer "B.CrtYd")
		)
		(fp_rect
			(start 0.508 0.9398)
			(end -0.508 -0.9398)
			(stroke
				(width 0)
				(type default)
			)
			(fill no)
			(layer "B.Fab")
		)
		(pad "1" smd custom
			(at 0 -0.4445 270)
			(size 0.1397 0.1397)
			(layers "B.Cu" "B.Mask" "B.Paste")
			(net "I2C_EXP_LOC_SDA_OUT")
			(options
				(clearance outline)
				(anchor circle)
			)
			(primitives
				(gr_poly
					(pts
						(arc
							(start -0.1778 0.2794)
							(mid -0.249642 0.249642)
							(end -0.2794 0.1778)
						)
						(arc
							(start -0.2794 -0.1778)
							(mid -0.249642 -0.249642)
							(end -0.1778 -0.2794)
						)
						(arc
							(start 0.1778 -0.2794)
							(mid 0.249642 -0.249642)
							(end 0.2794 -0.1778)
						)
						(arc
							(start 0.2794 0.1778)
							(mid 0.249642 0.249642)
							(end 0.1778 0.2794)
						)
					)
					(width 0)
					(fill yes)
				)
			)
		)
		(pad "2" smd custom
			(at 0 0.4445 270)
			(size 0.1397 0.1397)
			(layers "B.Cu" "B.Mask" "B.Paste")
			(net "P3V3_STBY")
			(options
				(clearance outline)
				(anchor circle)
			)
			(primitives
				(gr_poly
					(pts
						(arc
							(start -0.1778 0.2794)
							(mid -0.249642 0.249642)
							(end -0.2794 0.1778)
						)
						(arc
							(start -0.2794 -0.1778)
							(mid -0.249642 -0.249642)
							(end -0.1778 -0.2794)
						)
						(arc
							(start 0.1778 -0.2794)
							(mid 0.249642 -0.249642)
							(end 0.2794 -0.1778)
						)
						(arc
							(start 0.2794 0.1778)
							(mid 0.249642 0.249642)
							(end 0.1778 0.2794)
						)
					)
					(width 0)
					(fill yes)
				)
			)
		)
	)
	(footprint ""
		(layer "B.Cu")
		(at 25.557226 -143.81099 180)
		(property "Reference" "C70"
			(at 0 0 0)
			(layer "B.SilkS")
			(hide yes)
			(effects
				(font
					(size 1.27 1.27)
				)
				(justify mirror)
			)
		)
		(property "Value" "SCD1U16V2KX-3GP"
			(at -1.1811 -2.7051 180)
			(unlocked yes)
			(layer "B.Fab")
			(hide yes)
			(effects
				(font
					(size 1.016 1.016)
					(thickness 0.1524)
				)
				(justify mirror)
			)
		)
		(property "Device Type" "C402H22"
			(at -1.1811 -4.2291 180)
			(unlocked yes)
			(layer "B.Fab")
			(hide yes)
			(effects
				(font
					(size 1.016 1.016)
					(thickness 0.1524)
				)
				(justify mirror)
			)
		)
		(duplicate_pad_numbers_are_jumpers no)
		(fp_rect
			(start 0.4318 0.9525)
			(end -0.4318 -0.9525)
			(stroke
				(width 0)
				(type default)
			)
			(fill no)
			(layer "B.CrtYd")
		)
		(fp_rect
			(start 0.4318 0.9525)
			(end -0.4318 -0.9525)
			(stroke
				(width 0)
				(type default)
			)
			(fill no)
			(layer "B.Fab")
		)
		(pad "1" smd custom
			(at 0 -0.4445)
			(size 0.1524 0.1524)
			(layers "B.Cu" "B.Mask" "B.Paste")
			(net "GND")
			(options
				(clearance outline)
				(anchor circle)
			)
			(primitives
				(gr_poly
					(pts
						(arc
							(start 0.3048 0.2032)
							(mid 0.275042 0.275042)
							(end 0.2032 0.3048)
						)
						(arc
							(start -0.2032 0.3048)
							(mid -0.275042 0.275042)
							(end -0.3048 0.2032)
						)
						(arc
							(start -0.3048 -0.2032)
							(mid -0.275042 -0.275042)
							(end -0.2032 -0.3048)
						)
						(arc
							(start 0.2032 -0.3048)
							(mid 0.275042 -0.275042)
							(end 0.3048 -0.2032)
						)
					)
					(width 0)
					(fill yes)
				)
			)
		)
		(pad "2" smd custom
			(at 0 0.4445)
			(size 0.1524 0.1524)
			(layers "B.Cu" "B.Mask" "B.Paste")
			(net "P1V2_STBY")
			(options
				(clearance outline)
				(anchor circle)
			)
			(primitives
				(gr_poly
					(pts
						(arc
							(start 0.3048 0.2032)
							(mid 0.275042 0.275042)
							(end 0.2032 0.3048)
						)
						(arc
							(start -0.2032 0.3048)
							(mid -0.275042 0.275042)
							(end -0.3048 0.2032)
						)
						(arc
							(start -0.3048 -0.2032)
							(mid -0.275042 -0.275042)
							(end -0.2032 -0.3048)
						)
						(arc
							(start 0.2032 -0.3048)
							(mid 0.275042 -0.275042)
							(end 0.3048 -0.2032)
						)
					)
					(width 0)
					(fill yes)
				)
			)
		)
	)
	(footprint ""
		(layer "B.Cu")
		(at 197.35546 -72.34428 90)
		(property "Reference" "C360"
			(at 0 0 90)
			(layer "B.SilkS")
			(hide yes)
			(effects
				(font
					(size 1.27 1.27)
				)
				(justify mirror)
			)
		)
		(property "Value" "SCD1U6D3V1KX-GP"
			(at 2.8321 -1.7399 90)
			(unlocked yes)
			(layer "B.Fab")
			(hide yes)
			(effects
				(font
					(size 1.016 1.016)
					(thickness 0.1524)
				)
				(justify mirror)
			)
		)
		(property "Device Type" "C0201H13"
			(at 2.8321 -3.2639 90)
			(unlocked yes)
			(layer "B.Fab")
			(hide yes)
			(effects
				(font
					(size 1.016 1.016)
					(thickness 0.1524)
				)
				(justify mirror)
			)
		)
		(duplicate_pad_numbers_are_jumpers no)
		(fp_rect
			(start 0.2794 0.6477)
			(end -0.2794 -0.6477)
			(stroke
				(width 0)
				(type default)
			)
			(fill no)
			(layer "B.CrtYd")
		)
		(fp_rect
			(start 0.2794 0.6477)
			(end -0.2794 -0.6477)
			(stroke
				(width 0)
				(type default)
			)
			(fill no)
			(layer "B.Fab")
		)
		(pad "1" smd custom
			(at 0 -0.2794 270)
			(size 0.0762 0.0762)
			(layers "B.Cu" "B.Mask" "B.Paste")
			(net "PCE_VDDH")
			(options
				(clearance outline)
				(anchor circle)
			)
			(primitives
				(gr_poly
					(pts
						(arc
							(start 0.1524 0.127)
							(mid 0.137521 0.162921)
							(end 0.1016 0.1778)
						)
						(arc
							(start -0.1016 0.1778)
							(mid -0.137521 0.162921)
							(end -0.1524 0.127)
						)
						(arc
							(start -0.1524 -0.127)
							(mid -0.137521 -0.162921)
							(end -0.1016 -0.1778)
						)
						(arc
							(start 0.1016 -0.1778)
							(mid 0.137521 -0.162921)
							(end 0.1524 -0.127)
						)
					)
					(width 0)
					(fill yes)
				)
			)
		)
		(pad "2" smd custom
			(at 0 0.2794 270)
			(size 0.0762 0.0762)
			(layers "B.Cu" "B.Mask" "B.Paste")
			(net "GND")
			(options
				(clearance outline)
				(anchor circle)
			)
			(primitives
				(gr_poly
					(pts
						(arc
							(start 0.1524 0.127)
							(mid 0.137521 0.162921)
							(end 0.1016 0.1778)
						)
						(arc
							(start -0.1016 0.1778)
							(mid -0.137521 0.162921)
							(end -0.1524 0.127)
						)
						(arc
							(start -0.1524 -0.127)
							(mid -0.137521 -0.162921)
							(end -0.1016 -0.1778)
						)
						(arc
							(start 0.1016 -0.1778)
							(mid 0.137521 -0.162921)
							(end 0.1524 -0.127)
						)
					)
					(width 0)
					(fill yes)
				)
			)
		)
	)
	(footprint ""
		(layer "B.Cu")
		(at 24.456898 -145.973546)
		(property "Reference" "C72"
			(at 0 0 0)
			(layer "B.SilkS")
			(hide yes)
			(effects
				(font
					(size 1.27 1.27)
				)
				(justify mirror)
			)
		)
		(property "Value" "SCD1U16V2KX-3GP"
			(at -1.1811 -2.7051 0)
			(unlocked yes)
			(layer "B.Fab")
			(hide yes)
			(effects
				(font
					(size 1.016 1.016)
					(thickness 0.1524)
				)
				(justify mirror)
			)
		)
		(property "Device Type" "C402H22"
			(at -1.1811 -4.2291 0)
			(unlocked yes)
			(layer "B.Fab")
			(hide yes)
			(effects
				(font
					(size 1.016 1.016)
					(thickness 0.1524)
				)
				(justify mirror)
			)
		)
		(duplicate_pad_numbers_are_jumpers no)
		(fp_rect
			(start 0.4318 0.9525)
			(end -0.4318 -0.9525)
			(stroke
				(width 0)
				(type default)
			)
			(fill no)
			(layer "B.CrtYd")
		)
		(fp_rect
			(start 0.4318 0.9525)
			(end -0.4318 -0.9525)
			(stroke
				(width 0)
				(type default)
			)
			(fill no)
			(layer "B.Fab")
		)
		(pad "1" smd custom
			(at 0 -0.4445 180)
			(size 0.1524 0.1524)
			(layers "B.Cu" "B.Mask" "B.Paste")
			(net "GND")
			(options
				(clearance outline)
				(anchor circle)
			)
			(primitives
				(gr_poly
					(pts
						(arc
							(start 0.3048 0.2032)
							(mid 0.275042 0.275042)
							(end 0.2032 0.3048)
						)
						(arc
							(start -0.2032 0.3048)
							(mid -0.275042 0.275042)
							(end -0.3048 0.2032)
						)
						(arc
							(start -0.3048 -0.2032)
							(mid -0.275042 -0.275042)
							(end -0.2032 -0.3048)
						)
						(arc
							(start 0.2032 -0.3048)
							(mid 0.275042 -0.275042)
							(end 0.3048 -0.2032)
						)
					)
					(width 0)
					(fill yes)
				)
			)
		)
		(pad "2" smd custom
			(at 0 0.4445 180)
			(size 0.1524 0.1524)
			(layers "B.Cu" "B.Mask" "B.Paste")
			(net "P1V2_STBY")
			(options
				(clearance outline)
				(anchor circle)
			)
			(primitives
				(gr_poly
					(pts
						(arc
							(start 0.3048 0.2032)
							(mid 0.275042 0.275042)
							(end 0.2032 0.3048)
						)
						(arc
							(start -0.2032 0.3048)
							(mid -0.275042 0.275042)
							(end -0.3048 0.2032)
						)
						(arc
							(start -0.3048 -0.2032)
							(mid -0.275042 -0.275042)
							(end -0.2032 -0.3048)
						)
						(arc
							(start 0.2032 -0.3048)
							(mid 0.275042 -0.275042)
							(end 0.3048 -0.2032)
						)
					)
					(width 0)
					(fill yes)
				)
			)
		)
	)
	(footprint ""
		(layer "B.Cu")
		(at 35.738308 -124.678694)
		(property "Reference" "R783"
			(at 0 0 0)
			(layer "B.SilkS")
			(hide yes)
			(effects
				(font
					(size 1.27 1.27)
				)
				(justify mirror)
			)
		)
		(property "Value" "10KR2F-2-GP"
			(at -0.064008 -3.993896 0)
			(unlocked yes)
			(layer "B.Fab")
			(hide yes)
			(effects
				(font
					(size 1.016 1.016)
					(thickness 0.1524)
				)
				(justify mirror)
			)
		)
		(property "Device Type" "R402H16"
			(at -0.064008 -5.517896 0)
			(unlocked yes)
			(layer "B.Fab")
			(hide yes)
			(effects
				(font
					(size 1.016 1.016)
					(thickness 0.1524)
				)
				(justify mirror)
			)
		)
		(duplicate_pad_numbers_are_jumpers no)
		(fp_line
			(start -0.508 -0.9398)
			(end 0.508 -0.9398)
			(stroke
				(width 0.1524)
				(type default)
			)
			(layer "B.SilkS")
		)
		(fp_line
			(start 0.508 -0.9398)
			(end 0.508 0.9398)
			(stroke
				(width 0.1524)
				(type default)
			)
			(layer "B.SilkS")
		)
		(fp_rect
			(start 0.508 0.9398)
			(end -0.508 -0.9398)
			(stroke
				(width 0)
				(type default)
			)
			(fill no)
			(layer "B.CrtYd")
		)
		(fp_rect
			(start 0.508 0.9398)
			(end -0.508 -0.9398)
			(stroke
				(width 0)
				(type default)
			)
			(fill no)
			(layer "B.Fab")
		)
		(pad "1" smd custom
			(at 0 -0.4445 180)
			(size 0.1397 0.1397)
			(layers "B.Cu" "B.Mask" "B.Paste")
			(net "P3V3_STBY")
			(options
				(clearance outline)
				(anchor circle)
			)
			(primitives
				(gr_poly
					(pts
						(arc
							(start -0.1778 0.2794)
							(mid -0.249642 0.249642)
							(end -0.2794 0.1778)
						)
						(arc
							(start -0.2794 -0.1778)
							(mid -0.249642 -0.249642)
							(end -0.1778 -0.2794)
						)
						(arc
							(start 0.1778 -0.2794)
							(mid 0.249642 -0.249642)
							(end 0.2794 -0.1778)
						)
						(arc
							(start 0.2794 0.1778)
							(mid 0.249642 0.249642)
							(end 0.1778 0.2794)
						)
					)
					(width 0)
					(fill yes)
				)
			)
		)
		(pad "2" smd custom
			(at 0 0.4445 180)
			(size 0.1397 0.1397)
			(layers "B.Cu" "B.Mask" "B.Paste")
			(net "SYS_RESET_N_OUT")
			(options
				(clearance outline)
				(anchor circle)
			)
			(primitives
				(gr_poly
					(pts
						(arc
							(start -0.1778 0.2794)
							(mid -0.249642 0.249642)
							(end -0.2794 0.1778)
						)
						(arc
							(start -0.2794 -0.1778)
							(mid -0.249642 -0.249642)
							(end -0.1778 -0.2794)
						)
						(arc
							(start 0.1778 -0.2794)
							(mid 0.249642 -0.249642)
							(end 0.2794 -0.1778)
						)
						(arc
							(start 0.2794 0.1778)
							(mid 0.249642 0.249642)
							(end 0.1778 0.2794)
						)
					)
					(width 0)
					(fill yes)
				)
			)
		)
	)
	(footprint ""
		(layer "B.Cu")
		(at 37.228018 -143.050514)
		(property "Reference" "C59"
			(at 0 0 0)
			(layer "B.SilkS")
			(hide yes)
			(effects
				(font
					(size 1.27 1.27)
				)
				(justify mirror)
			)
		)
		(property "Value" "SC1U16V3KX-5GP"
			(at 0 -2.8194 0)
			(unlocked yes)
			(layer "B.Fab")
			(hide yes)
			(effects
				(font
					(size 1.016 1.016)
					(thickness 0.1524)
				)
				(justify mirror)
			)
		)
		(property "Device Type" "C603H36"
			(at 0 -4.3434 0)
			(unlocked yes)
			(layer "B.Fab")
			(hide yes)
			(effects
				(font
					(size 1.016 1.016)
					(thickness 0.1524)
				)
				(justify mirror)
			)
		)
		(duplicate_pad_numbers_are_jumpers no)
		(fp_line
			(start -0.508 0)
			(end 0.508 0)
			(stroke
				(width 0.2032)
				(type default)
			)
			(layer "B.SilkS")
		)
		(fp_rect
			(start 0.5842 1.3335)
			(end -0.5842 -1.3335)
			(stroke
				(width 0)
				(type default)
			)
			(fill no)
			(layer "B.CrtYd")
		)
		(fp_rect
			(start 0.5842 1.3335)
			(end -0.5842 -1.3335)
			(stroke
				(width 0)
				(type default)
			)
			(fill no)
			(layer "B.Fab")
		)
		(pad "1" smd custom
			(at 0 -0.762 180)
			(size 0.2159 0.2159)
			(layers "B.Cu" "B.Mask" "B.Paste")
			(net "P1V2_STBY")
			(options
				(clearance outline)
				(anchor circle)
			)
			(primitives
				(gr_poly
					(pts
						(arc
							(start -0.3302 0.4318)
							(mid -0.402042 0.402042)
							(end -0.4318 0.3302)
						)
						(arc
							(start -0.4318 -0.3302)
							(mid -0.402042 -0.402042)
							(end -0.3302 -0.4318)
						)
						(arc
							(start 0.3302 -0.4318)
							(mid 0.402042 -0.402042)
							(end 0.4318 -0.3302)
						)
						(arc
							(start 0.4318 0.3302)
							(mid 0.402042 0.402042)
							(end 0.3302 0.4318)
						)
					)
					(width 0)
					(fill yes)
				)
			)
		)
		(pad "2" smd custom
			(at 0 0.762 180)
			(size 0.2159 0.2159)
			(layers "B.Cu" "B.Mask" "B.Paste")
			(net "GND")
			(options
				(clearance outline)
				(anchor circle)
			)
			(primitives
				(gr_poly
					(pts
						(arc
							(start -0.3302 0.4318)
							(mid -0.402042 0.402042)
							(end -0.4318 0.3302)
						)
						(arc
							(start -0.4318 -0.3302)
							(mid -0.402042 -0.402042)
							(end -0.3302 -0.4318)
						)
						(arc
							(start 0.3302 -0.4318)
							(mid 0.402042 -0.402042)
							(end 0.4318 -0.3302)
						)
						(arc
							(start 0.4318 0.3302)
							(mid 0.402042 0.402042)
							(end 0.3302 0.4318)
						)
					)
					(width 0)
					(fill yes)
				)
			)
		)
	)
	(footprint ""
		(layer "B.Cu")
		(at 197.5612 -53.0098 -90)
		(property "Reference" "C348"
			(at 0 0 90)
			(layer "B.SilkS")
			(hide yes)
			(effects
				(font
					(size 1.27 1.27)
				)
				(justify mirror)
			)
		)
		(property "Value" "SC1U6D3V1MX-GP"
			(at -1.9177 2.0193 270)
			(unlocked yes)
			(layer "B.Fab")
			(hide yes)
			(effects
				(font
					(size 1.016 1.016)
					(thickness 0.1524)
				)
				(justify mirror)
			)
		)
		(property "Device Type" "C0201H14"
			(at -1.9177 0.4953 270)
			(unlocked yes)
			(layer "B.Fab")
			(hide yes)
			(effects
				(font
					(size 1.016 1.016)
					(thickness 0.1524)
				)
				(justify mirror)
			)
		)
		(duplicate_pad_numbers_are_jumpers no)
		(fp_rect
			(start 0.1524 0.3048)
			(end -0.1524 -0.3048)
			(stroke
				(width 0)
				(type default)
			)
			(fill no)
			(layer "B.CrtYd")
		)
		(fp_poly
			(pts
				(xy 0.2794 0.6477) (xy 0.2794 -0.6477) (xy -0.2794 -0.6477) (xy -0.2794 -0.1905) (xy -0.1524 -0.1905)
				(xy -0.1524 -0.3048) (xy 0.1524 -0.3048) (xy 0.1524 0.3048) (xy -0.1524 0.3048) (xy -0.1524 -0.1778)
				(xy -0.2794 -0.1778) (xy -0.2794 0.6477)
			)
			(stroke
				(width 0)
				(type default)
			)
			(fill no)
			(layer "B.CrtYd")
		)
		(fp_rect
			(start 0.2794 0.6477)
			(end -0.2794 -0.6477)
			(stroke
				(width 0)
				(type default)
			)
			(fill no)
			(layer "B.Fab")
		)
		(pad "1" smd custom
			(at 0 -0.2794 90)
			(size 0.0762 0.0762)
			(layers "B.Cu" "B.Mask" "B.Paste")
			(net "VDDA_SAS_REF_CLK")
			(options
				(clearance outline)
				(anchor circle)
			)
			(primitives
				(gr_poly
					(pts
						(arc
							(start 0.1524 0.127)
							(mid 0.137521 0.162921)
							(end 0.1016 0.1778)
						)
						(arc
							(start -0.1016 0.1778)
							(mid -0.137521 0.162921)
							(end -0.1524 0.127)
						)
						(arc
							(start -0.1524 -0.127)
							(mid -0.137521 -0.162921)
							(end -0.1016 -0.1778)
						)
						(arc
							(start 0.1016 -0.1778)
							(mid 0.137521 -0.162921)
							(end 0.1524 -0.127)
						)
					)
					(width 0)
					(fill yes)
				)
			)
		)
		(pad "2" smd custom
			(at 0 0.2794 90)
			(size 0.0762 0.0762)
			(layers "B.Cu" "B.Mask" "B.Paste")
			(net "GND")
			(options
				(clearance outline)
				(anchor circle)
			)
			(primitives
				(gr_poly
					(pts
						(arc
							(start 0.1524 0.127)
							(mid 0.137521 0.162921)
							(end 0.1016 0.1778)
						)
						(arc
							(start -0.1016 0.1778)
							(mid -0.137521 0.162921)
							(end -0.1524 0.127)
						)
						(arc
							(start -0.1524 -0.127)
							(mid -0.137521 -0.162921)
							(end -0.1016 -0.1778)
						)
						(arc
							(start 0.1016 -0.1778)
							(mid 0.137521 -0.162921)
							(end 0.1524 -0.127)
						)
					)
					(width 0)
					(fill yes)
				)
			)
		)
	)
	(footprint ""
		(layer "B.Cu")
		(at 82.511392 -48.766476 -90)
		(property "Reference" "C25"
			(at 0 0 90)
			(layer "B.SilkS")
			(hide yes)
			(effects
				(font
					(size 1.27 1.27)
				)
				(justify mirror)
			)
		)
		(property "Value" "SC2D2U25V5KX-2-GP"
			(at 0.0762 -6.1214 270)
			(unlocked yes)
			(layer "B.Fab")
			(hide yes)
			(effects
				(font
					(size 1.016 1.016)
					(thickness 0.1524)
				)
				(justify mirror)
			)
		)
		(property "Device Type" "C805H54"
			(at 0.0762 -8.1534 270)
			(unlocked yes)
			(layer "B.Fab")
			(hide yes)
			(effects
				(font
					(size 1.016 1.016)
					(thickness 0.1524)
				)
				(justify mirror)
			)
		)
		(duplicate_pad_numbers_are_jumpers no)
		(fp_line
			(start -0.635 0)
			(end 0.635 0)
			(stroke
				(width 0.508)
				(type default)
			)
			(layer "B.SilkS")
		)
		(fp_rect
			(start 0.9652 1.778)
			(end -0.9652 -1.778)
			(stroke
				(width 0)
				(type default)
			)
			(fill no)
			(layer "B.CrtYd")
		)
		(fp_poly
			(pts
				(xy 0.9652 -1.778) (xy -0.9652 -1.778) (xy -0.9652 1.778) (xy 0.9652 1.778)
			)
			(stroke
				(width 0)
				(type default)
			)
			(fill no)
			(layer "B.Fab")
		)
		(pad "1" smd rect
			(at 0 -0.9652 90)
			(size 1.397 1.143)
			(layers "B.Cu" "B.Mask" "B.Paste")
			(net "P5V_STBY")
		)
		(pad "2" smd rect
			(at 0 0.9652 90)
			(size 1.397 1.143)
			(layers "B.Cu" "B.Mask" "B.Paste")
			(net "GND")
		)
	)
	(footprint ""
		(layer "B.Cu")
		(at 207.7974 -56.9468 180)
		(property "Reference" "R592"
			(at 0 0 0)
			(layer "B.SilkS")
			(hide yes)
			(effects
				(font
					(size 1.27 1.27)
				)
				(justify mirror)
			)
		)
		(property "Value" "2K2R2F-GP"
			(at -0.064008 -3.993896 180)
			(unlocked yes)
			(layer "B.Fab")
			(hide yes)
			(effects
				(font
					(size 1.016 1.016)
					(thickness 0.1524)
				)
				(justify mirror)
			)
		)
		(property "Device Type" "R402H16"
			(at -0.064008 -5.517896 180)
			(unlocked yes)
			(layer "B.Fab")
			(hide yes)
			(effects
				(font
					(size 1.016 1.016)
					(thickness 0.1524)
				)
				(justify mirror)
			)
		)
		(duplicate_pad_numbers_are_jumpers no)
		(fp_line
			(start 0.508 -0.9398)
			(end 0.508 0.9398)
			(stroke
				(width 0.1524)
				(type default)
			)
			(layer "B.SilkS")
		)
		(fp_line
			(start -0.508 -0.9398)
			(end 0.508 -0.9398)
			(stroke
				(width 0.1524)
				(type default)
			)
			(layer "B.SilkS")
		)
		(fp_rect
			(start 0.508 0.9398)
			(end -0.508 -0.9398)
			(stroke
				(width 0)
				(type default)
			)
			(fill no)
			(layer "B.CrtYd")
		)
		(fp_rect
			(start 0.508 0.9398)
			(end -0.508 -0.9398)
			(stroke
				(width 0)
				(type default)
			)
			(fill no)
			(layer "B.Fab")
		)
		(pad "1" smd custom
			(at 0 -0.4445)
			(size 0.1397 0.1397)
			(layers "B.Cu" "B.Mask" "B.Paste")
			(net "P1V8")
			(options
				(clearance outline)
				(anchor circle)
			)
			(primitives
				(gr_poly
					(pts
						(arc
							(start -0.1778 0.2794)
							(mid -0.249642 0.249642)
							(end -0.2794 0.1778)
						)
						(arc
							(start -0.2794 -0.1778)
							(mid -0.249642 -0.249642)
							(end -0.1778 -0.2794)
						)
						(arc
							(start 0.1778 -0.2794)
							(mid 0.249642 -0.249642)
							(end 0.2794 -0.1778)
						)
						(arc
							(start 0.2794 0.1778)
							(mid 0.249642 0.249642)
							(end 0.1778 0.2794)
						)
					)
					(width 0)
					(fill yes)
				)
			)
		)
		(pad "2" smd custom
			(at 0 0.4445)
			(size 0.1397 0.1397)
			(layers "B.Cu" "B.Mask" "B.Paste")
			(net "SIO_CLK_1")
			(options
				(clearance outline)
				(anchor circle)
			)
			(primitives
				(gr_poly
					(pts
						(arc
							(start -0.1778 0.2794)
							(mid -0.249642 0.249642)
							(end -0.2794 0.1778)
						)
						(arc
							(start -0.2794 -0.1778)
							(mid -0.249642 -0.249642)
							(end -0.1778 -0.2794)
						)
						(arc
							(start 0.1778 -0.2794)
							(mid 0.249642 -0.249642)
							(end 0.2794 -0.1778)
						)
						(arc
							(start 0.2794 0.1778)
							(mid 0.249642 0.249642)
							(end 0.1778 0.2794)
						)
					)
					(width 0)
					(fill yes)
				)
			)
		)
	)
	(footprint ""
		(layer "B.Cu")
		(at 184.13476 -63.4619 90)
		(property "Reference" "C476"
			(at 0 0 90)
			(layer "B.SilkS")
			(hide yes)
			(effects
				(font
					(size 1.27 1.27)
				)
				(justify mirror)
			)
		)
		(property "Value" "SC1KP50V2KX-1GP"
			(at -1.1811 -2.7051 90)
			(unlocked yes)
			(layer "B.Fab")
			(hide yes)
			(effects
				(font
					(size 1.016 1.016)
					(thickness 0.1524)
				)
				(justify mirror)
			)
		)
		(property "Device Type" "C402H22"
			(at -1.1811 -4.2291 90)
			(unlocked yes)
			(layer "B.Fab")
			(hide yes)
			(effects
				(font
					(size 1.016 1.016)
					(thickness 0.1524)
				)
				(justify mirror)
			)
		)
		(duplicate_pad_numbers_are_jumpers no)
		(fp_rect
			(start 0.4318 0.9525)
			(end -0.4318 -0.9525)
			(stroke
				(width 0)
				(type default)
			)
			(fill no)
			(layer "B.CrtYd")
		)
		(fp_rect
			(start 0.4318 0.9525)
			(end -0.4318 -0.9525)
			(stroke
				(width 0)
				(type default)
			)
			(fill no)
			(layer "B.Fab")
		)
		(pad "1" smd custom
			(at 0 -0.4445 270)
			(size 0.1524 0.1524)
			(layers "B.Cu" "B.Mask" "B.Paste")
			(net "P1V8")
			(options
				(clearance outline)
				(anchor circle)
			)
			(primitives
				(gr_poly
					(pts
						(arc
							(start 0.3048 0.2032)
							(mid 0.275042 0.275042)
							(end 0.2032 0.3048)
						)
						(arc
							(start -0.2032 0.3048)
							(mid -0.275042 0.275042)
							(end -0.3048 0.2032)
						)
						(arc
							(start -0.3048 -0.2032)
							(mid -0.275042 -0.275042)
							(end -0.2032 -0.3048)
						)
						(arc
							(start 0.2032 -0.3048)
							(mid 0.275042 -0.275042)
							(end 0.3048 -0.2032)
						)
					)
					(width 0)
					(fill yes)
				)
			)
		)
		(pad "2" smd custom
			(at 0 0.4445 270)
			(size 0.1524 0.1524)
			(layers "B.Cu" "B.Mask" "B.Paste")
			(net "GND")
			(options
				(clearance outline)
				(anchor circle)
			)
			(primitives
				(gr_poly
					(pts
						(arc
							(start 0.3048 0.2032)
							(mid 0.275042 0.275042)
							(end 0.2032 0.3048)
						)
						(arc
							(start -0.2032 0.3048)
							(mid -0.275042 0.275042)
							(end -0.3048 0.2032)
						)
						(arc
							(start -0.3048 -0.2032)
							(mid -0.275042 -0.275042)
							(end -0.2032 -0.3048)
						)
						(arc
							(start 0.2032 -0.3048)
							(mid 0.275042 -0.275042)
							(end 0.3048 -0.2032)
						)
					)
					(width 0)
					(fill yes)
				)
			)
		)
	)
	(footprint ""
		(layer "B.Cu")
		(at 44.061888 -119.876062 90)
		(property "Reference" "U27"
			(at 0 0 90)
			(layer "B.SilkS")
			(hide yes)
			(effects
				(font
					(size 1.27 1.27)
				)
				(justify mirror)
			)
		)
		(property "Value" "TMP75AIDGKR-GP"
			(at 0.1143 -9.1948 90)
			(unlocked yes)
			(layer "B.Fab")
			(hide yes)
			(effects
				(font
					(size 1.016 1.016)
					(thickness 0.1524)
				)
				(justify mirror)
			)
		)
		(property "Device Type" "MSOP8-1H44"
			(at 0.1143 -10.795 90)
			(unlocked yes)
			(layer "B.Fab")
			(hide yes)
			(effects
				(font
					(size 1.016 1.016)
					(thickness 0.1524)
				)
				(justify mirror)
			)
		)
		(duplicate_pad_numbers_are_jumpers no)
		(fp_line
			(start 1.9558 -1.016)
			(end 1.9558 1.016)
			(stroke
				(width 0.1524)
				(type default)
			)
			(layer "B.SilkS")
		)
		(fp_line
			(start -1.0795 -1.016)
			(end 1.9558 -1.016)
			(stroke
				(width 0.1524)
				(type default)
			)
			(layer "B.SilkS")
		)
		(fp_line
			(start 1.9558 -0.5461)
			(end 1.4478 -0.0381)
			(stroke
				(width 0.1524)
				(type default)
			)
			(layer "B.SilkS")
		)
		(fp_line
			(start 1.4478 -0.0381)
			(end 1.9558 0.4699)
			(stroke
				(width 0.1524)
				(type default)
			)
			(layer "B.SilkS")
		)
		(fp_line
			(start 1.9558 1.016)
			(end -1.0795 1.016)
			(stroke
				(width 0.1524)
				(type default)
			)
			(layer "B.SilkS")
		)
		(fp_line
			(start -1.0795 1.016)
			(end -1.0795 -1.016)
			(stroke
				(width 0.1524)
				(type default)
			)
			(layer "B.SilkS")
		)
		(fp_line
			(start 1.778 1.0922)
			(end 1.778 3.048)
			(stroke
				(width 0.508)
				(type default)
			)
			(layer "B.SilkS")
		)
		(fp_poly
			(pts
				(xy 1.1557 -1.016) (xy 1.1557 1.016) (xy -1.1557 1.016) (xy -1.1557 -1.016)
			)
			(stroke
				(width 0)
				(type default)
			)
			(fill yes)
			(layer "B.SilkS")
		)
		(fp_rect
			(start 1.4986 2.4511)
			(end -1.4986 -2.4511)
			(stroke
				(width 0)
				(type default)
			)
			(fill no)
			(layer "B.CrtYd")
		)
		(fp_poly
			(pts
				(xy 2.032 3.302) (xy 2.032 -3.302) (xy -2.032 -3.302) (xy -2.032 -2.1209) (xy -1.4986 -2.1209) (xy -1.4986 -2.4511)
				(xy 1.4986 -2.4511) (xy 1.4986 2.4511) (xy -1.4986 2.4511) (xy -1.4986 -2.1082) (xy -2.032 -2.1082)
				(xy -2.032 3.302)
			)
			(stroke
				(width 0)
				(type default)
			)
			(fill no)
			(layer "B.CrtYd")
		)
		(fp_rect
			(start 2.032 3.302)
			(end -2.032 -3.302)
			(stroke
				(width 0)
				(type default)
			)
			(fill no)
			(layer "B.Fab")
		)
		(pad "1" smd rect
			(at 0.97536 2.05486 270)
			(size 0.3556 1.524)
			(layers "B.Cu" "B.Mask" "B.Paste")
			(net "TEMP_3_SDA")
		)
		(pad "2" smd rect
			(at 0.32512 2.05486 270)
			(size 0.3556 1.524)
			(layers "B.Cu" "B.Mask" "B.Paste")
			(net "TEMP_3_SCL")
		)
		(pad "3" smd rect
			(at -0.32512 2.05486 270)
			(size 0.3556 1.524)
			(layers "B.Cu" "B.Mask" "B.Paste")
			(net "TEMP_3_ALERT")
		)
		(pad "4" smd rect
			(at -0.97536 2.05486 270)
			(size 0.3556 1.524)
			(layers "B.Cu" "B.Mask" "B.Paste")
			(net "GND")
		)
		(pad "5" smd rect
			(at -0.97536 -2.05486 270)
			(size 0.3556 1.524)
			(layers "B.Cu" "B.Mask" "B.Paste")
			(net "TEMP_3_A2")
		)
		(pad "6" smd rect
			(at -0.32512 -2.05486 270)
			(size 0.3556 1.524)
			(layers "B.Cu" "B.Mask" "B.Paste")
			(net "TEMP_3_A1")
		)
		(pad "7" smd rect
			(at 0.32512 -2.05486 270)
			(size 0.3556 1.524)
			(layers "B.Cu" "B.Mask" "B.Paste")
			(net "TEMP_3_A0")
		)
		(pad "8" smd rect
			(at 0.97536 -2.05486 270)
			(size 0.3556 1.524)
			(layers "B.Cu" "B.Mask" "B.Paste")
			(net "P3V3_STBY")
		)
	)
	(footprint ""
		(layer "B.Cu")
		(at 203.8731 -54.94782)
		(property "Reference" "C453"
			(at 0 0 0)
			(layer "B.SilkS")
			(hide yes)
			(effects
				(font
					(size 1.27 1.27)
				)
				(justify mirror)
			)
		)
		(property "Value" "SCD1U16V2KX-3GP"
			(at -1.1811 -2.7051 0)
			(unlocked yes)
			(layer "B.Fab")
			(hide yes)
			(effects
				(font
					(size 1.016 1.016)
					(thickness 0.1524)
				)
				(justify mirror)
			)
		)
		(property "Device Type" "C402H22"
			(at -1.1811 -4.2291 0)
			(unlocked yes)
			(layer "B.Fab")
			(hide yes)
			(effects
				(font
					(size 1.016 1.016)
					(thickness 0.1524)
				)
				(justify mirror)
			)
		)
		(duplicate_pad_numbers_are_jumpers no)
		(fp_rect
			(start 0.4318 0.9525)
			(end -0.4318 -0.9525)
			(stroke
				(width 0)
				(type default)
			)
			(fill no)
			(layer "B.CrtYd")
		)
		(fp_rect
			(start 0.4318 0.9525)
			(end -0.4318 -0.9525)
			(stroke
				(width 0)
				(type default)
			)
			(fill no)
			(layer "B.Fab")
		)
		(pad "1" smd custom
			(at 0 -0.4445 180)
			(size 0.1524 0.1524)
			(layers "B.Cu" "B.Mask" "B.Paste")
			(net "P1V8")
			(options
				(clearance outline)
				(anchor circle)
			)
			(primitives
				(gr_poly
					(pts
						(arc
							(start 0.3048 0.2032)
							(mid 0.275042 0.275042)
							(end 0.2032 0.3048)
						)
						(arc
							(start -0.2032 0.3048)
							(mid -0.275042 0.275042)
							(end -0.3048 0.2032)
						)
						(arc
							(start -0.3048 -0.2032)
							(mid -0.275042 -0.275042)
							(end -0.2032 -0.3048)
						)
						(arc
							(start 0.2032 -0.3048)
							(mid 0.275042 -0.275042)
							(end 0.3048 -0.2032)
						)
					)
					(width 0)
					(fill yes)
				)
			)
		)
		(pad "2" smd custom
			(at 0 0.4445 180)
			(size 0.1524 0.1524)
			(layers "B.Cu" "B.Mask" "B.Paste")
			(net "GND")
			(options
				(clearance outline)
				(anchor circle)
			)
			(primitives
				(gr_poly
					(pts
						(arc
							(start 0.3048 0.2032)
							(mid 0.275042 0.275042)
							(end 0.2032 0.3048)
						)
						(arc
							(start -0.2032 0.3048)
							(mid -0.275042 0.275042)
							(end -0.3048 0.2032)
						)
						(arc
							(start -0.3048 -0.2032)
							(mid -0.275042 -0.275042)
							(end -0.2032 -0.3048)
						)
						(arc
							(start 0.2032 -0.3048)
							(mid 0.275042 -0.275042)
							(end 0.3048 -0.2032)
						)
					)
					(width 0)
					(fill yes)
				)
			)
		)
	)
	(footprint ""
		(layer "B.Cu")
		(at 208.3054 -64.1604)
		(property "Reference" "TP113"
			(at 0 0 0)
			(layer "B.SilkS")
			(hide yes)
			(effects
				(font
					(size 1.27 1.27)
				)
				(justify mirror)
			)
		)
		(property "Value" "TPAD28-2-GP"
			(at 0.0127 -1.6637 0)
			(unlocked yes)
			(layer "B.Fab")
			(hide yes)
			(effects
				(font
					(size 1.016 1.016)
					(thickness 0.1524)
				)
				(justify mirror)
			)
		)
		(property "Device Type" "TPAD28"
			(at 0.0127 -3.1877 0)
			(unlocked yes)
			(layer "B.Fab")
			(hide yes)
			(effects
				(font
					(size 1.016 1.016)
					(thickness 0.1524)
				)
				(justify mirror)
			)
		)
		(duplicate_pad_numbers_are_jumpers no)
		(fp_poly
			(pts
				(arc
					(start 0.3556 0)
					(mid -0.3556 0)
					(end 0.3556 0)
				)
			)
			(stroke
				(width 0)
				(type default)
			)
			(fill no)
			(layer "B.CrtYd")
		)
		(fp_poly
			(pts
				(arc
					(start 0.6096 0)
					(mid -0.6096 0)
					(end 0.6096 0)
				)
			)
			(stroke
				(width 0)
				(type default)
			)
			(fill no)
			(layer "B.Fab")
		)
		(pad "1" smd circle
			(at 0 0 180)
			(size 0.7112 0.7112)
			(layers "B.Cu" "B.Mask" "B.Paste")
			(net "SIO_DIN_0")
		)
	)
	(footprint ""
		(layer "B.Cu")
		(at 61.0108 -139.8016 90)
		(property "Reference" "R273"
			(at 0 0 90)
			(layer "B.SilkS")
			(hide yes)
			(effects
				(font
					(size 1.27 1.27)
				)
				(justify mirror)
			)
		)
		(property "Value" "4K7R2F-GP"
			(at -0.064008 -3.993896 90)
			(unlocked yes)
			(layer "B.Fab")
			(hide yes)
			(effects
				(font
					(size 1.016 1.016)
					(thickness 0.1524)
				)
				(justify mirror)
			)
		)
		(property "Device Type" "R402H16"
			(at -0.064008 -5.517896 90)
			(unlocked yes)
			(layer "B.Fab")
			(hide yes)
			(effects
				(font
					(size 1.016 1.016)
					(thickness 0.1524)
				)
				(justify mirror)
			)
		)
		(duplicate_pad_numbers_are_jumpers no)
		(fp_line
			(start 0.508 -0.9398)
			(end 0.508 0.9398)
			(stroke
				(width 0.1524)
				(type default)
			)
			(layer "B.SilkS")
		)
		(fp_line
			(start -0.508 -0.9398)
			(end 0.508 -0.9398)
			(stroke
				(width 0.1524)
				(type default)
			)
			(layer "B.SilkS")
		)
		(fp_rect
			(start 0.508 0.9398)
			(end -0.508 -0.9398)
			(stroke
				(width 0)
				(type default)
			)
			(fill no)
			(layer "B.CrtYd")
		)
		(fp_rect
			(start 0.508 0.9398)
			(end -0.508 -0.9398)
			(stroke
				(width 0)
				(type default)
			)
			(fill no)
			(layer "B.Fab")
		)
		(pad "1" smd custom
			(at 0 -0.4445 270)
			(size 0.1397 0.1397)
			(layers "B.Cu" "B.Mask" "B.Paste")
			(net "SYS_PWR_LED")
			(options
				(clearance outline)
				(anchor circle)
			)
			(primitives
				(gr_poly
					(pts
						(arc
							(start -0.1778 0.2794)
							(mid -0.249642 0.249642)
							(end -0.2794 0.1778)
						)
						(arc
							(start -0.2794 -0.1778)
							(mid -0.249642 -0.249642)
							(end -0.1778 -0.2794)
						)
						(arc
							(start 0.1778 -0.2794)
							(mid 0.249642 -0.249642)
							(end 0.2794 -0.1778)
						)
						(arc
							(start 0.2794 0.1778)
							(mid 0.249642 0.249642)
							(end 0.1778 0.2794)
						)
					)
					(width 0)
					(fill yes)
				)
			)
		)
		(pad "2" smd custom
			(at 0 0.4445 270)
			(size 0.1397 0.1397)
			(layers "B.Cu" "B.Mask" "B.Paste")
			(net "GND")
			(options
				(clearance outline)
				(anchor circle)
			)
			(primitives
				(gr_poly
					(pts
						(arc
							(start -0.1778 0.2794)
							(mid -0.249642 0.249642)
							(end -0.2794 0.1778)
						)
						(arc
							(start -0.2794 -0.1778)
							(mid -0.249642 -0.249642)
							(end -0.1778 -0.2794)
						)
						(arc
							(start 0.1778 -0.2794)
							(mid 0.249642 -0.249642)
							(end 0.2794 -0.1778)
						)
						(arc
							(start 0.2794 0.1778)
							(mid 0.249642 0.249642)
							(end 0.1778 0.2794)
						)
					)
					(width 0)
					(fill yes)
				)
			)
		)
	)
	(footprint ""
		(layer "B.Cu")
		(at 188.548518 -81.153 180)
		(property "Reference" "C303"
			(at 0 0 0)
			(layer "B.SilkS")
			(hide yes)
			(effects
				(font
					(size 1.27 1.27)
				)
				(justify mirror)
			)
		)
		(property "Value" "SCD22U10V1KX-GP"
			(at 2.8321 -1.7399 180)
			(unlocked yes)
			(layer "B.Fab")
			(hide yes)
			(effects
				(font
					(size 1.016 1.016)
					(thickness 0.1524)
				)
				(justify mirror)
			)
		)
		(property "Device Type" "C0201H13"
			(at 2.8321 -3.2639 180)
			(unlocked yes)
			(layer "B.Fab")
			(hide yes)
			(effects
				(font
					(size 1.016 1.016)
					(thickness 0.1524)
				)
				(justify mirror)
			)
		)
		(duplicate_pad_numbers_are_jumpers no)
		(fp_rect
			(start 0.2794 0.6477)
			(end -0.2794 -0.6477)
			(stroke
				(width 0)
				(type default)
			)
			(fill no)
			(layer "B.CrtYd")
		)
		(fp_rect
			(start 0.2794 0.6477)
			(end -0.2794 -0.6477)
			(stroke
				(width 0)
				(type default)
			)
			(fill no)
			(layer "B.Fab")
		)
		(pad "1" smd custom
			(at 0 -0.2794)
			(size 0.0762 0.0762)
			(layers "B.Cu" "B.Mask" "B.Paste")
			(net "PCIE_IOM_TO_COMP_15_DP_C")
			(options
				(clearance outline)
				(anchor circle)
			)
			(primitives
				(gr_poly
					(pts
						(arc
							(start 0.1524 0.127)
							(mid 0.137521 0.162921)
							(end 0.1016 0.1778)
						)
						(arc
							(start -0.1016 0.1778)
							(mid -0.137521 0.162921)
							(end -0.1524 0.127)
						)
						(arc
							(start -0.1524 -0.127)
							(mid -0.137521 -0.162921)
							(end -0.1016 -0.1778)
						)
						(arc
							(start 0.1016 -0.1778)
							(mid 0.137521 -0.162921)
							(end 0.1524 -0.127)
						)
					)
					(width 0)
					(fill yes)
				)
			)
		)
		(pad "2" smd custom
			(at 0 0.2794)
			(size 0.0762 0.0762)
			(layers "B.Cu" "B.Mask" "B.Paste")
			(net "PCIE_IOM_TO_COMP_15_DP")
			(options
				(clearance outline)
				(anchor circle)
			)
			(primitives
				(gr_poly
					(pts
						(arc
							(start 0.1524 0.127)
							(mid 0.137521 0.162921)
							(end 0.1016 0.1778)
						)
						(arc
							(start -0.1016 0.1778)
							(mid -0.137521 0.162921)
							(end -0.1524 0.127)
						)
						(arc
							(start -0.1524 -0.127)
							(mid -0.137521 -0.162921)
							(end -0.1016 -0.1778)
						)
						(arc
							(start 0.1016 -0.1778)
							(mid 0.137521 -0.162921)
							(end 0.1524 -0.127)
						)
					)
					(width 0)
					(fill yes)
				)
			)
		)
	)
	(footprint ""
		(layer "B.Cu")
		(at 62.75578 -158.22676 180)
		(property "Reference" "C81"
			(at 0 0 0)
			(layer "B.SilkS")
			(hide yes)
			(effects
				(font
					(size 1.27 1.27)
				)
				(justify mirror)
			)
		)
		(property "Value" "SC4D7U25V5KX-1-GP"
			(at 0.0762 -6.1214 180)
			(unlocked yes)
			(layer "B.Fab")
			(hide yes)
			(effects
				(font
					(size 1.016 1.016)
					(thickness 0.1524)
				)
				(justify mirror)
			)
		)
		(property "Device Type" "C805H58"
			(at 0.0762 -8.1534 180)
			(unlocked yes)
			(layer "B.Fab")
			(hide yes)
			(effects
				(font
					(size 1.016 1.016)
					(thickness 0.1524)
				)
				(justify mirror)
			)
		)
		(duplicate_pad_numbers_are_jumpers no)
		(fp_line
			(start -0.635 0)
			(end 0.635 0)
			(stroke
				(width 0.508)
				(type default)
			)
			(layer "B.SilkS")
		)
		(fp_rect
			(start 0.9652 1.778)
			(end -0.9652 -1.778)
			(stroke
				(width 0)
				(type default)
			)
			(fill no)
			(layer "B.CrtYd")
		)
		(fp_poly
			(pts
				(xy 0.9652 -1.778) (xy -0.9652 -1.778) (xy -0.9652 1.778) (xy 0.9652 1.778)
			)
			(stroke
				(width 0)
				(type default)
			)
			(fill no)
			(layer "B.Fab")
		)
		(pad "1" smd rect
			(at 0 -0.9652)
			(size 1.397 1.143)
			(layers "B.Cu" "B.Mask" "B.Paste")
			(net "P3V3_STBY")
		)
		(pad "2" smd rect
			(at 0 0.9652)
			(size 1.397 1.143)
			(layers "B.Cu" "B.Mask" "B.Paste")
			(net "GND")
		)
	)
	(footprint ""
		(layer "B.Cu")
		(at 57.365392 -147.743164 90)
		(property "Reference" "R365"
			(at 0 0 90)
			(layer "B.SilkS")
			(hide yes)
			(effects
				(font
					(size 1.27 1.27)
				)
				(justify mirror)
			)
		)
		(property "Value" "4K7R2F-GP"
			(at -0.064008 -3.993896 90)
			(unlocked yes)
			(layer "B.Fab")
			(hide yes)
			(effects
				(font
					(size 1.016 1.016)
					(thickness 0.1524)
				)
				(justify mirror)
			)
		)
		(property "Device Type" "R402H16"
			(at -0.064008 -5.517896 90)
			(unlocked yes)
			(layer "B.Fab")
			(hide yes)
			(effects
				(font
					(size 1.016 1.016)
					(thickness 0.1524)
				)
				(justify mirror)
			)
		)
		(duplicate_pad_numbers_are_jumpers no)
		(fp_line
			(start 0.508 -0.9398)
			(end 0.508 0.9398)
			(stroke
				(width 0.1524)
				(type default)
			)
			(layer "B.SilkS")
		)
		(fp_line
			(start -0.508 -0.9398)
			(end 0.508 -0.9398)
			(stroke
				(width 0.1524)
				(type default)
			)
			(layer "B.SilkS")
		)
		(fp_rect
			(start 0.508 0.9398)
			(end -0.508 -0.9398)
			(stroke
				(width 0)
				(type default)
			)
			(fill no)
			(layer "B.CrtYd")
		)
		(fp_rect
			(start 0.508 0.9398)
			(end -0.508 -0.9398)
			(stroke
				(width 0)
				(type default)
			)
			(fill no)
			(layer "B.Fab")
		)
		(pad "1" smd custom
			(at 0 -0.4445 270)
			(size 0.1397 0.1397)
			(layers "B.Cu" "B.Mask" "B.Paste")
			(net "BMC0_JTAG_RTCK")
			(options
				(clearance outline)
				(anchor circle)
			)
			(primitives
				(gr_poly
					(pts
						(arc
							(start -0.1778 0.2794)
							(mid -0.249642 0.249642)
							(end -0.2794 0.1778)
						)
						(arc
							(start -0.2794 -0.1778)
							(mid -0.249642 -0.249642)
							(end -0.1778 -0.2794)
						)
						(arc
							(start 0.1778 -0.2794)
							(mid 0.249642 -0.249642)
							(end 0.2794 -0.1778)
						)
						(arc
							(start 0.2794 0.1778)
							(mid 0.249642 0.249642)
							(end 0.1778 0.2794)
						)
					)
					(width 0)
					(fill yes)
				)
			)
		)
		(pad "2" smd custom
			(at 0 0.4445 270)
			(size 0.1397 0.1397)
			(layers "B.Cu" "B.Mask" "B.Paste")
			(net "GND")
			(options
				(clearance outline)
				(anchor circle)
			)
			(primitives
				(gr_poly
					(pts
						(arc
							(start -0.1778 0.2794)
							(mid -0.249642 0.249642)
							(end -0.2794 0.1778)
						)
						(arc
							(start -0.2794 -0.1778)
							(mid -0.249642 -0.249642)
							(end -0.1778 -0.2794)
						)
						(arc
							(start 0.1778 -0.2794)
							(mid 0.249642 -0.249642)
							(end 0.2794 -0.1778)
						)
						(arc
							(start 0.2794 0.1778)
							(mid 0.249642 0.249642)
							(end 0.1778 0.2794)
						)
					)
					(width 0)
					(fill yes)
				)
			)
		)
	)
	(footprint ""
		(layer "B.Cu")
		(at 180.2511 -63.3476)
		(property "Reference" "TP123"
			(at 0 0 0)
			(layer "B.SilkS")
			(hide yes)
			(effects
				(font
					(size 1.27 1.27)
				)
				(justify mirror)
			)
		)
		(property "Value" "TPAD28-2-GP"
			(at 0.0127 -1.6637 0)
			(unlocked yes)
			(layer "B.Fab")
			(hide yes)
			(effects
				(font
					(size 1.016 1.016)
					(thickness 0.1524)
				)
				(justify mirror)
			)
		)
		(property "Device Type" "TPAD28"
			(at 0.0127 -3.1877 0)
			(unlocked yes)
			(layer "B.Fab")
			(hide yes)
			(effects
				(font
					(size 1.016 1.016)
					(thickness 0.1524)
				)
				(justify mirror)
			)
		)
		(duplicate_pad_numbers_are_jumpers no)
		(fp_poly
			(pts
				(arc
					(start 0.3556 0)
					(mid -0.3556 0)
					(end 0.3556 0)
				)
			)
			(stroke
				(width 0)
				(type default)
			)
			(fill no)
			(layer "B.CrtYd")
		)
		(fp_poly
			(pts
				(arc
					(start 0.6096 0)
					(mid -0.6096 0)
					(end 0.6096 0)
				)
			)
			(stroke
				(width 0)
				(type default)
			)
			(fill no)
			(layer "B.Fab")
		)
		(pad "1" smd circle
			(at 0 0 180)
			(size 0.7112 0.7112)
			(layers "B.Cu" "B.Mask" "B.Paste")
			(net "IOC_GPIO_32")
		)
	)
	(footprint ""
		(layer "B.Cu")
		(at 19.870674 -143.306546 180)
		(property "Reference" "C66"
			(at 0 0 0)
			(layer "B.SilkS")
			(hide yes)
			(effects
				(font
					(size 1.27 1.27)
				)
				(justify mirror)
			)
		)
		(property "Value" "SCD1U16V2KX-3GP"
			(at -1.1811 -2.7051 180)
			(unlocked yes)
			(layer "B.Fab")
			(hide yes)
			(effects
				(font
					(size 1.016 1.016)
					(thickness 0.1524)
				)
				(justify mirror)
			)
		)
		(property "Device Type" "C402H22"
			(at -1.1811 -4.2291 180)
			(unlocked yes)
			(layer "B.Fab")
			(hide yes)
			(effects
				(font
					(size 1.016 1.016)
					(thickness 0.1524)
				)
				(justify mirror)
			)
		)
		(duplicate_pad_numbers_are_jumpers no)
		(fp_rect
			(start 0.4318 0.9525)
			(end -0.4318 -0.9525)
			(stroke
				(width 0)
				(type default)
			)
			(fill no)
			(layer "B.CrtYd")
		)
		(fp_rect
			(start 0.4318 0.9525)
			(end -0.4318 -0.9525)
			(stroke
				(width 0)
				(type default)
			)
			(fill no)
			(layer "B.Fab")
		)
		(pad "1" smd custom
			(at 0 -0.4445)
			(size 0.1524 0.1524)
			(layers "B.Cu" "B.Mask" "B.Paste")
			(net "MEMCK_TER")
			(options
				(clearance outline)
				(anchor circle)
			)
			(primitives
				(gr_poly
					(pts
						(arc
							(start 0.3048 0.2032)
							(mid 0.275042 0.275042)
							(end 0.2032 0.3048)
						)
						(arc
							(start -0.2032 0.3048)
							(mid -0.275042 0.275042)
							(end -0.3048 0.2032)
						)
						(arc
							(start -0.3048 -0.2032)
							(mid -0.275042 -0.275042)
							(end -0.2032 -0.3048)
						)
						(arc
							(start 0.2032 -0.3048)
							(mid 0.275042 -0.275042)
							(end 0.3048 -0.2032)
						)
					)
					(width 0)
					(fill yes)
				)
			)
		)
		(pad "2" smd custom
			(at 0 0.4445)
			(size 0.1524 0.1524)
			(layers "B.Cu" "B.Mask" "B.Paste")
			(net "GND")
			(options
				(clearance outline)
				(anchor circle)
			)
			(primitives
				(gr_poly
					(pts
						(arc
							(start 0.3048 0.2032)
							(mid 0.275042 0.275042)
							(end 0.2032 0.3048)
						)
						(arc
							(start -0.2032 0.3048)
							(mid -0.275042 0.275042)
							(end -0.3048 0.2032)
						)
						(arc
							(start -0.3048 -0.2032)
							(mid -0.275042 -0.275042)
							(end -0.2032 -0.3048)
						)
						(arc
							(start 0.2032 -0.3048)
							(mid 0.275042 -0.275042)
							(end 0.3048 -0.2032)
						)
					)
					(width 0)
					(fill yes)
				)
			)
		)
	)
	(footprint ""
		(layer "B.Cu")
		(at 20.376896 -141.833092 -90)
		(property "Reference" "R205"
			(at 0 0 90)
			(layer "B.SilkS")
			(hide yes)
			(effects
				(font
					(size 1.27 1.27)
				)
				(justify mirror)
			)
		)
		(property "Value" "60D4R2F-GP"
			(at -0.064008 -3.993896 270)
			(unlocked yes)
			(layer "B.Fab")
			(hide yes)
			(effects
				(font
					(size 1.016 1.016)
					(thickness 0.1524)
				)
				(justify mirror)
			)
		)
		(property "Device Type" "R402H16"
			(at -0.064008 -5.517896 270)
			(unlocked yes)
			(layer "B.Fab")
			(hide yes)
			(effects
				(font
					(size 1.016 1.016)
					(thickness 0.1524)
				)
				(justify mirror)
			)
		)
		(duplicate_pad_numbers_are_jumpers no)
		(fp_line
			(start -0.508 -0.9398)
			(end 0.508 -0.9398)
			(stroke
				(width 0.1524)
				(type default)
			)
			(layer "B.SilkS")
		)
		(fp_line
			(start 0.508 -0.9398)
			(end 0.508 0.9398)
			(stroke
				(width 0.1524)
				(type default)
			)
			(layer "B.SilkS")
		)
		(fp_rect
			(start 0.508 0.9398)
			(end -0.508 -0.9398)
			(stroke
				(width 0)
				(type default)
			)
			(fill no)
			(layer "B.CrtYd")
		)
		(fp_rect
			(start 0.508 0.9398)
			(end -0.508 -0.9398)
			(stroke
				(width 0)
				(type default)
			)
			(fill no)
			(layer "B.Fab")
		)
		(pad "1" smd custom
			(at 0 -0.4445 90)
			(size 0.1397 0.1397)
			(layers "B.Cu" "B.Mask" "B.Paste")
			(net "MEMCK_P")
			(options
				(clearance outline)
				(anchor circle)
			)
			(primitives
				(gr_poly
					(pts
						(arc
							(start -0.1778 0.2794)
							(mid -0.249642 0.249642)
							(end -0.2794 0.1778)
						)
						(arc
							(start -0.2794 -0.1778)
							(mid -0.249642 -0.249642)
							(end -0.1778 -0.2794)
						)
						(arc
							(start 0.1778 -0.2794)
							(mid 0.249642 -0.249642)
							(end 0.2794 -0.1778)
						)
						(arc
							(start 0.2794 0.1778)
							(mid 0.249642 0.249642)
							(end 0.1778 0.2794)
						)
					)
					(width 0)
					(fill yes)
				)
			)
		)
		(pad "2" smd custom
			(at 0 0.4445 90)
			(size 0.1397 0.1397)
			(layers "B.Cu" "B.Mask" "B.Paste")
			(net "MEMCK_TER")
			(options
				(clearance outline)
				(anchor circle)
			)
			(primitives
				(gr_poly
					(pts
						(arc
							(start -0.1778 0.2794)
							(mid -0.249642 0.249642)
							(end -0.2794 0.1778)
						)
						(arc
							(start -0.2794 -0.1778)
							(mid -0.249642 -0.249642)
							(end -0.1778 -0.2794)
						)
						(arc
							(start 0.1778 -0.2794)
							(mid 0.249642 -0.249642)
							(end 0.2794 -0.1778)
						)
						(arc
							(start 0.2794 0.1778)
							(mid 0.249642 0.249642)
							(end 0.1778 0.2794)
						)
					)
					(width 0)
					(fill yes)
				)
			)
		)
	)
	(footprint ""
		(layer "B.Cu")
		(at 39.544752 -132.622036 -90)
		(property "Reference" "R612"
			(at 0 0 90)
			(layer "B.SilkS")
			(hide yes)
			(effects
				(font
					(size 1.27 1.27)
				)
				(justify mirror)
			)
		)
		(property "Value" "4K7R2F-GP"
			(at -0.064008 -3.993896 270)
			(unlocked yes)
			(layer "B.Fab")
			(hide yes)
			(effects
				(font
					(size 1.016 1.016)
					(thickness 0.1524)
				)
				(justify mirror)
			)
		)
		(property "Device Type" "R402H16"
			(at -0.064008 -5.517896 270)
			(unlocked yes)
			(layer "B.Fab")
			(hide yes)
			(effects
				(font
					(size 1.016 1.016)
					(thickness 0.1524)
				)
				(justify mirror)
			)
		)
		(duplicate_pad_numbers_are_jumpers no)
		(fp_line
			(start -0.508 -0.9398)
			(end 0.508 -0.9398)
			(stroke
				(width 0.1524)
				(type default)
			)
			(layer "B.SilkS")
		)
		(fp_line
			(start 0.508 -0.9398)
			(end 0.508 0.9398)
			(stroke
				(width 0.1524)
				(type default)
			)
			(layer "B.SilkS")
		)
		(fp_rect
			(start 0.508 0.9398)
			(end -0.508 -0.9398)
			(stroke
				(width 0)
				(type default)
			)
			(fill no)
			(layer "B.CrtYd")
		)
		(fp_rect
			(start 0.508 0.9398)
			(end -0.508 -0.9398)
			(stroke
				(width 0)
				(type default)
			)
			(fill no)
			(layer "B.Fab")
		)
		(pad "1" smd custom
			(at 0 -0.4445 90)
			(size 0.1397 0.1397)
			(layers "B.Cu" "B.Mask" "B.Paste")
			(net "P3V3_STBY")
			(options
				(clearance outline)
				(anchor circle)
			)
			(primitives
				(gr_poly
					(pts
						(arc
							(start -0.1778 0.2794)
							(mid -0.249642 0.249642)
							(end -0.2794 0.1778)
						)
						(arc
							(start -0.2794 -0.1778)
							(mid -0.249642 -0.249642)
							(end -0.1778 -0.2794)
						)
						(arc
							(start 0.1778 -0.2794)
							(mid 0.249642 -0.249642)
							(end 0.2794 -0.1778)
						)
						(arc
							(start 0.2794 0.1778)
							(mid 0.249642 0.249642)
							(end 0.1778 0.2794)
						)
					)
					(width 0)
					(fill yes)
				)
			)
		)
		(pad "2" smd custom
			(at 0 0.4445 90)
			(size 0.1397 0.1397)
			(layers "B.Cu" "B.Mask" "B.Paste")
			(net "BMC_ML_PWR_BLUE_LED")
			(options
				(clearance outline)
				(anchor circle)
			)
			(primitives
				(gr_poly
					(pts
						(arc
							(start -0.1778 0.2794)
							(mid -0.249642 0.249642)
							(end -0.2794 0.1778)
						)
						(arc
							(start -0.2794 -0.1778)
							(mid -0.249642 -0.249642)
							(end -0.1778 -0.2794)
						)
						(arc
							(start 0.1778 -0.2794)
							(mid 0.249642 -0.249642)
							(end 0.2794 -0.1778)
						)
						(arc
							(start 0.2794 0.1778)
							(mid 0.249642 0.249642)
							(end 0.1778 0.2794)
						)
					)
					(width 0)
					(fill yes)
				)
			)
		)
	)
	(footprint ""
		(layer "B.Cu")
		(at 10.1854 -142.4686 90)
		(property "Reference" "R211"
			(at 0 0 90)
			(layer "B.SilkS")
			(hide yes)
			(effects
				(font
					(size 1.27 1.27)
				)
				(justify mirror)
			)
		)
		(property "Value" "120R2F-GP"
			(at -0.064008 -3.993896 90)
			(unlocked yes)
			(layer "B.Fab")
			(hide yes)
			(effects
				(font
					(size 1.016 1.016)
					(thickness 0.1524)
				)
				(justify mirror)
			)
		)
		(property "Device Type" "R402H16"
			(at -0.064008 -5.517896 90)
			(unlocked yes)
			(layer "B.Fab")
			(hide yes)
			(effects
				(font
					(size 1.016 1.016)
					(thickness 0.1524)
				)
				(justify mirror)
			)
		)
		(duplicate_pad_numbers_are_jumpers no)
		(fp_line
			(start 0.508 -0.9398)
			(end 0.508 0.9398)
			(stroke
				(width 0.1524)
				(type default)
			)
			(layer "B.SilkS")
		)
		(fp_line
			(start -0.508 -0.9398)
			(end 0.508 -0.9398)
			(stroke
				(width 0.1524)
				(type default)
			)
			(layer "B.SilkS")
		)
		(fp_rect
			(start 0.508 0.9398)
			(end -0.508 -0.9398)
			(stroke
				(width 0)
				(type default)
			)
			(fill no)
			(layer "B.CrtYd")
		)
		(fp_rect
			(start 0.508 0.9398)
			(end -0.508 -0.9398)
			(stroke
				(width 0)
				(type default)
			)
			(fill no)
			(layer "B.Fab")
		)
		(pad "1" smd custom
			(at 0 -0.4445 270)
			(size 0.1397 0.1397)
			(layers "B.Cu" "B.Mask" "B.Paste")
			(net "GND")
			(options
				(clearance outline)
				(anchor circle)
			)
			(primitives
				(gr_poly
					(pts
						(arc
							(start -0.1778 0.2794)
							(mid -0.249642 0.249642)
							(end -0.2794 0.1778)
						)
						(arc
							(start -0.2794 -0.1778)
							(mid -0.249642 -0.249642)
							(end -0.1778 -0.2794)
						)
						(arc
							(start 0.1778 -0.2794)
							(mid 0.249642 -0.249642)
							(end 0.2794 -0.1778)
						)
						(arc
							(start 0.2794 0.1778)
							(mid 0.249642 0.249642)
							(end 0.1778 0.2794)
						)
					)
					(width 0)
					(fill yes)
				)
			)
		)
		(pad "2" smd custom
			(at 0 0.4445 270)
			(size 0.1397 0.1397)
			(layers "B.Cu" "B.Mask" "B.Paste")
			(net "MEMODT")
			(options
				(clearance outline)
				(anchor circle)
			)
			(primitives
				(gr_poly
					(pts
						(arc
							(start -0.1778 0.2794)
							(mid -0.249642 0.249642)
							(end -0.2794 0.1778)
						)
						(arc
							(start -0.2794 -0.1778)
							(mid -0.249642 -0.249642)
							(end -0.1778 -0.2794)
						)
						(arc
							(start 0.1778 -0.2794)
							(mid 0.249642 -0.249642)
							(end 0.2794 -0.1778)
						)
						(arc
							(start 0.2794 0.1778)
							(mid 0.249642 0.249642)
							(end 0.1778 0.2794)
						)
					)
					(width 0)
					(fill yes)
				)
			)
		)
	)
	(footprint ""
		(layer "B.Cu")
		(at 17.723612 -131.007358 180)
		(property "Reference" "R241"
			(at 0 0 0)
			(layer "B.SilkS")
			(hide yes)
			(effects
				(font
					(size 1.27 1.27)
				)
				(justify mirror)
			)
		)
		(property "Value" "120R2F-GP"
			(at -0.064008 -3.993896 180)
			(unlocked yes)
			(layer "B.Fab")
			(hide yes)
			(effects
				(font
					(size 1.016 1.016)
					(thickness 0.1524)
				)
				(justify mirror)
			)
		)
		(property "Device Type" "R402H16"
			(at -0.064008 -5.517896 180)
			(unlocked yes)
			(layer "B.Fab")
			(hide yes)
			(effects
				(font
					(size 1.016 1.016)
					(thickness 0.1524)
				)
				(justify mirror)
			)
		)
		(duplicate_pad_numbers_are_jumpers no)
		(fp_line
			(start 0.508 -0.9398)
			(end 0.508 0.9398)
			(stroke
				(width 0.1524)
				(type default)
			)
			(layer "B.SilkS")
		)
		(fp_line
			(start -0.508 -0.9398)
			(end 0.508 -0.9398)
			(stroke
				(width 0.1524)
				(type default)
			)
			(layer "B.SilkS")
		)
		(fp_rect
			(start 0.508 0.9398)
			(end -0.508 -0.9398)
			(stroke
				(width 0)
				(type default)
			)
			(fill no)
			(layer "B.CrtYd")
		)
		(fp_rect
			(start 0.508 0.9398)
			(end -0.508 -0.9398)
			(stroke
				(width 0)
				(type default)
			)
			(fill no)
			(layer "B.Fab")
		)
		(pad "1" smd custom
			(at 0 -0.4445)
			(size 0.1397 0.1397)
			(layers "B.Cu" "B.Mask" "B.Paste")
			(net "MEMA_3")
			(options
				(clearance outline)
				(anchor circle)
			)
			(primitives
				(gr_poly
					(pts
						(arc
							(start -0.1778 0.2794)
							(mid -0.249642 0.249642)
							(end -0.2794 0.1778)
						)
						(arc
							(start -0.2794 -0.1778)
							(mid -0.249642 -0.249642)
							(end -0.1778 -0.2794)
						)
						(arc
							(start 0.1778 -0.2794)
							(mid 0.249642 -0.249642)
							(end 0.2794 -0.1778)
						)
						(arc
							(start 0.2794 0.1778)
							(mid 0.249642 0.249642)
							(end 0.1778 0.2794)
						)
					)
					(width 0)
					(fill yes)
				)
			)
		)
		(pad "2" smd custom
			(at 0 0.4445)
			(size 0.1397 0.1397)
			(layers "B.Cu" "B.Mask" "B.Paste")
			(net "P1V2_STBY")
			(options
				(clearance outline)
				(anchor circle)
			)
			(primitives
				(gr_poly
					(pts
						(arc
							(start -0.1778 0.2794)
							(mid -0.249642 0.249642)
							(end -0.2794 0.1778)
						)
						(arc
							(start -0.2794 -0.1778)
							(mid -0.249642 -0.249642)
							(end -0.1778 -0.2794)
						)
						(arc
							(start 0.1778 -0.2794)
							(mid 0.249642 -0.249642)
							(end 0.2794 -0.1778)
						)
						(arc
							(start 0.2794 0.1778)
							(mid 0.249642 0.249642)
							(end 0.1778 0.2794)
						)
					)
					(width 0)
					(fill yes)
				)
			)
		)
	)
	(footprint ""
		(layer "B.Cu")
		(at 82.504788 -46.810676 -90)
		(property "Reference" "C511"
			(at 0 0 90)
			(layer "B.SilkS")
			(hide yes)
			(effects
				(font
					(size 1.27 1.27)
				)
				(justify mirror)
			)
		)
		(property "Value" "SC10U16V5KX-7-GP-U"
			(at 0.0762 -6.1214 270)
			(unlocked yes)
			(layer "B.Fab")
			(hide yes)
			(effects
				(font
					(size 1.016 1.016)
					(thickness 0.1524)
				)
				(justify mirror)
			)
		)
		(property "Device Type" "C805H58"
			(at 0.0762 -8.1534 270)
			(unlocked yes)
			(layer "B.Fab")
			(hide yes)
			(effects
				(font
					(size 1.016 1.016)
					(thickness 0.1524)
				)
				(justify mirror)
			)
		)
		(duplicate_pad_numbers_are_jumpers no)
		(fp_line
			(start -0.635 0)
			(end 0.635 0)
			(stroke
				(width 0.508)
				(type default)
			)
			(layer "B.SilkS")
		)
		(fp_rect
			(start 0.9652 1.778)
			(end -0.9652 -1.778)
			(stroke
				(width 0)
				(type default)
			)
			(fill no)
			(layer "B.CrtYd")
		)
		(fp_poly
			(pts
				(xy 0.9652 -1.778) (xy -0.9652 -1.778) (xy -0.9652 1.778) (xy 0.9652 1.778)
			)
			(stroke
				(width 0)
				(type default)
			)
			(fill no)
			(layer "B.Fab")
		)
		(pad "1" smd rect
			(at 0 -0.9652 90)
			(size 1.397 1.143)
			(layers "B.Cu" "B.Mask" "B.Paste")
			(net "P5V_STBY")
		)
		(pad "2" smd rect
			(at 0 0.9652 90)
			(size 1.397 1.143)
			(layers "B.Cu" "B.Mask" "B.Paste")
			(net "GND")
		)
	)
	(footprint ""
		(layer "B.Cu")
		(at 209.033872 -59.934856 -90)
		(property "Reference" "R594"
			(at 0 0 90)
			(layer "B.SilkS")
			(hide yes)
			(effects
				(font
					(size 1.27 1.27)
				)
				(justify mirror)
			)
		)
		(property "Value" "2K2R2F-GP"
			(at -0.064008 -3.993896 270)
			(unlocked yes)
			(layer "B.Fab")
			(hide yes)
			(effects
				(font
					(size 1.016 1.016)
					(thickness 0.1524)
				)
				(justify mirror)
			)
		)
		(property "Device Type" "R402H16"
			(at -0.064008 -5.517896 270)
			(unlocked yes)
			(layer "B.Fab")
			(hide yes)
			(effects
				(font
					(size 1.016 1.016)
					(thickness 0.1524)
				)
				(justify mirror)
			)
		)
		(duplicate_pad_numbers_are_jumpers no)
		(fp_line
			(start -0.508 -0.9398)
			(end 0.508 -0.9398)
			(stroke
				(width 0.1524)
				(type default)
			)
			(layer "B.SilkS")
		)
		(fp_line
			(start 0.508 -0.9398)
			(end 0.508 0.9398)
			(stroke
				(width 0.1524)
				(type default)
			)
			(layer "B.SilkS")
		)
		(fp_rect
			(start 0.508 0.9398)
			(end -0.508 -0.9398)
			(stroke
				(width 0)
				(type default)
			)
			(fill no)
			(layer "B.CrtYd")
		)
		(fp_rect
			(start 0.508 0.9398)
			(end -0.508 -0.9398)
			(stroke
				(width 0)
				(type default)
			)
			(fill no)
			(layer "B.Fab")
		)
		(pad "1" smd custom
			(at 0 -0.4445 90)
			(size 0.1397 0.1397)
			(layers "B.Cu" "B.Mask" "B.Paste")
			(net "P1V8")
			(options
				(clearance outline)
				(anchor circle)
			)
			(primitives
				(gr_poly
					(pts
						(arc
							(start -0.1778 0.2794)
							(mid -0.249642 0.249642)
							(end -0.2794 0.1778)
						)
						(arc
							(start -0.2794 -0.1778)
							(mid -0.249642 -0.249642)
							(end -0.1778 -0.2794)
						)
						(arc
							(start 0.1778 -0.2794)
							(mid 0.249642 -0.249642)
							(end 0.2794 -0.1778)
						)
						(arc
							(start 0.2794 0.1778)
							(mid 0.249642 0.249642)
							(end 0.1778 0.2794)
						)
					)
					(width 0)
					(fill yes)
				)
			)
		)
		(pad "2" smd custom
			(at 0 0.4445 90)
			(size 0.1397 0.1397)
			(layers "B.Cu" "B.Mask" "B.Paste")
			(net "SIO_DOUT_1")
			(options
				(clearance outline)
				(anchor circle)
			)
			(primitives
				(gr_poly
					(pts
						(arc
							(start -0.1778 0.2794)
							(mid -0.249642 0.249642)
							(end -0.2794 0.1778)
						)
						(arc
							(start -0.2794 -0.1778)
							(mid -0.249642 -0.249642)
							(end -0.1778 -0.2794)
						)
						(arc
							(start 0.1778 -0.2794)
							(mid 0.249642 -0.249642)
							(end 0.2794 -0.1778)
						)
						(arc
							(start 0.2794 0.1778)
							(mid 0.249642 0.249642)
							(end 0.1778 0.2794)
						)
					)
					(width 0)
					(fill yes)
				)
			)
		)
	)
	(footprint ""
		(layer "B.Cu")
		(at 197.25386 -62.96152 90)
		(property "Reference" "C391"
			(at 0 0 90)
			(layer "B.SilkS")
			(hide yes)
			(effects
				(font
					(size 1.27 1.27)
				)
				(justify mirror)
			)
		)
		(property "Value" "SC1U16V2KX-7-GP"
			(at -1.7526 -1.6002 90)
			(unlocked yes)
			(layer "B.Fab")
			(hide yes)
			(effects
				(font
					(size 1.016 1.016)
					(thickness 0.1524)
				)
				(justify mirror)
			)
		)
		(property "Device Type" "C402-TO0D2H24"
			(at -1.7526 -3.1242 90)
			(unlocked yes)
			(layer "B.Fab")
			(hide yes)
			(effects
				(font
					(size 1.016 1.016)
					(thickness 0.1524)
				)
				(justify mirror)
			)
		)
		(duplicate_pad_numbers_are_jumpers no)
		(fp_rect
			(start 0.4826 0.889)
			(end -0.4826 -0.889)
			(stroke
				(width 0)
				(type default)
			)
			(fill no)
			(layer "B.CrtYd")
		)
		(fp_rect
			(start 0.4826 0.889)
			(end -0.4826 -0.889)
			(stroke
				(width 0)
				(type default)
			)
			(fill no)
			(layer "B.Fab")
		)
		(pad "1" smd custom
			(at 0 -0.4572 270)
			(size 0.1524 0.1524)
			(layers "B.Cu" "B.Mask" "B.Paste")
			(net "P0V975")
			(options
				(clearance outline)
				(anchor circle)
			)
			(primitives
				(gr_poly
					(pts
						(arc
							(start -0.254 -0.3048)
							(mid -0.325842 -0.275042)
							(end -0.3556 -0.2032)
						)
						(arc
							(start -0.3556 0.2032)
							(mid -0.325842 0.275042)
							(end -0.254 0.3048)
						)
						(arc
							(start 0.254 0.3048)
							(mid 0.325842 0.275042)
							(end 0.3556 0.2032)
						)
						(arc
							(start 0.3556 -0.2032)
							(mid 0.325842 -0.275042)
							(end 0.254 -0.3048)
						)
					)
					(width 0)
					(fill yes)
				)
			)
		)
		(pad "2" smd custom
			(at 0 0.4572 270)
			(size 0.1524 0.1524)
			(layers "B.Cu" "B.Mask" "B.Paste")
			(net "GND")
			(options
				(clearance outline)
				(anchor circle)
			)
			(primitives
				(gr_poly
					(pts
						(arc
							(start -0.254 -0.3048)
							(mid -0.325842 -0.275042)
							(end -0.3556 -0.2032)
						)
						(arc
							(start -0.3556 0.2032)
							(mid -0.325842 0.275042)
							(end -0.254 0.3048)
						)
						(arc
							(start 0.254 0.3048)
							(mid 0.325842 0.275042)
							(end 0.3556 0.2032)
						)
						(arc
							(start 0.3556 -0.2032)
							(mid 0.325842 -0.275042)
							(end 0.254 -0.3048)
						)
					)
					(width 0)
					(fill yes)
				)
			)
		)
	)
	(footprint ""
		(layer "B.Cu")
		(at 45.466 -128.2192)
		(property "Reference" "R292"
			(at 0 0 0)
			(layer "B.SilkS")
			(hide yes)
			(effects
				(font
					(size 1.27 1.27)
				)
				(justify mirror)
			)
		)
		(property "Value" "0R2J-2-GP"
			(at -0.064008 -3.993896 0)
			(unlocked yes)
			(layer "B.Fab")
			(hide yes)
			(effects
				(font
					(size 1.016 1.016)
					(thickness 0.1524)
				)
				(justify mirror)
			)
		)
		(property "Device Type" "R402H16"
			(at -0.064008 -5.517896 0)
			(unlocked yes)
			(layer "B.Fab")
			(hide yes)
			(effects
				(font
					(size 1.016 1.016)
					(thickness 0.1524)
				)
				(justify mirror)
			)
		)
		(duplicate_pad_numbers_are_jumpers no)
		(fp_line
			(start -0.508 -0.9398)
			(end 0.508 -0.9398)
			(stroke
				(width 0.1524)
				(type default)
			)
			(layer "B.SilkS")
		)
		(fp_line
			(start 0.508 -0.9398)
			(end 0.508 0.9398)
			(stroke
				(width 0.1524)
				(type default)
			)
			(layer "B.SilkS")
		)
		(fp_rect
			(start 0.508 0.9398)
			(end -0.508 -0.9398)
			(stroke
				(width 0)
				(type default)
			)
			(fill no)
			(layer "B.CrtYd")
		)
		(fp_rect
			(start 0.508 0.9398)
			(end -0.508 -0.9398)
			(stroke
				(width 0)
				(type default)
			)
			(fill no)
			(layer "B.Fab")
		)
		(pad "1" smd custom
			(at 0 -0.4445 180)
			(size 0.1397 0.1397)
			(layers "B.Cu" "B.Mask" "B.Paste")
			(net "IOM_LOC_INS_N")
			(options
				(clearance outline)
				(anchor circle)
			)
			(primitives
				(gr_poly
					(pts
						(arc
							(start -0.1778 0.2794)
							(mid -0.249642 0.249642)
							(end -0.2794 0.1778)
						)
						(arc
							(start -0.2794 -0.1778)
							(mid -0.249642 -0.249642)
							(end -0.1778 -0.2794)
						)
						(arc
							(start 0.1778 -0.2794)
							(mid 0.249642 -0.249642)
							(end 0.2794 -0.1778)
						)
						(arc
							(start 0.2794 0.1778)
							(mid 0.249642 0.249642)
							(end 0.1778 0.2794)
						)
					)
					(width 0)
					(fill yes)
				)
			)
		)
		(pad "2" smd custom
			(at 0 0.4445 180)
			(size 0.1397 0.1397)
			(layers "B.Cu" "B.Mask" "B.Paste")
			(net "GND")
			(options
				(clearance outline)
				(anchor circle)
			)
			(primitives
				(gr_poly
					(pts
						(arc
							(start -0.1778 0.2794)
							(mid -0.249642 0.249642)
							(end -0.2794 0.1778)
						)
						(arc
							(start -0.2794 -0.1778)
							(mid -0.249642 -0.249642)
							(end -0.1778 -0.2794)
						)
						(arc
							(start 0.1778 -0.2794)
							(mid 0.249642 -0.249642)
							(end 0.2794 -0.1778)
						)
						(arc
							(start 0.2794 0.1778)
							(mid 0.249642 0.249642)
							(end 0.1778 0.2794)
						)
					)
					(width 0)
					(fill yes)
				)
			)
		)
	)
	(footprint ""
		(layer "B.Cu")
		(at 90.5764 -132.7404)
		(property "Reference" "C503"
			(at 0 0 0)
			(layer "B.SilkS")
			(hide yes)
			(effects
				(font
					(size 1.27 1.27)
				)
				(justify mirror)
			)
		)
		(property "Value" "SCD1U16V2KX-3GP"
			(at -1.1811 -2.7051 0)
			(unlocked yes)
			(layer "B.Fab")
			(hide yes)
			(effects
				(font
					(size 1.016 1.016)
					(thickness 0.1524)
				)
				(justify mirror)
			)
		)
		(property "Device Type" "C402H22"
			(at -1.1811 -4.2291 0)
			(unlocked yes)
			(layer "B.Fab")
			(hide yes)
			(effects
				(font
					(size 1.016 1.016)
					(thickness 0.1524)
				)
				(justify mirror)
			)
		)
		(duplicate_pad_numbers_are_jumpers no)
		(fp_rect
			(start 0.4318 0.9525)
			(end -0.4318 -0.9525)
			(stroke
				(width 0)
				(type default)
			)
			(fill no)
			(layer "B.CrtYd")
		)
		(fp_rect
			(start 0.4318 0.9525)
			(end -0.4318 -0.9525)
			(stroke
				(width 0)
				(type default)
			)
			(fill no)
			(layer "B.Fab")
		)
		(pad "1" smd custom
			(at 0 -0.4445 180)
			(size 0.1524 0.1524)
			(layers "B.Cu" "B.Mask" "B.Paste")
			(net "P3V3_STBY")
			(options
				(clearance outline)
				(anchor circle)
			)
			(primitives
				(gr_poly
					(pts
						(arc
							(start 0.3048 0.2032)
							(mid 0.275042 0.275042)
							(end 0.2032 0.3048)
						)
						(arc
							(start -0.2032 0.3048)
							(mid -0.275042 0.275042)
							(end -0.3048 0.2032)
						)
						(arc
							(start -0.3048 -0.2032)
							(mid -0.275042 -0.275042)
							(end -0.2032 -0.3048)
						)
						(arc
							(start 0.2032 -0.3048)
							(mid 0.275042 -0.275042)
							(end 0.3048 -0.2032)
						)
					)
					(width 0)
					(fill yes)
				)
			)
		)
		(pad "2" smd custom
			(at 0 0.4445 180)
			(size 0.1524 0.1524)
			(layers "B.Cu" "B.Mask" "B.Paste")
			(net "GND")
			(options
				(clearance outline)
				(anchor circle)
			)
			(primitives
				(gr_poly
					(pts
						(arc
							(start 0.3048 0.2032)
							(mid 0.275042 0.275042)
							(end 0.2032 0.3048)
						)
						(arc
							(start -0.2032 0.3048)
							(mid -0.275042 0.275042)
							(end -0.3048 0.2032)
						)
						(arc
							(start -0.3048 -0.2032)
							(mid -0.275042 -0.275042)
							(end -0.2032 -0.3048)
						)
						(arc
							(start 0.2032 -0.3048)
							(mid 0.275042 -0.275042)
							(end 0.3048 -0.2032)
						)
					)
					(width 0)
					(fill yes)
				)
			)
		)
	)
	(footprint ""
		(layer "B.Cu")
		(at 180.594 -59.1312)
		(property "Reference" "TP164"
			(at 0 0 0)
			(layer "B.SilkS")
			(hide yes)
			(effects
				(font
					(size 1.27 1.27)
				)
				(justify mirror)
			)
		)
		(property "Value" "TPAD28-2-GP"
			(at 0.0127 -1.6637 0)
			(unlocked yes)
			(layer "B.Fab")
			(hide yes)
			(effects
				(font
					(size 1.016 1.016)
					(thickness 0.1524)
				)
				(justify mirror)
			)
		)
		(property "Device Type" "TPAD28"
			(at 0.0127 -3.1877 0)
			(unlocked yes)
			(layer "B.Fab")
			(hide yes)
			(effects
				(font
					(size 1.016 1.016)
					(thickness 0.1524)
				)
				(justify mirror)
			)
		)
		(duplicate_pad_numbers_are_jumpers no)
		(fp_poly
			(pts
				(arc
					(start 0.3556 0)
					(mid -0.3556 0)
					(end 0.3556 0)
				)
			)
			(stroke
				(width 0)
				(type default)
			)
			(fill no)
			(layer "B.CrtYd")
		)
		(fp_poly
			(pts
				(arc
					(start 0.6096 0)
					(mid -0.6096 0)
					(end 0.6096 0)
				)
			)
			(stroke
				(width 0)
				(type default)
			)
			(fill no)
			(layer "B.Fab")
		)
		(pad "1" smd circle
			(at 0 0 180)
			(size 0.7112 0.7112)
			(layers "B.Cu" "B.Mask" "B.Paste")
			(net "XM_ADDR_25")
		)
	)
	(footprint ""
		(layer "B.Cu")
		(at 41.9862 -134.0358 90)
		(property "Reference" "R373"
			(at 0 0 90)
			(layer "B.SilkS")
			(hide yes)
			(effects
				(font
					(size 1.27 1.27)
				)
				(justify mirror)
			)
		)
		(property "Value" "4K7R2F-GP"
			(at -0.064008 -3.993896 90)
			(unlocked yes)
			(layer "B.Fab")
			(hide yes)
			(effects
				(font
					(size 1.016 1.016)
					(thickness 0.1524)
				)
				(justify mirror)
			)
		)
		(property "Device Type" "R402H16"
			(at -0.064008 -5.517896 90)
			(unlocked yes)
			(layer "B.Fab")
			(hide yes)
			(effects
				(font
					(size 1.016 1.016)
					(thickness 0.1524)
				)
				(justify mirror)
			)
		)
		(duplicate_pad_numbers_are_jumpers no)
		(fp_line
			(start 0.508 -0.9398)
			(end 0.508 0.9398)
			(stroke
				(width 0.1524)
				(type default)
			)
			(layer "B.SilkS")
		)
		(fp_line
			(start -0.508 -0.9398)
			(end 0.508 -0.9398)
			(stroke
				(width 0.1524)
				(type default)
			)
			(layer "B.SilkS")
		)
		(fp_rect
			(start 0.508 0.9398)
			(end -0.508 -0.9398)
			(stroke
				(width 0)
				(type default)
			)
			(fill no)
			(layer "B.CrtYd")
		)
		(fp_rect
			(start 0.508 0.9398)
			(end -0.508 -0.9398)
			(stroke
				(width 0)
				(type default)
			)
			(fill no)
			(layer "B.Fab")
		)
		(pad "1" smd custom
			(at 0 -0.4445 270)
			(size 0.1397 0.1397)
			(layers "B.Cu" "B.Mask" "B.Paste")
			(net "P3V3_STBY")
			(options
				(clearance outline)
				(anchor circle)
			)
			(primitives
				(gr_poly
					(pts
						(arc
							(start -0.1778 0.2794)
							(mid -0.249642 0.249642)
							(end -0.2794 0.1778)
						)
						(arc
							(start -0.2794 -0.1778)
							(mid -0.249642 -0.249642)
							(end -0.1778 -0.2794)
						)
						(arc
							(start 0.1778 -0.2794)
							(mid 0.249642 -0.249642)
							(end 0.2794 -0.1778)
						)
						(arc
							(start 0.2794 0.1778)
							(mid 0.249642 0.249642)
							(end 0.1778 0.2794)
						)
					)
					(width 0)
					(fill yes)
				)
			)
		)
		(pad "2" smd custom
			(at 0 0.4445 270)
			(size 0.1397 0.1397)
			(layers "B.Cu" "B.Mask" "B.Paste")
			(net "BMC_GPIOS5")
			(options
				(clearance outline)
				(anchor circle)
			)
			(primitives
				(gr_poly
					(pts
						(arc
							(start -0.1778 0.2794)
							(mid -0.249642 0.249642)
							(end -0.2794 0.1778)
						)
						(arc
							(start -0.2794 -0.1778)
							(mid -0.249642 -0.249642)
							(end -0.1778 -0.2794)
						)
						(arc
							(start 0.1778 -0.2794)
							(mid 0.249642 -0.249642)
							(end 0.2794 -0.1778)
						)
						(arc
							(start 0.2794 0.1778)
							(mid 0.249642 0.249642)
							(end 0.1778 0.2794)
						)
					)
					(width 0)
					(fill yes)
				)
			)
		)
	)
	(footprint ""
		(layer "B.Cu")
		(at 50.103786 -146.684238 -90)
		(property "Reference" "C98"
			(at 0 0 90)
			(layer "B.SilkS")
			(hide yes)
			(effects
				(font
					(size 1.27 1.27)
				)
				(justify mirror)
			)
		)
		(property "Value" "SC1U16V3KX-5GP"
			(at 0 -2.8194 270)
			(unlocked yes)
			(layer "B.Fab")
			(hide yes)
			(effects
				(font
					(size 1.016 1.016)
					(thickness 0.1524)
				)
				(justify mirror)
			)
		)
		(property "Device Type" "C603H36"
			(at 0 -4.3434 270)
			(unlocked yes)
			(layer "B.Fab")
			(hide yes)
			(effects
				(font
					(size 1.016 1.016)
					(thickness 0.1524)
				)
				(justify mirror)
			)
		)
		(duplicate_pad_numbers_are_jumpers no)
		(fp_line
			(start -0.508 0)
			(end 0.508 0)
			(stroke
				(width 0.2032)
				(type default)
			)
			(layer "B.SilkS")
		)
		(fp_rect
			(start 0.5842 1.3335)
			(end -0.5842 -1.3335)
			(stroke
				(width 0)
				(type default)
			)
			(fill no)
			(layer "B.CrtYd")
		)
		(fp_rect
			(start 0.5842 1.3335)
			(end -0.5842 -1.3335)
			(stroke
				(width 0)
				(type default)
			)
			(fill no)
			(layer "B.Fab")
		)
		(pad "1" smd custom
			(at 0 -0.762 90)
			(size 0.2159 0.2159)
			(layers "B.Cu" "B.Mask" "B.Paste")
			(net "P3V3_STBY")
			(options
				(clearance outline)
				(anchor circle)
			)
			(primitives
				(gr_poly
					(pts
						(arc
							(start -0.3302 0.4318)
							(mid -0.402042 0.402042)
							(end -0.4318 0.3302)
						)
						(arc
							(start -0.4318 -0.3302)
							(mid -0.402042 -0.402042)
							(end -0.3302 -0.4318)
						)
						(arc
							(start 0.3302 -0.4318)
							(mid 0.402042 -0.402042)
							(end 0.4318 -0.3302)
						)
						(arc
							(start 0.4318 0.3302)
							(mid 0.402042 0.402042)
							(end 0.3302 0.4318)
						)
					)
					(width 0)
					(fill yes)
				)
			)
		)
		(pad "2" smd custom
			(at 0 0.762 90)
			(size 0.2159 0.2159)
			(layers "B.Cu" "B.Mask" "B.Paste")
			(net "GND")
			(options
				(clearance outline)
				(anchor circle)
			)
			(primitives
				(gr_poly
					(pts
						(arc
							(start -0.3302 0.4318)
							(mid -0.402042 0.402042)
							(end -0.4318 0.3302)
						)
						(arc
							(start -0.4318 -0.3302)
							(mid -0.402042 -0.402042)
							(end -0.3302 -0.4318)
						)
						(arc
							(start 0.3302 -0.4318)
							(mid 0.402042 -0.402042)
							(end 0.4318 -0.3302)
						)
						(arc
							(start 0.4318 0.3302)
							(mid 0.402042 0.402042)
							(end 0.3302 0.4318)
						)
					)
					(width 0)
					(fill yes)
				)
			)
		)
	)
	(footprint ""
		(layer "B.Cu")
		(at 163.83 -140.8938 180)
		(property "Reference" "C212"
			(at 0 0 0)
			(layer "B.SilkS")
			(hide yes)
			(effects
				(font
					(size 1.27 1.27)
				)
				(justify mirror)
			)
		)
		(property "Value" "SC1KP50V2KX-1GP"
			(at -1.1811 -2.7051 180)
			(unlocked yes)
			(layer "B.Fab")
			(hide yes)
			(effects
				(font
					(size 1.016 1.016)
					(thickness 0.1524)
				)
				(justify mirror)
			)
		)
		(property "Device Type" "C402H22"
			(at -1.1811 -4.2291 180)
			(unlocked yes)
			(layer "B.Fab")
			(hide yes)
			(effects
				(font
					(size 1.016 1.016)
					(thickness 0.1524)
				)
				(justify mirror)
			)
		)
		(duplicate_pad_numbers_are_jumpers no)
		(fp_rect
			(start 0.4318 0.9525)
			(end -0.4318 -0.9525)
			(stroke
				(width 0)
				(type default)
			)
			(fill no)
			(layer "B.CrtYd")
		)
		(fp_rect
			(start 0.4318 0.9525)
			(end -0.4318 -0.9525)
			(stroke
				(width 0)
				(type default)
			)
			(fill no)
			(layer "B.Fab")
		)
		(pad "1" smd custom
			(at 0 -0.4445)
			(size 0.1524 0.1524)
			(layers "B.Cu" "B.Mask" "B.Paste")
			(net "P1V8_STBY_VFB_R")
			(options
				(clearance outline)
				(anchor circle)
			)
			(primitives
				(gr_poly
					(pts
						(arc
							(start 0.3048 0.2032)
							(mid 0.275042 0.275042)
							(end 0.2032 0.3048)
						)
						(arc
							(start -0.2032 0.3048)
							(mid -0.275042 0.275042)
							(end -0.3048 0.2032)
						)
						(arc
							(start -0.3048 -0.2032)
							(mid -0.275042 -0.275042)
							(end -0.2032 -0.3048)
						)
						(arc
							(start 0.2032 -0.3048)
							(mid 0.275042 -0.275042)
							(end 0.3048 -0.2032)
						)
					)
					(width 0)
					(fill yes)
				)
			)
		)
		(pad "2" smd custom
			(at 0 0.4445)
			(size 0.1524 0.1524)
			(layers "B.Cu" "B.Mask" "B.Paste")
			(net "P1V8_STBY_VFB")
			(options
				(clearance outline)
				(anchor circle)
			)
			(primitives
				(gr_poly
					(pts
						(arc
							(start 0.3048 0.2032)
							(mid 0.275042 0.275042)
							(end 0.2032 0.3048)
						)
						(arc
							(start -0.2032 0.3048)
							(mid -0.275042 0.275042)
							(end -0.3048 0.2032)
						)
						(arc
							(start -0.3048 -0.2032)
							(mid -0.275042 -0.275042)
							(end -0.2032 -0.3048)
						)
						(arc
							(start 0.2032 -0.3048)
							(mid 0.275042 -0.275042)
							(end 0.3048 -0.2032)
						)
					)
					(width 0)
					(fill yes)
				)
			)
		)
	)
	(footprint ""
		(layer "B.Cu")
		(at 152.781 -92.3544 180)
		(property "Reference" "U41"
			(at 0 0 0)
			(layer "B.SilkS")
			(hide yes)
			(effects
				(font
					(size 1.27 1.27)
				)
				(justify mirror)
			)
		)
		(property "Value" "TPS3808G18DRVT-GP-U"
			(at 2.7813 -0.4572 180)
			(unlocked yes)
			(layer "B.Fab")
			(hide yes)
			(effects
				(font
					(size 1.016 1.016)
					(thickness 0.1524)
				)
				(justify mirror)
			)
		)
		(property "Device Type" "DFN6F2-G1711-UH32"
			(at 2.7813 -1.9812 180)
			(unlocked yes)
			(layer "B.Fab")
			(hide yes)
			(effects
				(font
					(size 1.016 1.016)
					(thickness 0.1524)
				)
				(justify mirror)
			)
		)
		(duplicate_pad_numbers_are_jumpers no)
		(fp_line
			(start 1.5113 1.7653)
			(end 0.7493 1.7653)
			(stroke
				(width 0.1524)
				(type default)
			)
			(layer "B.SilkS")
		)
		(fp_line
			(start 1.5113 1.0033)
			(end 1.5113 1.7653)
			(stroke
				(width 0.1524)
				(type default)
			)
			(layer "B.SilkS")
		)
		(fp_line
			(start 1.5113 -1.0033)
			(end 1.5113 -1.7653)
			(stroke
				(width 0.1524)
				(type default)
			)
			(layer "B.SilkS")
		)
		(fp_line
			(start 1.5113 -1.7653)
			(end 0.7493 -1.7653)
			(stroke
				(width 0.1524)
				(type default)
			)
			(layer "B.SilkS")
		)
		(fp_line
			(start 0 1.5113)
			(end 0 2.0193)
			(stroke
				(width 0.1524)
				(type default)
			)
			(layer "B.SilkS")
		)
		(fp_line
			(start -1.5113 1.7653)
			(end -0.7493 1.7653)
			(stroke
				(width 0.1524)
				(type default)
			)
			(layer "B.SilkS")
		)
		(fp_line
			(start -1.5113 1.0033)
			(end -1.5113 1.7653)
			(stroke
				(width 0.1524)
				(type default)
			)
			(layer "B.SilkS")
		)
		(fp_poly
			(pts
				(xy -0.7493 -1.7653) (xy -1.5113 -1.0033) (xy -1.5113 -1.7653)
			)
			(stroke
				(width 0)
				(type default)
			)
			(fill yes)
			(layer "B.SilkS")
		)
		(fp_rect
			(start 1.0033 1.0033)
			(end -1.0033 -1.0033)
			(stroke
				(width 0)
				(type default)
			)
			(fill no)
			(layer "B.CrtYd")
		)
		(fp_poly
			(pts
				(xy 1.5113 1.7653) (xy 1.5113 -1.7653) (xy -1.5113 -1.7653) (xy -1.5113 0.99822) (xy -1.0033 0.99822)
				(xy -1.0033 -1.0033) (xy 1.0033 -1.0033) (xy 1.0033 1.0033) (xy -1.5113 1.0033) (xy -1.5113 1.7653)
			)
			(stroke
				(width 0)
				(type default)
			)
			(fill no)
			(layer "B.CrtYd")
		)
		(fp_rect
			(start 1.5113 1.7653)
			(end -1.5113 -1.7653)
			(stroke
				(width 0)
				(type default)
			)
			(fill no)
			(layer "B.Fab")
		)
		(pad "1" smd rect
			(at -0.649986 -1.1303)
			(size 0.4064 0.508)
			(drill
				(offset 0 -0.127)
			)
			(layers "B.Cu" "B.Mask" "B.Paste")
			(net "P1V8_STBY")
		)
		(pad "2" smd rect
			(at 0 -1.1303)
			(size 0.4064 0.508)
			(drill
				(offset 0 -0.127)
			)
			(layers "B.Cu" "B.Mask" "B.Paste")
			(net "PWRGD_P0V975")
		)
		(pad "3" smd rect
			(at 0.649986 -1.1303)
			(size 0.4064 0.508)
			(drill
				(offset 0 -0.127)
			)
			(layers "B.Cu" "B.Mask" "B.Paste")
			(net "Net_189")
		)
		(pad "4" smd rect
			(at 0.649986 1.1303)
			(size 0.4064 0.508)
			(drill
				(offset 0 0.127)
			)
			(layers "B.Cu" "B.Mask" "B.Paste")
			(net "IOC_VREF_SET")
		)
		(pad "5" smd rect
			(at 0 1.1303)
			(size 0.4064 0.508)
			(drill
				(offset 0 0.127)
			)
			(layers "B.Cu" "B.Mask" "B.Paste")
			(net "GND")
		)
		(pad "6" smd rect
			(at -0.649986 1.1303)
			(size 0.4064 0.508)
			(drill
				(offset 0 0.127)
			)
			(layers "B.Cu" "B.Mask" "B.Paste")
			(net "IOC_RESET#")
		)
		(pad "7" smd rect
			(at 0 0)
			(size 1.7018 1.0922)
			(layers "B.Cu" "B.Mask" "B.Paste")
			(net "GND")
		)
	)
	(footprint ""
		(layer "B.Cu")
		(at 179.731416 -69.10578)
		(property "Reference" "TP128"
			(at 0 0 0)
			(layer "B.SilkS")
			(hide yes)
			(effects
				(font
					(size 1.27 1.27)
				)
				(justify mirror)
			)
		)
		(property "Value" "TPAD28-2-GP"
			(at 0.0127 -1.6637 0)
			(unlocked yes)
			(layer "B.Fab")
			(hide yes)
			(effects
				(font
					(size 1.016 1.016)
					(thickness 0.1524)
				)
				(justify mirror)
			)
		)
		(property "Device Type" "TPAD28"
			(at 0.0127 -3.1877 0)
			(unlocked yes)
			(layer "B.Fab")
			(hide yes)
			(effects
				(font
					(size 1.016 1.016)
					(thickness 0.1524)
				)
				(justify mirror)
			)
		)
		(duplicate_pad_numbers_are_jumpers no)
		(fp_poly
			(pts
				(arc
					(start 0.3556 0)
					(mid -0.3556 0)
					(end 0.3556 0)
				)
			)
			(stroke
				(width 0)
				(type default)
			)
			(fill no)
			(layer "B.CrtYd")
		)
		(fp_poly
			(pts
				(arc
					(start 0.6096 0)
					(mid -0.6096 0)
					(end 0.6096 0)
				)
			)
			(stroke
				(width 0)
				(type default)
			)
			(fill no)
			(layer "B.Fab")
		)
		(pad "1" smd circle
			(at 0 0 180)
			(size 0.7112 0.7112)
			(layers "B.Cu" "B.Mask" "B.Paste")
			(net "IOC_GPIO_35")
		)
	)
	(footprint ""
		(layer "B.Cu")
		(at 52.19446 -161.8615 -90)
		(property "Reference" "R411"
			(at 0 0 90)
			(layer "B.SilkS")
			(hide yes)
			(effects
				(font
					(size 1.27 1.27)
				)
				(justify mirror)
			)
		)
		(property "Value" "1KR2F-3-GP"
			(at -0.064008 -3.993896 270)
			(unlocked yes)
			(layer "B.Fab")
			(hide yes)
			(effects
				(font
					(size 1.016 1.016)
					(thickness 0.1524)
				)
				(justify mirror)
			)
		)
		(property "Device Type" "R402H16"
			(at -0.064008 -5.517896 270)
			(unlocked yes)
			(layer "B.Fab")
			(hide yes)
			(effects
				(font
					(size 1.016 1.016)
					(thickness 0.1524)
				)
				(justify mirror)
			)
		)
		(duplicate_pad_numbers_are_jumpers no)
		(fp_line
			(start -0.508 -0.9398)
			(end 0.508 -0.9398)
			(stroke
				(width 0.1524)
				(type default)
			)
			(layer "B.SilkS")
		)
		(fp_line
			(start 0.508 -0.9398)
			(end 0.508 0.9398)
			(stroke
				(width 0.1524)
				(type default)
			)
			(layer "B.SilkS")
		)
		(fp_rect
			(start 0.508 0.9398)
			(end -0.508 -0.9398)
			(stroke
				(width 0)
				(type default)
			)
			(fill no)
			(layer "B.CrtYd")
		)
		(fp_rect
			(start 0.508 0.9398)
			(end -0.508 -0.9398)
			(stroke
				(width 0)
				(type default)
			)
			(fill no)
			(layer "B.Fab")
		)
		(pad "1" smd custom
			(at 0 -0.4445 90)
			(size 0.1397 0.1397)
			(layers "B.Cu" "B.Mask" "B.Paste")
			(net "ADC_P1V5")
			(options
				(clearance outline)
				(anchor circle)
			)
			(primitives
				(gr_poly
					(pts
						(arc
							(start -0.1778 0.2794)
							(mid -0.249642 0.249642)
							(end -0.2794 0.1778)
						)
						(arc
							(start -0.2794 -0.1778)
							(mid -0.249642 -0.249642)
							(end -0.1778 -0.2794)
						)
						(arc
							(start 0.1778 -0.2794)
							(mid 0.249642 -0.249642)
							(end 0.2794 -0.1778)
						)
						(arc
							(start 0.2794 0.1778)
							(mid 0.249642 0.249642)
							(end 0.1778 0.2794)
						)
					)
					(width 0)
					(fill yes)
				)
			)
		)
		(pad "2" smd custom
			(at 0 0.4445 90)
			(size 0.1397 0.1397)
			(layers "B.Cu" "B.Mask" "B.Paste")
			(net "GND")
			(options
				(clearance outline)
				(anchor circle)
			)
			(primitives
				(gr_poly
					(pts
						(arc
							(start -0.1778 0.2794)
							(mid -0.249642 0.249642)
							(end -0.2794 0.1778)
						)
						(arc
							(start -0.2794 -0.1778)
							(mid -0.249642 -0.249642)
							(end -0.1778 -0.2794)
						)
						(arc
							(start 0.1778 -0.2794)
							(mid 0.249642 -0.249642)
							(end 0.2794 -0.1778)
						)
						(arc
							(start 0.2794 0.1778)
							(mid 0.249642 0.249642)
							(end 0.1778 0.2794)
						)
					)
					(width 0)
					(fill yes)
				)
			)
		)
	)
	(footprint ""
		(layer "B.Cu")
		(at 58.009536 -158.599886 180)
		(property "Reference" "C95"
			(at 0 0 0)
			(layer "B.SilkS")
			(hide yes)
			(effects
				(font
					(size 1.27 1.27)
				)
				(justify mirror)
			)
		)
		(property "Value" "SC1U16V3KX-5GP"
			(at 0 -2.8194 180)
			(unlocked yes)
			(layer "B.Fab")
			(hide yes)
			(effects
				(font
					(size 1.016 1.016)
					(thickness 0.1524)
				)
				(justify mirror)
			)
		)
		(property "Device Type" "C603H36"
			(at 0 -4.3434 180)
			(unlocked yes)
			(layer "B.Fab")
			(hide yes)
			(effects
				(font
					(size 1.016 1.016)
					(thickness 0.1524)
				)
				(justify mirror)
			)
		)
		(duplicate_pad_numbers_are_jumpers no)
		(fp_line
			(start -0.508 0)
			(end 0.508 0)
			(stroke
				(width 0.2032)
				(type default)
			)
			(layer "B.SilkS")
		)
		(fp_rect
			(start 0.5842 1.3335)
			(end -0.5842 -1.3335)
			(stroke
				(width 0)
				(type default)
			)
			(fill no)
			(layer "B.CrtYd")
		)
		(fp_rect
			(start 0.5842 1.3335)
			(end -0.5842 -1.3335)
			(stroke
				(width 0)
				(type default)
			)
			(fill no)
			(layer "B.Fab")
		)
		(pad "1" smd custom
			(at 0 -0.762)
			(size 0.2159 0.2159)
			(layers "B.Cu" "B.Mask" "B.Paste")
			(net "VPLLAV33")
			(options
				(clearance outline)
				(anchor circle)
			)
			(primitives
				(gr_poly
					(pts
						(arc
							(start -0.3302 0.4318)
							(mid -0.402042 0.402042)
							(end -0.4318 0.3302)
						)
						(arc
							(start -0.4318 -0.3302)
							(mid -0.402042 -0.402042)
							(end -0.3302 -0.4318)
						)
						(arc
							(start 0.3302 -0.4318)
							(mid 0.402042 -0.402042)
							(end 0.4318 -0.3302)
						)
						(arc
							(start 0.4318 0.3302)
							(mid 0.402042 0.402042)
							(end 0.3302 0.4318)
						)
					)
					(width 0)
					(fill yes)
				)
			)
		)
		(pad "2" smd custom
			(at 0 0.762)
			(size 0.2159 0.2159)
			(layers "B.Cu" "B.Mask" "B.Paste")
			(net "GND")
			(options
				(clearance outline)
				(anchor circle)
			)
			(primitives
				(gr_poly
					(pts
						(arc
							(start -0.3302 0.4318)
							(mid -0.402042 0.402042)
							(end -0.4318 0.3302)
						)
						(arc
							(start -0.4318 -0.3302)
							(mid -0.402042 -0.402042)
							(end -0.3302 -0.4318)
						)
						(arc
							(start 0.3302 -0.4318)
							(mid 0.402042 -0.402042)
							(end 0.4318 -0.3302)
						)
						(arc
							(start 0.4318 0.3302)
							(mid 0.402042 0.402042)
							(end 0.3302 0.4318)
						)
					)
					(width 0)
					(fill yes)
				)
			)
		)
	)
	(footprint ""
		(layer "B.Cu")
		(at 177.488342 -70.763638)
		(property "Reference" "TP160"
			(at 0 0 0)
			(layer "B.SilkS")
			(hide yes)
			(effects
				(font
					(size 1.27 1.27)
				)
				(justify mirror)
			)
		)
		(property "Value" "TPAD28-2-GP"
			(at 0.0127 -1.6637 0)
			(unlocked yes)
			(layer "B.Fab")
			(hide yes)
			(effects
				(font
					(size 1.016 1.016)
					(thickness 0.1524)
				)
				(justify mirror)
			)
		)
		(property "Device Type" "TPAD28"
			(at 0.0127 -3.1877 0)
			(unlocked yes)
			(layer "B.Fab")
			(hide yes)
			(effects
				(font
					(size 1.016 1.016)
					(thickness 0.1524)
				)
				(justify mirror)
			)
		)
		(duplicate_pad_numbers_are_jumpers no)
		(fp_poly
			(pts
				(arc
					(start 0.3556 0)
					(mid -0.3556 0)
					(end 0.3556 0)
				)
			)
			(stroke
				(width 0)
				(type default)
			)
			(fill no)
			(layer "B.CrtYd")
		)
		(fp_poly
			(pts
				(arc
					(start 0.6096 0)
					(mid -0.6096 0)
					(end 0.6096 0)
				)
			)
			(stroke
				(width 0)
				(type default)
			)
			(fill no)
			(layer "B.Fab")
		)
		(pad "1" smd circle
			(at 0 0 180)
			(size 0.7112 0.7112)
			(layers "B.Cu" "B.Mask" "B.Paste")
			(net "SPARE4")
		)
	)
	(footprint ""
		(layer "B.Cu")
		(at 198.4248 -71.11492 90)
		(property "Reference" "C369"
			(at 0 0 90)
			(layer "B.SilkS")
			(hide yes)
			(effects
				(font
					(size 1.27 1.27)
				)
				(justify mirror)
			)
		)
		(property "Value" "SCD1U6D3V1KX-GP"
			(at 2.8321 -1.7399 90)
			(unlocked yes)
			(layer "B.Fab")
			(hide yes)
			(effects
				(font
					(size 1.016 1.016)
					(thickness 0.1524)
				)
				(justify mirror)
			)
		)
		(property "Device Type" "C0201H13"
			(at 2.8321 -3.2639 90)
			(unlocked yes)
			(layer "B.Fab")
			(hide yes)
			(effects
				(font
					(size 1.016 1.016)
					(thickness 0.1524)
				)
				(justify mirror)
			)
		)
		(duplicate_pad_numbers_are_jumpers no)
		(fp_rect
			(start 0.2794 0.6477)
			(end -0.2794 -0.6477)
			(stroke
				(width 0)
				(type default)
			)
			(fill no)
			(layer "B.CrtYd")
		)
		(fp_rect
			(start 0.2794 0.6477)
			(end -0.2794 -0.6477)
			(stroke
				(width 0)
				(type default)
			)
			(fill no)
			(layer "B.Fab")
		)
		(pad "1" smd custom
			(at 0 -0.2794 270)
			(size 0.0762 0.0762)
			(layers "B.Cu" "B.Mask" "B.Paste")
			(net "PCE_AVDD")
			(options
				(clearance outline)
				(anchor circle)
			)
			(primitives
				(gr_poly
					(pts
						(arc
							(start 0.1524 0.127)
							(mid 0.137521 0.162921)
							(end 0.1016 0.1778)
						)
						(arc
							(start -0.1016 0.1778)
							(mid -0.137521 0.162921)
							(end -0.1524 0.127)
						)
						(arc
							(start -0.1524 -0.127)
							(mid -0.137521 -0.162921)
							(end -0.1016 -0.1778)
						)
						(arc
							(start 0.1016 -0.1778)
							(mid 0.137521 -0.162921)
							(end 0.1524 -0.127)
						)
					)
					(width 0)
					(fill yes)
				)
			)
		)
		(pad "2" smd custom
			(at 0 0.2794 270)
			(size 0.0762 0.0762)
			(layers "B.Cu" "B.Mask" "B.Paste")
			(net "GND")
			(options
				(clearance outline)
				(anchor circle)
			)
			(primitives
				(gr_poly
					(pts
						(arc
							(start 0.1524 0.127)
							(mid 0.137521 0.162921)
							(end 0.1016 0.1778)
						)
						(arc
							(start -0.1016 0.1778)
							(mid -0.137521 0.162921)
							(end -0.1524 0.127)
						)
						(arc
							(start -0.1524 -0.127)
							(mid -0.137521 -0.162921)
							(end -0.1016 -0.1778)
						)
						(arc
							(start 0.1016 -0.1778)
							(mid 0.137521 -0.162921)
							(end 0.1524 -0.127)
						)
					)
					(width 0)
					(fill yes)
				)
			)
		)
	)
	(footprint ""
		(layer "B.Cu")
		(at 210.5152 -60.3504)
		(property "Reference" "R630"
			(at 0 0 0)
			(layer "B.SilkS")
			(hide yes)
			(effects
				(font
					(size 1.27 1.27)
				)
				(justify mirror)
			)
		)
		(property "Value" "4K7R2F-GP"
			(at -0.064008 -3.993896 0)
			(unlocked yes)
			(layer "B.Fab")
			(hide yes)
			(effects
				(font
					(size 1.016 1.016)
					(thickness 0.1524)
				)
				(justify mirror)
			)
		)
		(property "Device Type" "R402H16"
			(at -0.064008 -5.517896 0)
			(unlocked yes)
			(layer "B.Fab")
			(hide yes)
			(effects
				(font
					(size 1.016 1.016)
					(thickness 0.1524)
				)
				(justify mirror)
			)
		)
		(duplicate_pad_numbers_are_jumpers no)
		(fp_line
			(start -0.508 -0.9398)
			(end 0.508 -0.9398)
			(stroke
				(width 0.1524)
				(type default)
			)
			(layer "B.SilkS")
		)
		(fp_line
			(start 0.508 -0.9398)
			(end 0.508 0.9398)
			(stroke
				(width 0.1524)
				(type default)
			)
			(layer "B.SilkS")
		)
		(fp_rect
			(start 0.508 0.9398)
			(end -0.508 -0.9398)
			(stroke
				(width 0)
				(type default)
			)
			(fill no)
			(layer "B.CrtYd")
		)
		(fp_rect
			(start 0.508 0.9398)
			(end -0.508 -0.9398)
			(stroke
				(width 0)
				(type default)
			)
			(fill no)
			(layer "B.Fab")
		)
		(pad "1" smd custom
			(at 0 -0.4445 180)
			(size 0.1397 0.1397)
			(layers "B.Cu" "B.Mask" "B.Paste")
			(net "P1V8")
			(options
				(clearance outline)
				(anchor circle)
			)
			(primitives
				(gr_poly
					(pts
						(arc
							(start -0.1778 0.2794)
							(mid -0.249642 0.249642)
							(end -0.2794 0.1778)
						)
						(arc
							(start -0.2794 -0.1778)
							(mid -0.249642 -0.249642)
							(end -0.1778 -0.2794)
						)
						(arc
							(start 0.1778 -0.2794)
							(mid 0.249642 -0.249642)
							(end 0.2794 -0.1778)
						)
						(arc
							(start 0.2794 0.1778)
							(mid 0.249642 0.249642)
							(end 0.1778 0.2794)
						)
					)
					(width 0)
					(fill yes)
				)
			)
		)
		(pad "2" smd custom
			(at 0 0.4445 180)
			(size 0.1397 0.1397)
			(layers "B.Cu" "B.Mask" "B.Paste")
			(net "ICE1_TDI")
			(options
				(clearance outline)
				(anchor circle)
			)
			(primitives
				(gr_poly
					(pts
						(arc
							(start -0.1778 0.2794)
							(mid -0.249642 0.249642)
							(end -0.2794 0.1778)
						)
						(arc
							(start -0.2794 -0.1778)
							(mid -0.249642 -0.249642)
							(end -0.1778 -0.2794)
						)
						(arc
							(start 0.1778 -0.2794)
							(mid 0.249642 -0.249642)
							(end 0.2794 -0.1778)
						)
						(arc
							(start 0.2794 0.1778)
							(mid 0.249642 0.249642)
							(end 0.1778 0.2794)
						)
					)
					(width 0)
					(fill yes)
				)
			)
		)
	)
	(footprint ""
		(layer "B.Cu")
		(at 197.5866 -46.2788 90)
		(property "Reference" "R683"
			(at 0 0 90)
			(layer "B.SilkS")
			(hide yes)
			(effects
				(font
					(size 1.27 1.27)
				)
				(justify mirror)
			)
		)
		(property "Value" "10R2F-L-GP"
			(at -0.064008 -3.993896 90)
			(unlocked yes)
			(layer "B.Fab")
			(hide yes)
			(effects
				(font
					(size 1.016 1.016)
					(thickness 0.1524)
				)
				(justify mirror)
			)
		)
		(property "Device Type" "R402H14"
			(at -0.064008 -5.517896 90)
			(unlocked yes)
			(layer "B.Fab")
			(hide yes)
			(effects
				(font
					(size 1.016 1.016)
					(thickness 0.1524)
				)
				(justify mirror)
			)
		)
		(duplicate_pad_numbers_are_jumpers no)
		(fp_line
			(start 0.508 -0.9398)
			(end 0.508 0.9398)
			(stroke
				(width 0.1524)
				(type default)
			)
			(layer "B.SilkS")
		)
		(fp_line
			(start -0.508 -0.9398)
			(end 0.508 -0.9398)
			(stroke
				(width 0.1524)
				(type default)
			)
			(layer "B.SilkS")
		)
		(fp_rect
			(start 0.508 0.9398)
			(end -0.508 -0.9398)
			(stroke
				(width 0)
				(type default)
			)
			(fill no)
			(layer "B.CrtYd")
		)
		(fp_rect
			(start 0.508 0.9398)
			(end -0.508 -0.9398)
			(stroke
				(width 0)
				(type default)
			)
			(fill no)
			(layer "B.Fab")
		)
		(pad "1" smd custom
			(at 0 -0.4445 270)
			(size 0.1397 0.1397)
			(layers "B.Cu" "B.Mask" "B.Paste")
			(net "P1V8")
			(options
				(clearance outline)
				(anchor circle)
			)
			(primitives
				(gr_poly
					(pts
						(arc
							(start -0.1778 0.2794)
							(mid -0.249642 0.249642)
							(end -0.2794 0.1778)
						)
						(arc
							(start -0.2794 -0.1778)
							(mid -0.249642 -0.249642)
							(end -0.1778 -0.2794)
						)
						(arc
							(start 0.1778 -0.2794)
							(mid 0.249642 -0.249642)
							(end 0.2794 -0.1778)
						)
						(arc
							(start 0.2794 0.1778)
							(mid 0.249642 0.249642)
							(end 0.1778 0.2794)
						)
					)
					(width 0)
					(fill yes)
				)
			)
		)
		(pad "2" smd custom
			(at 0 0.4445 270)
			(size 0.1397 0.1397)
			(layers "B.Cu" "B.Mask" "B.Paste")
			(net "VDDA_SAS_REF_CLK")
			(options
				(clearance outline)
				(anchor circle)
			)
			(primitives
				(gr_poly
					(pts
						(arc
							(start -0.1778 0.2794)
							(mid -0.249642 0.249642)
							(end -0.2794 0.1778)
						)
						(arc
							(start -0.2794 -0.1778)
							(mid -0.249642 -0.249642)
							(end -0.1778 -0.2794)
						)
						(arc
							(start 0.1778 -0.2794)
							(mid 0.249642 -0.249642)
							(end 0.2794 -0.1778)
						)
						(arc
							(start 0.2794 0.1778)
							(mid 0.249642 0.249642)
							(end 0.1778 0.2794)
						)
					)
					(width 0)
					(fill yes)
				)
			)
		)
	)
	(footprint ""
		(layer "B.Cu")
		(at 34.8234 -150.8252 180)
		(property "Reference" "C94"
			(at 0 0 0)
			(layer "B.SilkS")
			(hide yes)
			(effects
				(font
					(size 1.27 1.27)
				)
				(justify mirror)
			)
		)
		(property "Value" "SC100P50V2JN-3GP"
			(at -1.1811 -2.7051 180)
			(unlocked yes)
			(layer "B.Fab")
			(hide yes)
			(effects
				(font
					(size 1.016 1.016)
					(thickness 0.1524)
				)
				(justify mirror)
			)
		)
		(property "Device Type" "C402H22"
			(at -1.1811 -4.2291 180)
			(unlocked yes)
			(layer "B.Fab")
			(hide yes)
			(effects
				(font
					(size 1.016 1.016)
					(thickness 0.1524)
				)
				(justify mirror)
			)
		)
		(duplicate_pad_numbers_are_jumpers no)
		(fp_rect
			(start 0.4318 0.9525)
			(end -0.4318 -0.9525)
			(stroke
				(width 0)
				(type default)
			)
			(fill no)
			(layer "B.CrtYd")
		)
		(fp_rect
			(start 0.4318 0.9525)
			(end -0.4318 -0.9525)
			(stroke
				(width 0)
				(type default)
			)
			(fill no)
			(layer "B.Fab")
		)
		(pad "1" smd custom
			(at 0 -0.4445)
			(size 0.1524 0.1524)
			(layers "B.Cu" "B.Mask" "B.Paste")
			(net "MPLLAV33")
			(options
				(clearance outline)
				(anchor circle)
			)
			(primitives
				(gr_poly
					(pts
						(arc
							(start 0.3048 0.2032)
							(mid 0.275042 0.275042)
							(end 0.2032 0.3048)
						)
						(arc
							(start -0.2032 0.3048)
							(mid -0.275042 0.275042)
							(end -0.3048 0.2032)
						)
						(arc
							(start -0.3048 -0.2032)
							(mid -0.275042 -0.275042)
							(end -0.2032 -0.3048)
						)
						(arc
							(start 0.2032 -0.3048)
							(mid 0.275042 -0.275042)
							(end 0.3048 -0.2032)
						)
					)
					(width 0)
					(fill yes)
				)
			)
		)
		(pad "2" smd custom
			(at 0 0.4445)
			(size 0.1524 0.1524)
			(layers "B.Cu" "B.Mask" "B.Paste")
			(net "GND")
			(options
				(clearance outline)
				(anchor circle)
			)
			(primitives
				(gr_poly
					(pts
						(arc
							(start 0.3048 0.2032)
							(mid 0.275042 0.275042)
							(end 0.2032 0.3048)
						)
						(arc
							(start -0.2032 0.3048)
							(mid -0.275042 0.275042)
							(end -0.3048 0.2032)
						)
						(arc
							(start -0.3048 -0.2032)
							(mid -0.275042 -0.275042)
							(end -0.2032 -0.3048)
						)
						(arc
							(start 0.2032 -0.3048)
							(mid 0.275042 -0.275042)
							(end 0.3048 -0.2032)
						)
					)
					(width 0)
					(fill yes)
				)
			)
		)
	)
	(footprint ""
		(layer "B.Cu")
		(at 179.4764 -77.1652)
		(property "Reference" "TP106"
			(at 0 0 0)
			(layer "B.SilkS")
			(hide yes)
			(effects
				(font
					(size 1.27 1.27)
				)
				(justify mirror)
			)
		)
		(property "Value" "TPAD28-2-GP"
			(at 0.0127 -1.6637 0)
			(unlocked yes)
			(layer "B.Fab")
			(hide yes)
			(effects
				(font
					(size 1.016 1.016)
					(thickness 0.1524)
				)
				(justify mirror)
			)
		)
		(property "Device Type" "TPAD28"
			(at 0.0127 -3.1877 0)
			(unlocked yes)
			(layer "B.Fab")
			(hide yes)
			(effects
				(font
					(size 1.016 1.016)
					(thickness 0.1524)
				)
				(justify mirror)
			)
		)
		(duplicate_pad_numbers_are_jumpers no)
		(fp_poly
			(pts
				(arc
					(start 0.3556 0)
					(mid -0.3556 0)
					(end 0.3556 0)
				)
			)
			(stroke
				(width 0)
				(type default)
			)
			(fill no)
			(layer "B.CrtYd")
		)
		(fp_poly
			(pts
				(arc
					(start 0.6096 0)
					(mid -0.6096 0)
					(end 0.6096 0)
				)
			)
			(stroke
				(width 0)
				(type default)
			)
			(fill no)
			(layer "B.Fab")
		)
		(pad "1" smd circle
			(at 0 0 180)
			(size 0.7112 0.7112)
			(layers "B.Cu" "B.Mask" "B.Paste")
			(net "IOC_GPIO_21")
		)
	)
	(footprint ""
		(layer "B.Cu")
		(at 83.198208 -56.231536)
		(property "Reference" "C29"
			(at 0 0 0)
			(layer "B.SilkS")
			(hide yes)
			(effects
				(font
					(size 1.27 1.27)
				)
				(justify mirror)
			)
		)
		(property "Value" "SC2D2U25V5KX-2-GP"
			(at 0.0762 -6.1214 0)
			(unlocked yes)
			(layer "B.Fab")
			(hide yes)
			(effects
				(font
					(size 1.016 1.016)
					(thickness 0.1524)
				)
				(justify mirror)
			)
		)
		(property "Device Type" "C805H54"
			(at 0.0762 -8.1534 0)
			(unlocked yes)
			(layer "B.Fab")
			(hide yes)
			(effects
				(font
					(size 1.016 1.016)
					(thickness 0.1524)
				)
				(justify mirror)
			)
		)
		(duplicate_pad_numbers_are_jumpers no)
		(fp_line
			(start -0.635 0)
			(end 0.635 0)
			(stroke
				(width 0.508)
				(type default)
			)
			(layer "B.SilkS")
		)
		(fp_rect
			(start 0.9652 1.778)
			(end -0.9652 -1.778)
			(stroke
				(width 0)
				(type default)
			)
			(fill no)
			(layer "B.CrtYd")
		)
		(fp_poly
			(pts
				(xy 0.9652 -1.778) (xy -0.9652 -1.778) (xy -0.9652 1.778) (xy 0.9652 1.778)
			)
			(stroke
				(width 0)
				(type default)
			)
			(fill no)
			(layer "B.Fab")
		)
		(pad "1" smd rect
			(at 0 -0.9652 180)
			(size 1.397 1.143)
			(layers "B.Cu" "B.Mask" "B.Paste")
			(net "P3V3_STBY")
		)
		(pad "2" smd rect
			(at 0 0.9652 180)
			(size 1.397 1.143)
			(layers "B.Cu" "B.Mask" "B.Paste")
			(net "GND")
		)
	)
	(footprint ""
		(layer "B.Cu")
		(at 197.5104 -113.538 180)
		(property "Reference" "C261"
			(at 0 0 0)
			(layer "B.SilkS")
			(hide yes)
			(effects
				(font
					(size 1.27 1.27)
				)
				(justify mirror)
			)
		)
		(property "Value" "SC22U6D3V6KX-2-GP"
			(at 0.0762 -5.1308 180)
			(unlocked yes)
			(layer "B.Fab")
			(hide yes)
			(effects
				(font
					(size 1.016 1.016)
					(thickness 0.1524)
				)
				(justify mirror)
			)
		)
		(property "Device Type" "C1206H71"
			(at 0.127 -6.6548 180)
			(unlocked yes)
			(layer "B.Fab")
			(hide yes)
			(effects
				(font
					(size 1.016 1.016)
					(thickness 0.1524)
				)
				(justify mirror)
			)
		)
		(duplicate_pad_numbers_are_jumpers no)
		(fp_line
			(start 1.016 2.2352)
			(end 1.016 0.8382)
			(stroke
				(width 0.1524)
				(type default)
			)
			(layer "B.SilkS")
		)
		(fp_line
			(start 1.016 -0.8382)
			(end 1.016 -2.2352)
			(stroke
				(width 0.1524)
				(type default)
			)
			(layer "B.SilkS")
		)
		(fp_line
			(start 1.016 -2.2352)
			(end -1.016 -2.2352)
			(stroke
				(width 0.1524)
				(type default)
			)
			(layer "B.SilkS")
		)
		(fp_line
			(start -1.016 2.2352)
			(end 1.016 2.2352)
			(stroke
				(width 0.1524)
				(type default)
			)
			(layer "B.SilkS")
		)
		(fp_line
			(start -1.016 0.8382)
			(end -1.016 2.2352)
			(stroke
				(width 0.1524)
				(type default)
			)
			(layer "B.SilkS")
		)
		(fp_line
			(start -1.016 -2.2352)
			(end -1.016 -0.8382)
			(stroke
				(width 0.1524)
				(type default)
			)
			(layer "B.SilkS")
		)
		(fp_rect
			(start 1.0922 2.3114)
			(end -1.0922 -2.3114)
			(stroke
				(width 0)
				(type default)
			)
			(fill no)
			(layer "B.CrtYd")
		)
		(fp_poly
			(pts
				(xy -1.0922 -2.3114) (xy -1.0922 2.3114) (xy 1.0922 2.3114) (xy 1.0922 -2.3114)
			)
			(stroke
				(width 0)
				(type default)
			)
			(fill no)
			(layer "B.Fab")
		)
		(pad "1" smd rect
			(at 0 -1.397)
			(size 1.651 1.27)
			(layers "B.Cu" "B.Mask" "B.Paste")
			(net "P0V975")
		)
		(pad "2" smd rect
			(at 0 1.397)
			(size 1.651 1.27)
			(layers "B.Cu" "B.Mask" "B.Paste")
			(net "GND")
		)
	)
	(footprint ""
		(layer "B.Cu")
		(at 60.213748 -154.031188 -90)
		(property "Reference" "R394"
			(at 0 0 90)
			(layer "B.SilkS")
			(hide yes)
			(effects
				(font
					(size 1.27 1.27)
				)
				(justify mirror)
			)
		)
		(property "Value" "4K7R2F-GP"
			(at -0.064008 -3.993896 270)
			(unlocked yes)
			(layer "B.Fab")
			(hide yes)
			(effects
				(font
					(size 1.016 1.016)
					(thickness 0.1524)
				)
				(justify mirror)
			)
		)
		(property "Device Type" "R402H16"
			(at -0.064008 -5.517896 270)
			(unlocked yes)
			(layer "B.Fab")
			(hide yes)
			(effects
				(font
					(size 1.016 1.016)
					(thickness 0.1524)
				)
				(justify mirror)
			)
		)
		(duplicate_pad_numbers_are_jumpers no)
		(fp_line
			(start -0.508 -0.9398)
			(end 0.508 -0.9398)
			(stroke
				(width 0.1524)
				(type default)
			)
			(layer "B.SilkS")
		)
		(fp_line
			(start 0.508 -0.9398)
			(end 0.508 0.9398)
			(stroke
				(width 0.1524)
				(type default)
			)
			(layer "B.SilkS")
		)
		(fp_rect
			(start 0.508 0.9398)
			(end -0.508 -0.9398)
			(stroke
				(width 0)
				(type default)
			)
			(fill no)
			(layer "B.CrtYd")
		)
		(fp_rect
			(start 0.508 0.9398)
			(end -0.508 -0.9398)
			(stroke
				(width 0)
				(type default)
			)
			(fill no)
			(layer "B.Fab")
		)
		(pad "1" smd custom
			(at 0 -0.4445 90)
			(size 0.1397 0.1397)
			(layers "B.Cu" "B.Mask" "B.Paste")
			(net "P3V3_STBY")
			(options
				(clearance outline)
				(anchor circle)
			)
			(primitives
				(gr_poly
					(pts
						(arc
							(start -0.1778 0.2794)
							(mid -0.249642 0.249642)
							(end -0.2794 0.1778)
						)
						(arc
							(start -0.2794 -0.1778)
							(mid -0.249642 -0.249642)
							(end -0.1778 -0.2794)
						)
						(arc
							(start 0.1778 -0.2794)
							(mid 0.249642 -0.249642)
							(end 0.2794 -0.1778)
						)
						(arc
							(start 0.2794 0.1778)
							(mid 0.249642 0.249642)
							(end 0.1778 0.2794)
						)
					)
					(width 0)
					(fill yes)
				)
			)
		)
		(pad "2" smd custom
			(at 0 0.4445 90)
			(size 0.1397 0.1397)
			(layers "B.Cu" "B.Mask" "B.Paste")
			(net "MAC2_TXD3")
			(options
				(clearance outline)
				(anchor circle)
			)
			(primitives
				(gr_poly
					(pts
						(arc
							(start -0.1778 0.2794)
							(mid -0.249642 0.249642)
							(end -0.2794 0.1778)
						)
						(arc
							(start -0.2794 -0.1778)
							(mid -0.249642 -0.249642)
							(end -0.1778 -0.2794)
						)
						(arc
							(start 0.1778 -0.2794)
							(mid 0.249642 -0.249642)
							(end 0.2794 -0.1778)
						)
						(arc
							(start 0.2794 0.1778)
							(mid 0.249642 0.249642)
							(end 0.1778 0.2794)
						)
					)
					(width 0)
					(fill yes)
				)
			)
		)
	)
	(footprint ""
		(layer "B.Cu")
		(at 52.5272 -135.70712)
		(property "Reference" "R607"
			(at 0 0 0)
			(layer "B.SilkS")
			(hide yes)
			(effects
				(font
					(size 1.27 1.27)
				)
				(justify mirror)
			)
		)
		(property "Value" "0R2J-2-GP"
			(at -0.064008 -3.993896 0)
			(unlocked yes)
			(layer "B.Fab")
			(hide yes)
			(effects
				(font
					(size 1.016 1.016)
					(thickness 0.1524)
				)
				(justify mirror)
			)
		)
		(property "Device Type" "R402H16"
			(at -0.064008 -5.517896 0)
			(unlocked yes)
			(layer "B.Fab")
			(hide yes)
			(effects
				(font
					(size 1.016 1.016)
					(thickness 0.1524)
				)
				(justify mirror)
			)
		)
		(duplicate_pad_numbers_are_jumpers no)
		(fp_line
			(start -0.508 -0.9398)
			(end 0.508 -0.9398)
			(stroke
				(width 0.1524)
				(type default)
			)
			(layer "B.SilkS")
		)
		(fp_line
			(start 0.508 -0.9398)
			(end 0.508 0.9398)
			(stroke
				(width 0.1524)
				(type default)
			)
			(layer "B.SilkS")
		)
		(fp_rect
			(start 0.508 0.9398)
			(end -0.508 -0.9398)
			(stroke
				(width 0)
				(type default)
			)
			(fill no)
			(layer "B.CrtYd")
		)
		(fp_rect
			(start 0.508 0.9398)
			(end -0.508 -0.9398)
			(stroke
				(width 0)
				(type default)
			)
			(fill no)
			(layer "B.Fab")
		)
		(pad "1" smd custom
			(at 0 -0.4445 180)
			(size 0.1397 0.1397)
			(layers "B.Cu" "B.Mask" "B.Paste")
			(net "SYS_RESET_N_OUT_R")
			(options
				(clearance outline)
				(anchor circle)
			)
			(primitives
				(gr_poly
					(pts
						(arc
							(start -0.1778 0.2794)
							(mid -0.249642 0.249642)
							(end -0.2794 0.1778)
						)
						(arc
							(start -0.2794 -0.1778)
							(mid -0.249642 -0.249642)
							(end -0.1778 -0.2794)
						)
						(arc
							(start 0.1778 -0.2794)
							(mid 0.249642 -0.249642)
							(end 0.2794 -0.1778)
						)
						(arc
							(start 0.2794 0.1778)
							(mid 0.249642 0.249642)
							(end 0.1778 0.2794)
						)
					)
					(width 0)
					(fill yes)
				)
			)
		)
		(pad "2" smd custom
			(at 0 0.4445 180)
			(size 0.1397 0.1397)
			(layers "B.Cu" "B.Mask" "B.Paste")
			(net "SYS_RESET_N_OUT")
			(options
				(clearance outline)
				(anchor circle)
			)
			(primitives
				(gr_poly
					(pts
						(arc
							(start -0.1778 0.2794)
							(mid -0.249642 0.249642)
							(end -0.2794 0.1778)
						)
						(arc
							(start -0.2794 -0.1778)
							(mid -0.249642 -0.249642)
							(end -0.1778 -0.2794)
						)
						(arc
							(start 0.1778 -0.2794)
							(mid 0.249642 -0.249642)
							(end 0.2794 -0.1778)
						)
						(arc
							(start 0.2794 0.1778)
							(mid 0.249642 0.249642)
							(end 0.1778 0.2794)
						)
					)
					(width 0)
					(fill yes)
				)
			)
		)
	)
	(footprint ""
		(layer "B.Cu")
		(at 191.68999 -19.177 -90)
		(property "Reference" "C488"
			(at 0 0 90)
			(layer "B.SilkS")
			(hide yes)
			(effects
				(font
					(size 1.27 1.27)
				)
				(justify mirror)
			)
		)
		(property "Value" "SCD01U16V1KX-GP"
			(at 2.8321 -1.7399 270)
			(unlocked yes)
			(layer "B.Fab")
			(hide yes)
			(effects
				(font
					(size 1.016 1.016)
					(thickness 0.1524)
				)
				(justify mirror)
			)
		)
		(property "Device Type" "C0201H13"
			(at 2.8321 -3.2639 270)
			(unlocked yes)
			(layer "B.Fab")
			(hide yes)
			(effects
				(font
					(size 1.016 1.016)
					(thickness 0.1524)
				)
				(justify mirror)
			)
		)
		(duplicate_pad_numbers_are_jumpers no)
		(fp_rect
			(start 0.2794 0.6477)
			(end -0.2794 -0.6477)
			(stroke
				(width 0)
				(type default)
			)
			(fill no)
			(layer "B.CrtYd")
		)
		(fp_rect
			(start 0.2794 0.6477)
			(end -0.2794 -0.6477)
			(stroke
				(width 0)
				(type default)
			)
			(fill no)
			(layer "B.Fab")
		)
		(pad "1" smd custom
			(at 0 -0.2794 90)
			(size 0.0762 0.0762)
			(layers "B.Cu" "B.Mask" "B.Paste")
			(net "PHY_CON_A_TO_IOC_0_DN")
			(options
				(clearance outline)
				(anchor circle)
			)
			(primitives
				(gr_poly
					(pts
						(arc
							(start 0.1524 0.127)
							(mid 0.137521 0.162921)
							(end 0.1016 0.1778)
						)
						(arc
							(start -0.1016 0.1778)
							(mid -0.137521 0.162921)
							(end -0.1524 0.127)
						)
						(arc
							(start -0.1524 -0.127)
							(mid -0.137521 -0.162921)
							(end -0.1016 -0.1778)
						)
						(arc
							(start 0.1016 -0.1778)
							(mid 0.137521 -0.162921)
							(end 0.1524 -0.127)
						)
					)
					(width 0)
					(fill yes)
				)
			)
		)
		(pad "2" smd custom
			(at 0 0.2794 90)
			(size 0.0762 0.0762)
			(layers "B.Cu" "B.Mask" "B.Paste")
			(net "PHY_CON_A_TO_IOC_0_DN_C")
			(options
				(clearance outline)
				(anchor circle)
			)
			(primitives
				(gr_poly
					(pts
						(arc
							(start 0.1524 0.127)
							(mid 0.137521 0.162921)
							(end 0.1016 0.1778)
						)
						(arc
							(start -0.1016 0.1778)
							(mid -0.137521 0.162921)
							(end -0.1524 0.127)
						)
						(arc
							(start -0.1524 -0.127)
							(mid -0.137521 -0.162921)
							(end -0.1016 -0.1778)
						)
						(arc
							(start 0.1016 -0.1778)
							(mid 0.137521 -0.162921)
							(end 0.1524 -0.127)
						)
					)
					(width 0)
					(fill yes)
				)
			)
		)
	)
	(footprint ""
		(layer "B.Cu")
		(at 45.3644 -135.6614 180)
		(property "Reference" "R154"
			(at 0 0 0)
			(layer "B.SilkS")
			(hide yes)
			(effects
				(font
					(size 1.27 1.27)
				)
				(justify mirror)
			)
		)
		(property "Value" "0R2J-2-GP"
			(at -0.064008 -3.993896 180)
			(unlocked yes)
			(layer "B.Fab")
			(hide yes)
			(effects
				(font
					(size 1.016 1.016)
					(thickness 0.1524)
				)
				(justify mirror)
			)
		)
		(property "Device Type" "R402H16"
			(at -0.064008 -5.517896 180)
			(unlocked yes)
			(layer "B.Fab")
			(hide yes)
			(effects
				(font
					(size 1.016 1.016)
					(thickness 0.1524)
				)
				(justify mirror)
			)
		)
		(duplicate_pad_numbers_are_jumpers no)
		(fp_line
			(start 0.508 -0.9398)
			(end 0.508 0.9398)
			(stroke
				(width 0.1524)
				(type default)
			)
			(layer "B.SilkS")
		)
		(fp_line
			(start -0.508 -0.9398)
			(end 0.508 -0.9398)
			(stroke
				(width 0.1524)
				(type default)
			)
			(layer "B.SilkS")
		)
		(fp_rect
			(start 0.508 0.9398)
			(end -0.508 -0.9398)
			(stroke
				(width 0)
				(type default)
			)
			(fill no)
			(layer "B.CrtYd")
		)
		(fp_rect
			(start 0.508 0.9398)
			(end -0.508 -0.9398)
			(stroke
				(width 0)
				(type default)
			)
			(fill no)
			(layer "B.Fab")
		)
		(pad "1" smd custom
			(at 0 -0.4445)
			(size 0.1397 0.1397)
			(layers "B.Cu" "B.Mask" "B.Paste")
			(net "I2C_IOM_SDA")
			(options
				(clearance outline)
				(anchor circle)
			)
			(primitives
				(gr_poly
					(pts
						(arc
							(start -0.1778 0.2794)
							(mid -0.249642 0.249642)
							(end -0.2794 0.1778)
						)
						(arc
							(start -0.2794 -0.1778)
							(mid -0.249642 -0.249642)
							(end -0.1778 -0.2794)
						)
						(arc
							(start 0.1778 -0.2794)
							(mid 0.249642 -0.249642)
							(end 0.2794 -0.1778)
						)
						(arc
							(start 0.2794 0.1778)
							(mid 0.249642 0.249642)
							(end 0.1778 0.2794)
						)
					)
					(width 0)
					(fill yes)
				)
			)
		)
		(pad "2" smd custom
			(at 0 0.4445)
			(size 0.1397 0.1397)
			(layers "B.Cu" "B.Mask" "B.Paste")
			(net "BMC_SMB1_DAT")
			(options
				(clearance outline)
				(anchor circle)
			)
			(primitives
				(gr_poly
					(pts
						(arc
							(start -0.1778 0.2794)
							(mid -0.249642 0.249642)
							(end -0.2794 0.1778)
						)
						(arc
							(start -0.2794 -0.1778)
							(mid -0.249642 -0.249642)
							(end -0.1778 -0.2794)
						)
						(arc
							(start 0.1778 -0.2794)
							(mid 0.249642 -0.249642)
							(end 0.2794 -0.1778)
						)
						(arc
							(start 0.2794 0.1778)
							(mid 0.249642 0.249642)
							(end 0.1778 0.2794)
						)
					)
					(width 0)
					(fill yes)
				)
			)
		)
	)
	(footprint ""
		(layer "B.Cu")
		(at 192.4177 -63.7794 90)
		(property "Reference" "C419"
			(at 0 0 90)
			(layer "B.SilkS")
			(hide yes)
			(effects
				(font
					(size 1.27 1.27)
				)
				(justify mirror)
			)
		)
		(property "Value" "SCD1U6D3V1KX-GP"
			(at 2.8321 -1.7399 90)
			(unlocked yes)
			(layer "B.Fab")
			(hide yes)
			(effects
				(font
					(size 1.016 1.016)
					(thickness 0.1524)
				)
				(justify mirror)
			)
		)
		(property "Device Type" "C0201H13"
			(at 2.8321 -3.2639 90)
			(unlocked yes)
			(layer "B.Fab")
			(hide yes)
			(effects
				(font
					(size 1.016 1.016)
					(thickness 0.1524)
				)
				(justify mirror)
			)
		)
		(duplicate_pad_numbers_are_jumpers no)
		(fp_rect
			(start 0.2794 0.6477)
			(end -0.2794 -0.6477)
			(stroke
				(width 0)
				(type default)
			)
			(fill no)
			(layer "B.CrtYd")
		)
		(fp_rect
			(start 0.2794 0.6477)
			(end -0.2794 -0.6477)
			(stroke
				(width 0)
				(type default)
			)
			(fill no)
			(layer "B.Fab")
		)
		(pad "1" smd custom
			(at 0 -0.2794 270)
			(size 0.0762 0.0762)
			(layers "B.Cu" "B.Mask" "B.Paste")
			(net "P0V975")
			(options
				(clearance outline)
				(anchor circle)
			)
			(primitives
				(gr_poly
					(pts
						(arc
							(start 0.1524 0.127)
							(mid 0.137521 0.162921)
							(end 0.1016 0.1778)
						)
						(arc
							(start -0.1016 0.1778)
							(mid -0.137521 0.162921)
							(end -0.1524 0.127)
						)
						(arc
							(start -0.1524 -0.127)
							(mid -0.137521 -0.162921)
							(end -0.1016 -0.1778)
						)
						(arc
							(start 0.1016 -0.1778)
							(mid 0.137521 -0.162921)
							(end 0.1524 -0.127)
						)
					)
					(width 0)
					(fill yes)
				)
			)
		)
		(pad "2" smd custom
			(at 0 0.2794 270)
			(size 0.0762 0.0762)
			(layers "B.Cu" "B.Mask" "B.Paste")
			(net "GND")
			(options
				(clearance outline)
				(anchor circle)
			)
			(primitives
				(gr_poly
					(pts
						(arc
							(start 0.1524 0.127)
							(mid 0.137521 0.162921)
							(end 0.1016 0.1778)
						)
						(arc
							(start -0.1016 0.1778)
							(mid -0.137521 0.162921)
							(end -0.1524 0.127)
						)
						(arc
							(start -0.1524 -0.127)
							(mid -0.137521 -0.162921)
							(end -0.1016 -0.1778)
						)
						(arc
							(start 0.1016 -0.1778)
							(mid 0.137521 -0.162921)
							(end 0.1524 -0.127)
						)
					)
					(width 0)
					(fill yes)
				)
			)
		)
	)
	(gr_line
		(start 18.034508 -144.16151)
		(end 18.434558 -143.76146)
		(stroke
			(width 0.06223)
			(type default)
		)
		(layer "F.Cu")
	)
	(gr_line
		(start 18.434558 -144.56156)
		(end 18.834608 -144.16151)
		(stroke
			(width 0.06223)
			(type default)
		)
		(layer "F.Cu")
	)
	(gr_line
		(start 21.63445 -148.561552)
		(end 22.0345 -148.961602)
		(stroke
			(width 0.06223)
			(type default)
		)
		(layer "F.Cu")
	)
	(gr_line
		(start 21.63445 -147.761452)
		(end 22.0345 -148.161502)
		(stroke
			(width 0.06223)
			(type default)
		)
		(layer "F.Cu")
	)
	(gr_arc
		(start 32.38246 -144.957546)
		(mid 32.297427 -144.752257)
		(end 32.092138 -144.667224)
		(stroke
			(width 0.06223)
			(type default)
		)
		(layer "F.Cu")
	)
	(gr_arc
		(start 33.174178 -144.687544)
		(mid 32.904907 -144.769663)
		(end 32.78886 -145.026126)
		(stroke
			(width 0.06223)
			(type default)
		)
		(layer "F.Cu")
	)
	(gr_line
		(start 36.798504 -150.076916)
		(end 36.96716 -149.908514)
		(stroke
			(width 0.06223)
			(type default)
		)
		(layer "F.Cu")
	)
	(gr_line
		(start 36.798504 -149.141942)
		(end 36.868608 -149.212046)
		(stroke
			(width 0.06223)
			(type default)
		)
		(layer "F.Cu")
	)
	(gr_arc
		(start 36.868608 -149.212046)
		(mid 37.051803 -149.334453)
		(end 37.267896 -149.3774)
		(stroke
			(width 0.06223)
			(type default)
		)
		(layer "F.Cu")
	)
	(gr_arc
		(start 37.267896 -149.7838)
		(mid 37.105114 -149.816228)
		(end 36.96716 -149.908514)
		(stroke
			(width 0.06223)
			(type default)
		)
		(layer "F.Cu")
	)
	(gr_arc
		(start 37.695886 -146.220688)
		(mid 37.865172 -146.380484)
		(end 38.090602 -146.43862)
		(stroke
			(width 0.06223)
			(type default)
		)
		(layer "F.Cu")
	)
	(gr_arc
		(start 38.065456 -146.84502)
		(mid 37.824083 -146.933011)
		(end 37.695886 -147.155662)
		(stroke
			(width 0.06223)
			(type default)
		)
		(layer "F.Cu")
	)
	(gr_arc
		(start 38.955472 -148.771356)
		(mid 39.115218 -148.739487)
		(end 39.25062 -148.648928)
		(stroke
			(width 0.06223)
			(type default)
		)
		(layer "F.Cu")
	)
	(gr_arc
		(start 38.9636 -144.81175)
		(mid 39.162326 -144.754376)
		(end 39.299896 -144.599914)
		(stroke
			(width 0.06223)
			(type default)
		)
		(layer "F.Cu")
	)
	(gr_arc
		(start 39.022274 -146.43862)
		(mid 39.205413 -146.370784)
		(end 39.299896 -146.19986)
		(stroke
			(width 0.06223)
			(type default)
		)
		(layer "F.Cu")
	)
	(gr_arc
		(start 39.054024 -146.846544)
		(mid 39.038294 -146.845402)
		(end 39.022528 -146.84502)
		(stroke
			(width 0.06223)
			(type default)
		)
		(layer "F.Cu")
	)
	(gr_arc
		(start 39.164006 -149.264116)
		(mid 39.06832 -149.200228)
		(end 38.955472 -149.177756)
		(stroke
			(width 0.06223)
			(type default)
		)
		(layer "F.Cu")
	)
	(gr_line
		(start 39.164006 -149.264116)
		(end 39.299896 -149.400006)
		(stroke
			(width 0.06223)
			(type default)
		)
		(layer "F.Cu")
	)
	(gr_line
		(start 39.25062 -148.648928)
		(end 39.299896 -148.599906)
		(stroke
			(width 0.06223)
			(type default)
		)
		(layer "F.Cu")
	)
	(gr_arc
		(start 39.299896 -146.99996)
		(mid 39.194955 -146.894406)
		(end 39.054024 -146.846544)
		(stroke
			(width 0.06223)
			(type default)
		)
		(layer "F.Cu")
	)
	(gr_arc
		(start 39.299896 -145.400014)
		(mid 39.154765 -145.266516)
		(end 38.9636 -145.21815)
		(stroke
			(width 0.06223)
			(type default)
		)
		(layer "F.Cu")
	)
	(gr_line
		(start 55.299864 -149.400006)
		(end 55.734458 -149.8346)
		(stroke
			(width 0.072898)
			(type default)
		)
		(layer "F.Cu")
	)
	(gr_line
		(start 55.734458 -149.8346)
		(end 55.909718 -149.8346)
		(stroke
			(width 0.072898)
			(type default)
		)
		(layer "F.Cu")
	)
	(gr_line
		(start 56.099964 -149.400006)
		(end 56.209946 -149.509988)
		(stroke
			(width 0.072898)
			(type default)
		)
		(layer "F.Cu")
	)
	(gr_line
		(start 56.099964 -148.599906)
		(end 56.278018 -148.421852)
		(stroke
			(width 0.072898)
			(type default)
		)
		(layer "F.Cu")
	)
	(gr_line
		(start 56.099964 -147.80006)
		(end 56.278018 -147.978114)
		(stroke
			(width 0.072898)
			(type default)
		)
		(layer "F.Cu")
	)
	(gr_line
		(start 63.626746 -152.569418)
		(end 63.839852 -152.782524)
		(stroke
			(width 0.072898)
			(type default)
		)
		(layer "F.Cu")
	)
	(gr_line
		(start 63.626746 -152.125934)
		(end 63.833756 -151.918924)
		(stroke
			(width 0.072898)
			(type default)
		)
		(layer "F.Cu")
	)
	(gr_line
		(start 65.440306 -154.73299)
		(end 65.6717 -154.964384)
		(stroke
			(width 0.072898)
			(type default)
		)
		(layer "F.Cu")
	)
	(gr_line
		(start 65.440306 -154.289252)
		(end 65.6717 -154.057858)
		(stroke
			(width 0.072898)
			(type default)
		)
		(layer "F.Cu")
	)
	(gr_line
		(start 75.475084 -93.75013)
		(end 76.318872 -93.75013)
		(stroke
			(width 0.072898)
			(type default)
		)
		(layer "F.Cu")
	)
	(gr_line
		(start 75.475084 -92.95003)
		(end 76.32954 -92.95003)
		(stroke
			(width 0.072898)
			(type default)
		)
		(layer "F.Cu")
	)
	(gr_line
		(start 75.475084 -90.549984)
		(end 76.4159 -90.549984)
		(stroke
			(width 0.072898)
			(type default)
		)
		(layer "F.Cu")
	)
	(gr_line
		(start 75.475084 -89.750138)
		(end 76.313284 -89.750138)
		(stroke
			(width 0.072898)
			(type default)
		)
		(layer "F.Cu")
	)
	(gr_line
		(start 75.475084 -87.350092)
		(end 76.366624 -87.350092)
		(stroke
			(width 0.072898)
			(type default)
		)
		(layer "F.Cu")
	)
	(gr_line
		(start 75.475084 -86.549992)
		(end 76.281788 -86.549992)
		(stroke
			(width 0.072898)
			(type default)
		)
		(layer "F.Cu")
	)
	(gr_line
		(start 75.475084 -84.149946)
		(end 76.474574 -84.149946)
		(stroke
			(width 0.072898)
			(type default)
		)
		(layer "F.Cu")
	)
	(gr_line
		(start 75.475084 -83.3501)
		(end 76.341732 -83.3501)
		(stroke
			(width 0.072898)
			(type default)
		)
		(layer "F.Cu")
	)
	(gr_line
		(start 75.475084 -80.950054)
		(end 76.385928 -80.950054)
		(stroke
			(width 0.072898)
			(type default)
		)
		(layer "F.Cu")
	)
	(gr_line
		(start 75.475084 -80.149954)
		(end 76.341478 -80.149954)
		(stroke
			(width 0.072898)
			(type default)
		)
		(layer "F.Cu")
	)
	(gr_line
		(start 75.475084 -77.749908)
		(end 76.659232 -77.749908)
		(stroke
			(width 0.068326)
			(type default)
		)
		(layer "F.Cu")
	)
	(gr_line
		(start 75.475084 -76.950062)
		(end 76.659486 -76.950062)
		(stroke
			(width 0.068326)
			(type default)
		)
		(layer "F.Cu")
	)
	(gr_line
		(start 75.475084 -74.550016)
		(end 76.321666 -74.550016)
		(stroke
			(width 0.072898)
			(type default)
		)
		(layer "F.Cu")
	)
	(gr_line
		(start 75.475084 -73.749916)
		(end 76.293218 -73.749916)
		(stroke
			(width 0.072898)
			(type default)
		)
		(layer "F.Cu")
	)
	(gr_line
		(start 75.475084 -71.350124)
		(end 76.659232 -71.350124)
		(stroke
			(width 0.068326)
			(type default)
		)
		(layer "F.Cu")
	)
	(gr_line
		(start 75.475084 -70.550024)
		(end 76.659232 -70.550024)
		(stroke
			(width 0.068326)
			(type default)
		)
		(layer "F.Cu")
	)
	(gr_line
		(start 75.475084 -68.149978)
		(end 76.552552 -68.149978)
		(stroke
			(width 0.072898)
			(type default)
		)
		(layer "F.Cu")
	)
	(gr_line
		(start 75.475084 -67.350132)
		(end 76.546964 -67.350132)
		(stroke
			(width 0.072898)
			(type default)
		)
		(layer "F.Cu")
	)
	(gr_line
		(start 76.281788 -86.549992)
		(end 76.502514 -86.770718)
		(stroke
			(width 0.072898)
			(type default)
		)
		(layer "F.Cu")
	)
	(gr_line
		(start 76.293218 -73.749916)
		(end 76.48575 -73.942448)
		(stroke
			(width 0.072898)
			(type default)
		)
		(layer "F.Cu")
	)
	(gr_line
		(start 76.313284 -89.750138)
		(end 76.542646 -89.9795)
		(stroke
			(width 0.072898)
			(type default)
		)
		(layer "F.Cu")
	)
	(gr_line
		(start 76.318872 -93.75013)
		(end 76.502514 -93.566488)
		(stroke
			(width 0.072898)
			(type default)
		)
		(layer "F.Cu")
	)
	(gr_line
		(start 76.321666 -74.550016)
		(end 76.48575 -74.385932)
		(stroke
			(width 0.072898)
			(type default)
		)
		(layer "F.Cu")
	)
	(gr_line
		(start 76.32954 -92.95003)
		(end 76.502514 -93.123004)
		(stroke
			(width 0.072898)
			(type default)
		)
		(layer "F.Cu")
	)
	(gr_line
		(start 76.341478 -80.149954)
		(end 76.541884 -80.35036)
		(stroke
			(width 0.072898)
			(type default)
		)
		(layer "F.Cu")
	)
	(gr_line
		(start 76.341732 -83.3501)
		(end 76.586334 -83.594702)
		(stroke
			(width 0.072898)
			(type default)
		)
		(layer "F.Cu")
	)
	(gr_line
		(start 76.366624 -87.350092)
		(end 76.502514 -87.214202)
		(stroke
			(width 0.072898)
			(type default)
		)
		(layer "F.Cu")
	)
	(gr_line
		(start 76.385928 -80.950054)
		(end 76.541884 -80.794098)
		(stroke
			(width 0.072898)
			(type default)
		)
		(layer "F.Cu")
	)
	(gr_line
		(start 76.4159 -90.549984)
		(end 76.542646 -90.423238)
		(stroke
			(width 0.072898)
			(type default)
		)
		(layer "F.Cu")
	)
	(gr_line
		(start 76.474574 -84.149946)
		(end 76.586334 -84.038186)
		(stroke
			(width 0.072898)
			(type default)
		)
		(layer "F.Cu")
	)
	(gr_line
		(start 76.546964 -67.350132)
		(end 76.727812 -67.53098)
		(stroke
			(width 0.072898)
			(type default)
		)
		(layer "F.Cu")
	)
	(gr_line
		(start 76.552552 -68.149978)
		(end 76.727812 -67.974718)
		(stroke
			(width 0.072898)
			(type default)
		)
		(layer "F.Cu")
	)
	(gr_line
		(start 76.659232 -77.749908)
		(end 76.83754 -77.5716)
		(stroke
			(width 0.072898)
			(type default)
		)
		(layer "F.Cu")
	)
	(gr_line
		(start 76.659232 -71.350124)
		(end 76.83754 -71.171816)
		(stroke
			(width 0.072898)
			(type default)
		)
		(layer "F.Cu")
	)
	(gr_line
		(start 76.659232 -70.550024)
		(end 76.83754 -70.728332)
		(stroke
			(width 0.072898)
			(type default)
		)
		(layer "F.Cu")
	)
	(gr_line
		(start 76.659486 -76.950062)
		(end 76.83754 -77.128116)
		(stroke
			(width 0.072898)
			(type default)
		)
		(layer "F.Cu")
	)
	(gr_arc
		(start 76.995782 -80.397604)
		(mid 77.199454 -80.31324)
		(end 77.283818 -80.109568)
		(stroke
			(width 0.072898)
			(type default)
		)
		(layer "F.Cu")
	)
	(gr_arc
		(start 76.996544 -86.797642)
		(mid 77.199677 -86.713501)
		(end 77.283818 -86.510368)
		(stroke
			(width 0.072898)
			(type default)
		)
		(layer "F.Cu")
	)
	(gr_arc
		(start 77.00137 -73.991216)
		(mid 77.201091 -73.908489)
		(end 77.283818 -73.708768)
		(stroke
			(width 0.072898)
			(type default)
		)
		(layer "F.Cu")
	)
	(gr_arc
		(start 77.033628 -93.19768)
		(mid 77.210539 -93.124401)
		(end 77.283818 -92.94749)
		(stroke
			(width 0.072898)
			(type default)
		)
		(layer "F.Cu")
	)
	(gr_arc
		(start 77.059028 -67.60464)
		(mid 77.211513 -67.541479)
		(end 77.274674 -67.388994)
		(stroke
			(width 0.072898)
			(type default)
		)
		(layer "F.Cu")
	)
	(gr_arc
		(start 77.274674 -68.131436)
		(mid 77.211527 -67.978918)
		(end 77.059028 -67.91579)
		(stroke
			(width 0.072898)
			(type default)
		)
		(layer "F.Cu")
	)
	(gr_line
		(start 77.274674 -68.131436)
		(end 77.274674 -68.211192)
		(stroke
			(width 0.072898)
			(type default)
		)
		(layer "F.Cu")
	)
	(gr_line
		(start 77.274674 -67.322192)
		(end 77.274674 -67.388994)
		(stroke
			(width 0.072898)
			(type default)
		)
		(layer "F.Cu")
	)
	(gr_arc
		(start 77.283818 -93.75902)
		(mid 77.210548 -93.582086)
		(end 77.033628 -93.50883)
		(stroke
			(width 0.072898)
			(type default)
		)
		(layer "F.Cu")
	)
	(gr_line
		(start 77.283818 -93.75902)
		(end 77.283818 -93.800168)
		(stroke
			(width 0.072898)
			(type default)
		)
		(layer "F.Cu")
	)
	(gr_line
		(start 77.283818 -92.911168)
		(end 77.283818 -92.94749)
		(stroke
			(width 0.072898)
			(type default)
		)
		(layer "F.Cu")
	)
	(gr_arc
		(start 77.283818 -87.399368)
		(mid 77.198701 -87.193906)
		(end 76.993242 -87.108792)
		(stroke
			(width 0.072898)
			(type default)
		)
		(layer "F.Cu")
	)
	(gr_arc
		(start 77.283818 -80.998568)
		(mid 77.198922 -80.793658)
		(end 76.994004 -80.708754)
		(stroke
			(width 0.072898)
			(type default)
		)
		(layer "F.Cu")
	)
	(gr_arc
		(start 77.283818 -74.597768)
		(mid 77.197286 -74.388902)
		(end 76.988416 -74.302366)
		(stroke
			(width 0.072898)
			(type default)
		)
		(layer "F.Cu")
	)
	(gr_arc
		(start 77.832204 -70.798182)
		(mid 78.037133 -70.713297)
		(end 78.122018 -70.508368)
		(stroke
			(width 0.072898)
			(type default)
		)
		(layer "F.Cu")
	)
	(gr_arc
		(start 77.835252 -89.997534)
		(mid 78.038026 -89.913542)
		(end 78.122018 -89.710768)
		(stroke
			(width 0.072898)
			(type default)
		)
		(layer "F.Cu")
	)
	(gr_arc
		(start 77.838046 -77.203046)
		(mid 78.038845 -77.119873)
		(end 78.122018 -76.919074)
		(stroke
			(width 0.072898)
			(type default)
		)
		(layer "F.Cu")
	)
	(gr_arc
		(start 77.846428 -83.622896)
		(mid 78.0413 -83.542178)
		(end 78.122018 -83.347306)
		(stroke
			(width 0.072898)
			(type default)
		)
		(layer "F.Cu")
	)
	(gr_arc
		(start 78.122018 -90.599768)
		(mid 78.036752 -90.393949)
		(end 77.830934 -90.308684)
		(stroke
			(width 0.072898)
			(type default)
		)
		(layer "F.Cu")
	)
	(gr_arc
		(start 78.122018 -84.209636)
		(mid 78.041314 -84.014731)
		(end 77.846428 -83.934046)
		(stroke
			(width 0.072898)
			(type default)
		)
		(layer "F.Cu")
	)
	(gr_line
		(start 78.122018 -84.209636)
		(end 78.122018 -84.224368)
		(stroke
			(width 0.072898)
			(type default)
		)
		(layer "F.Cu")
	)
	(gr_line
		(start 78.122018 -83.335368)
		(end 78.122018 -83.347306)
		(stroke
			(width 0.072898)
			(type default)
		)
		(layer "F.Cu")
	)
	(gr_arc
		(start 78.122018 -77.798168)
		(mid 78.038836 -77.597374)
		(end 77.838046 -77.514196)
		(stroke
			(width 0.072898)
			(type default)
		)
		(layer "F.Cu")
	)
	(gr_line
		(start 78.122018 -76.909168)
		(end 78.122018 -76.919074)
		(stroke
			(width 0.072898)
			(type default)
		)
		(layer "F.Cu")
	)
	(gr_arc
		(start 78.122018 -71.397368)
		(mid 78.037642 -71.193723)
		(end 77.833982 -71.109332)
		(stroke
			(width 0.072898)
			(type default)
		)
		(layer "F.Cu")
	)
	(gr_line
		(start 79.925164 -95.350076)
		(end 81.111344 -95.350076)
		(stroke
			(width 0.072898)
			(type default)
		)
		(layer "F.Cu")
	)
	(gr_line
		(start 79.925164 -94.549976)
		(end 81.111598 -94.549976)
		(stroke
			(width 0.072898)
			(type default)
		)
		(layer "F.Cu")
	)
	(gr_line
		(start 79.925164 -92.14993)
		(end 81.111344 -92.14993)
		(stroke
			(width 0.072898)
			(type default)
		)
		(layer "F.Cu")
	)
	(gr_line
		(start 79.925164 -91.350084)
		(end 81.111344 -91.350084)
		(stroke
			(width 0.072898)
			(type default)
		)
		(layer "F.Cu")
	)
	(gr_line
		(start 79.925164 -88.950038)
		(end 81.111344 -88.950038)
		(stroke
			(width 0.072898)
			(type default)
		)
		(layer "F.Cu")
	)
	(gr_line
		(start 79.925164 -88.149938)
		(end 81.111598 -88.149938)
		(stroke
			(width 0.072898)
			(type default)
		)
		(layer "F.Cu")
	)
	(gr_line
		(start 79.925164 -85.750146)
		(end 81.111344 -85.750146)
		(stroke
			(width 0.072898)
			(type default)
		)
		(layer "F.Cu")
	)
	(gr_line
		(start 79.925164 -84.950046)
		(end 81.111598 -84.950046)
		(stroke
			(width 0.072898)
			(type default)
		)
		(layer "F.Cu")
	)
	(gr_line
		(start 79.925164 -82.55)
		(end 81.111344 -82.55)
		(stroke
			(width 0.072898)
			(type default)
		)
		(layer "F.Cu")
	)
	(gr_line
		(start 79.925164 -81.7499)
		(end 81.111598 -81.7499)
		(stroke
			(width 0.072898)
			(type default)
		)
		(layer "F.Cu")
	)
	(gr_line
		(start 79.925164 -79.350108)
		(end 81.111344 -79.350108)
		(stroke
			(width 0.072898)
			(type default)
		)
		(layer "F.Cu")
	)
	(gr_line
		(start 79.925164 -78.550008)
		(end 81.111598 -78.550008)
		(stroke
			(width 0.072898)
			(type default)
		)
		(layer "F.Cu")
	)
	(gr_line
		(start 79.925164 -76.149962)
		(end 81.111344 -76.149962)
		(stroke
			(width 0.072898)
			(type default)
		)
		(layer "F.Cu")
	)
	(gr_line
		(start 79.925164 -75.350116)
		(end 81.111344 -75.350116)
		(stroke
			(width 0.072898)
			(type default)
		)
		(layer "F.Cu")
	)
	(gr_line
		(start 79.925164 -72.95007)
		(end 81.111344 -72.95007)
		(stroke
			(width 0.072898)
			(type default)
		)
		(layer "F.Cu")
	)
	(gr_line
		(start 79.925164 -72.14997)
		(end 81.11109 -72.14997)
		(stroke
			(width 0.072898)
			(type default)
		)
		(layer "F.Cu")
	)
	(gr_line
		(start 81.11109 -72.14997)
		(end 81.289398 -72.328278)
		(stroke
			(width 0.072898)
			(type default)
		)
		(layer "F.Cu")
	)
	(gr_line
		(start 81.111344 -95.350076)
		(end 81.289652 -95.171768)
		(stroke
			(width 0.072898)
			(type default)
		)
		(layer "F.Cu")
	)
	(gr_line
		(start 81.111344 -92.14993)
		(end 81.289398 -91.971876)
		(stroke
			(width 0.072898)
			(type default)
		)
		(layer "F.Cu")
	)
	(gr_line
		(start 81.111344 -91.350084)
		(end 81.289398 -91.528138)
		(stroke
			(width 0.072898)
			(type default)
		)
		(layer "F.Cu")
	)
	(gr_line
		(start 81.111344 -88.950038)
		(end 81.289652 -88.77173)
		(stroke
			(width 0.072898)
			(type default)
		)
		(layer "F.Cu")
	)
	(gr_line
		(start 81.111344 -85.750146)
		(end 81.289652 -85.571838)
		(stroke
			(width 0.072898)
			(type default)
		)
		(layer "F.Cu")
	)
	(gr_line
		(start 81.111344 -82.55)
		(end 81.289652 -82.371692)
		(stroke
			(width 0.072898)
			(type default)
		)
		(layer "F.Cu")
	)
	(gr_line
		(start 81.111344 -79.350108)
		(end 81.289652 -79.1718)
		(stroke
			(width 0.072898)
			(type default)
		)
		(layer "F.Cu")
	)
	(gr_line
		(start 81.111344 -76.149962)
		(end 81.289652 -75.971654)
		(stroke
			(width 0.072898)
			(type default)
		)
		(layer "F.Cu")
	)
	(gr_line
		(start 81.111344 -75.350116)
		(end 81.111598 -75.349862)
		(stroke
			(width 0.072898)
			(type default)
		)
		(layer "F.Cu")
	)
	(gr_line
		(start 81.111344 -72.95007)
		(end 81.289398 -72.772016)
		(stroke
			(width 0.072898)
			(type default)
		)
		(layer "F.Cu")
	)
	(gr_line
		(start 81.111598 -94.549976)
		(end 81.289652 -94.72803)
		(stroke
			(width 0.072898)
			(type default)
		)
		(layer "F.Cu")
	)
	(gr_line
		(start 81.111598 -88.149938)
		(end 81.289652 -88.327992)
		(stroke
			(width 0.072898)
			(type default)
		)
		(layer "F.Cu")
	)
	(gr_line
		(start 81.111598 -84.950046)
		(end 81.289652 -85.1281)
		(stroke
			(width 0.072898)
			(type default)
		)
		(layer "F.Cu")
	)
	(gr_line
		(start 81.111598 -81.7499)
		(end 81.289652 -81.927954)
		(stroke
			(width 0.072898)
			(type default)
		)
		(layer "F.Cu")
	)
	(gr_line
		(start 81.111598 -78.550008)
		(end 81.289652 -78.728062)
		(stroke
			(width 0.072898)
			(type default)
		)
		(layer "F.Cu")
	)
	(gr_line
		(start 81.111598 -75.349862)
		(end 81.289652 -75.527916)
		(stroke
			(width 0.072898)
			(type default)
		)
		(layer "F.Cu")
	)
	(gr_arc
		(start 83.056476 -94.794324)
		(mid 83.269847 -94.705943)
		(end 83.358228 -94.492572)
		(stroke
			(width 0.072898)
			(type default)
		)
		(layer "F.Cu")
	)
	(gr_arc
		(start 83.091528 -75.59421)
		(mid 83.280113 -75.516095)
		(end 83.358228 -75.32751)
		(stroke
			(width 0.072898)
			(type default)
		)
		(layer "F.Cu")
	)
	(gr_arc
		(start 83.104228 -81.994248)
		(mid 83.283833 -81.919853)
		(end 83.358228 -81.740248)
		(stroke
			(width 0.072898)
			(type default)
		)
		(layer "F.Cu")
	)
	(gr_arc
		(start 83.116928 -88.394286)
		(mid 83.287553 -88.323611)
		(end 83.358228 -88.152986)
		(stroke
			(width 0.072898)
			(type default)
		)
		(layer "F.Cu")
	)
	(gr_arc
		(start 83.358228 -95.381572)
		(mid 83.277353 -95.186349)
		(end 83.08213 -95.105474)
		(stroke
			(width 0.072898)
			(type default)
		)
		(layer "F.Cu")
	)
	(gr_arc
		(start 83.358228 -88.946736)
		(mid 83.287567 -88.776078)
		(end 83.116928 -88.705436)
		(stroke
			(width 0.072898)
			(type default)
		)
		(layer "F.Cu")
	)
	(gr_line
		(start 83.358228 -88.946736)
		(end 83.358228 -88.994234)
		(stroke
			(width 0.072898)
			(type default)
		)
		(layer "F.Cu")
	)
	(gr_line
		(start 83.358228 -88.105234)
		(end 83.358228 -88.152986)
		(stroke
			(width 0.072898)
			(type default)
		)
		(layer "F.Cu")
	)
	(gr_arc
		(start 83.358228 -82.559398)
		(mid 83.283834 -82.379784)
		(end 83.104228 -82.305398)
		(stroke
			(width 0.072898)
			(type default)
		)
		(layer "F.Cu")
	)
	(gr_line
		(start 83.358228 -82.559398)
		(end 83.358228 -82.594196)
		(stroke
			(width 0.072898)
			(type default)
		)
		(layer "F.Cu")
	)
	(gr_line
		(start 83.358228 -81.705196)
		(end 83.358228 -81.740248)
		(stroke
			(width 0.072898)
			(type default)
		)
		(layer "F.Cu")
	)
	(gr_arc
		(start 83.358228 -76.17206)
		(mid 83.280101 -75.983491)
		(end 83.091528 -75.90536)
		(stroke
			(width 0.072898)
			(type default)
		)
		(layer "F.Cu")
	)
	(gr_line
		(start 83.358228 -76.17206)
		(end 83.358228 -76.194158)
		(stroke
			(width 0.072898)
			(type default)
		)
		(layer "F.Cu")
	)
	(gr_line
		(start 83.358228 -75.305158)
		(end 83.358228 -75.32751)
		(stroke
			(width 0.072898)
			(type default)
		)
		(layer "F.Cu")
	)
	(gr_arc
		(start 84.704428 -91.594432)
		(mid 84.901994 -91.512598)
		(end 84.983828 -91.315032)
		(stroke
			(width 0.072898)
			(type default)
		)
		(layer "F.Cu")
	)
	(gr_arc
		(start 84.704428 -72.394572)
		(mid 84.901994 -72.312738)
		(end 84.983828 -72.115172)
		(stroke
			(width 0.072898)
			(type default)
		)
		(layer "F.Cu")
	)
	(gr_arc
		(start 84.742528 -78.794356)
		(mid 84.913153 -78.723681)
		(end 84.983828 -78.553056)
		(stroke
			(width 0.072898)
			(type default)
		)
		(layer "F.Cu")
	)
	(gr_arc
		(start 84.780628 -85.194394)
		(mid 84.924312 -85.134878)
		(end 84.983828 -84.991194)
		(stroke
			(width 0.072898)
			(type default)
		)
		(layer "F.Cu")
	)
	(gr_arc
		(start 84.983828 -92.184982)
		(mid 84.901989 -91.987418)
		(end 84.704428 -91.905582)
		(stroke
			(width 0.072898)
			(type default)
		)
		(layer "F.Cu")
	)
	(gr_line
		(start 84.983828 -92.184982)
		(end 84.983828 -92.195396)
		(stroke
			(width 0.072898)
			(type default)
		)
		(layer "F.Cu")
	)
	(gr_line
		(start 84.983828 -91.306396)
		(end 84.983828 -91.315032)
		(stroke
			(width 0.072898)
			(type default)
		)
		(layer "F.Cu")
	)
	(gr_arc
		(start 84.983828 -85.708744)
		(mid 84.924329 -85.565022)
		(end 84.780628 -85.505544)
		(stroke
			(width 0.072898)
			(type default)
		)
		(layer "F.Cu")
	)
	(gr_line
		(start 84.983828 -85.708744)
		(end 84.983828 -85.793834)
		(stroke
			(width 0.072898)
			(type default)
		)
		(layer "F.Cu")
	)
	(gr_line
		(start 84.983828 -84.904834)
		(end 84.983828 -84.991194)
		(stroke
			(width 0.072898)
			(type default)
		)
		(layer "F.Cu")
	)
	(gr_arc
		(start 84.983828 -79.346806)
		(mid 84.913157 -79.176167)
		(end 84.742528 -79.105506)
		(stroke
			(width 0.072898)
			(type default)
		)
		(layer "F.Cu")
	)
	(gr_line
		(start 84.983828 -79.346806)
		(end 84.983828 -79.393796)
		(stroke
			(width 0.072898)
			(type default)
		)
		(layer "F.Cu")
	)
	(gr_line
		(start 84.983828 -78.504796)
		(end 84.983828 -78.553056)
		(stroke
			(width 0.072898)
			(type default)
		)
		(layer "F.Cu")
	)
	(gr_arc
		(start 84.983828 -72.970136)
		(mid 84.906397 -72.783139)
		(end 84.719414 -72.705722)
		(stroke
			(width 0.072898)
			(type default)
		)
		(layer "F.Cu")
	)
	(gr_line
		(start 84.983828 -72.081136)
		(end 84.983828 -72.115172)
		(stroke
			(width 0.072898)
			(type default)
		)
		(layer "F.Cu")
	)
	(gr_line
		(start 85.099144 -153.171906)
		(end 85.413088 -153.48585)
		(stroke
			(width 0.072898)
			(type default)
		)
		(layer "F.Cu")
	)
	(gr_line
		(start 85.413088 -153.608532)
		(end 85.43925 -153.634694)
		(stroke
			(width 0.072898)
			(type default)
		)
		(layer "F.Cu")
	)
	(gr_line
		(start 85.413088 -153.48585)
		(end 85.413088 -153.608532)
		(stroke
			(width 0.072898)
			(type default)
		)
		(layer "F.Cu")
	)
	(gr_line
		(start 85.88121 -153.328878)
		(end 85.88121 -153.632916)
		(stroke
			(width 0.072898)
			(type default)
		)
		(layer "F.Cu")
	)
	(gr_line
		(start 85.88121 -153.328878)
		(end 86.038182 -153.171906)
		(stroke
			(width 0.072898)
			(type default)
		)
		(layer "F.Cu")
	)
	(gr_line
		(start 86.296754 -156.688028)
		(end 86.544404 -156.440378)
		(stroke
			(width 0.072898)
			(type default)
		)
		(layer "F.Cu")
	)
	(gr_line
		(start 86.296754 -155.74899)
		(end 86.544404 -155.99664)
		(stroke
			(width 0.072898)
			(type default)
		)
		(layer "F.Cu")
	)
	(gr_line
		(start 86.3854 -160.379918)
		(end 86.63305 -160.132268)
		(stroke
			(width 0.072898)
			(type default)
		)
		(layer "F.Cu")
	)
	(gr_line
		(start 87.076788 -160.132268)
		(end 87.324438 -160.379918)
		(stroke
			(width 0.072898)
			(type default)
		)
		(layer "F.Cu")
	)
	(gr_line
		(start 88.000078 -18.19529)
		(end 88.000078 -18.979896)
		(stroke
			(width 0.072898)
			(type default)
		)
		(layer "F.Cu")
	)
	(gr_line
		(start 88.000078 -18.19529)
		(end 88.12149 -18.073878)
		(stroke
			(width 0.072898)
			(type default)
		)
		(layer "F.Cu")
	)
	(gr_line
		(start 88.000078 -17.508982)
		(end 88.12149 -17.630394)
		(stroke
			(width 0.072898)
			(type default)
		)
		(layer "F.Cu")
	)
	(gr_line
		(start 88.000078 -16.9799)
		(end 88.000078 -17.508982)
		(stroke
			(width 0.072898)
			(type default)
		)
		(layer "F.Cu")
	)
	(gr_line
		(start 88.00973 -156.374084)
		(end 88.04148 -156.374084)
		(stroke
			(width 0.072898)
			(type default)
		)
		(layer "F.Cu")
	)
	(gr_line
		(start 88.32088 -156.213302)
		(end 88.35263 -156.213302)
		(stroke
			(width 0.072898)
			(type default)
		)
		(layer "F.Cu")
	)
	(gr_line
		(start 89.00922 -155.077414)
		(end 89.03716 -155.105354)
		(stroke
			(width 0.072898)
			(type default)
		)
		(layer "F.Cu")
	)
	(gr_line
		(start 89.00922 -154.633676)
		(end 89.037414 -154.605482)
		(stroke
			(width 0.072898)
			(type default)
		)
		(layer "F.Cu")
	)
	(gr_line
		(start 89.027 -156.605478)
		(end 89.881456 -156.605478)
		(stroke
			(width 0.072898)
			(type default)
		)
		(layer "F.Cu")
	)
	(gr_line
		(start 89.029286 -156.16428)
		(end 89.08796 -156.105606)
		(stroke
			(width 0.072898)
			(type default)
		)
		(layer "F.Cu")
	)
	(gr_line
		(start 89.03716 -155.105354)
		(end 89.881456 -155.105354)
		(stroke
			(width 0.072898)
			(type default)
		)
		(layer "F.Cu")
	)
	(gr_line
		(start 89.037414 -154.605482)
		(end 89.881456 -154.605482)
		(stroke
			(width 0.072898)
			(type default)
		)
		(layer "F.Cu")
	)
	(gr_line
		(start 89.08796 -156.105606)
		(end 89.881456 -156.105606)
		(stroke
			(width 0.072898)
			(type default)
		)
		(layer "F.Cu")
	)
	(gr_line
		(start 89.103962 -157.569408)
		(end 89.14003 -157.605476)
		(stroke
			(width 0.072898)
			(type default)
		)
		(layer "F.Cu")
	)
	(gr_line
		(start 89.103962 -157.12567)
		(end 89.124028 -157.105604)
		(stroke
			(width 0.072898)
			(type default)
		)
		(layer "F.Cu")
	)
	(gr_line
		(start 89.124028 -157.105604)
		(end 89.881456 -157.105604)
		(stroke
			(width 0.072898)
			(type default)
		)
		(layer "F.Cu")
	)
	(gr_line
		(start 89.14003 -157.605476)
		(end 89.792556 -157.605476)
		(stroke
			(width 0.072898)
			(type default)
		)
		(layer "F.Cu")
	)
	(gr_line
		(start 91.324938 -17.234662)
		(end 91.484958 -17.394682)
		(stroke
			(width 0.072898)
			(type default)
		)
		(layer "F.Cu")
	)
	(gr_line
		(start 91.484958 -17.394682)
		(end 91.923108 -17.394682)
		(stroke
			(width 0.072898)
			(type default)
		)
		(layer "F.Cu")
	)
	(gr_line
		(start 91.636088 -16.920972)
		(end 91.771978 -16.920972)
		(stroke
			(width 0.072898)
			(type default)
		)
		(layer "F.Cu")
	)
	(gr_line
		(start 91.923108 -17.394682)
		(end 92.083128 -17.234662)
		(stroke
			(width 0.072898)
			(type default)
		)
		(layer "F.Cu")
	)
	(gr_line
		(start 93.251782 -159.305244)
		(end 93.279976 -159.333438)
		(stroke
			(width 0.072898)
			(type default)
		)
		(layer "F.Cu")
	)
	(gr_line
		(start 93.251782 -158.47568)
		(end 93.251782 -159.305244)
		(stroke
			(width 0.072898)
			(type default)
		)
		(layer "F.Cu")
	)
	(gr_line
		(start 93.72346 -159.333438)
		(end 93.751654 -159.305244)
		(stroke
			(width 0.072898)
			(type default)
		)
		(layer "F.Cu")
	)
	(gr_line
		(start 93.751654 -158.47568)
		(end 93.751654 -159.305244)
		(stroke
			(width 0.072898)
			(type default)
		)
		(layer "F.Cu")
	)
	(gr_line
		(start 94.341442 -17.290542)
		(end 94.488 -17.4371)
		(stroke
			(width 0.072898)
			(type default)
		)
		(layer "F.Cu")
	)
	(gr_line
		(start 94.341442 -16.847058)
		(end 94.488 -16.7005)
		(stroke
			(width 0.072898)
			(type default)
		)
		(layer "F.Cu")
	)
	(gr_line
		(start 94.488 -17.4371)
		(end 94.634558 -17.290542)
		(stroke
			(width 0.072898)
			(type default)
		)
		(layer "F.Cu")
	)
	(gr_line
		(start 94.488 -16.7005)
		(end 94.634558 -16.847058)
		(stroke
			(width 0.072898)
			(type default)
		)
		(layer "F.Cu")
	)
	(gr_line
		(start 96.081088 -16.92021)
		(end 96.126808 -16.92021)
		(stroke
			(width 0.072898)
			(type default)
		)
		(layer "F.Cu")
	)
	(gr_line
		(start 96.392238 -17.094962)
		(end 96.437958 -17.094962)
		(stroke
			(width 0.072898)
			(type default)
		)
		(layer "F.Cu")
	)
	(gr_line
		(start 96.394016 -16.653002)
		(end 96.490028 -16.55699)
		(stroke
			(width 0.072898)
			(type default)
		)
		(layer "F.Cu")
	)
	(gr_line
		(start 96.440498 -17.094962)
		(end 96.622108 -17.094962)
		(stroke
			(width 0.072898)
			(type default)
		)
		(layer "F.Cu")
	)
	(gr_line
		(start 96.622108 -17.094962)
		(end 96.931988 -16.785082)
		(stroke
			(width 0.072898)
			(type default)
		)
		(layer "F.Cu")
	)
	(gr_line
		(start 96.632522 -162.07867)
		(end 96.882458 -161.828734)
		(stroke
			(width 0.072898)
			(type default)
		)
		(layer "F.Cu")
	)
	(gr_line
		(start 96.931988 -16.558768)
		(end 96.931988 -16.785082)
		(stroke
			(width 0.072898)
			(type default)
		)
		(layer "F.Cu")
	)
	(gr_line
		(start 97.326196 -161.828734)
		(end 97.576132 -162.07867)
		(stroke
			(width 0.072898)
			(type default)
		)
		(layer "F.Cu")
	)
	(gr_line
		(start 98.228658 -19.011138)
		(end 98.495358 -19.277838)
		(stroke
			(width 0.072898)
			(type default)
		)
		(layer "F.Cu")
	)
	(gr_line
		(start 98.228658 -18.74266)
		(end 98.228658 -19.011138)
		(stroke
			(width 0.072898)
			(type default)
		)
		(layer "F.Cu")
	)
	(gr_line
		(start 98.228658 -16.693896)
		(end 98.228658 -17.06626)
		(stroke
			(width 0.072898)
			(type default)
		)
		(layer "F.Cu")
	)
	(gr_line
		(start 98.228658 -16.693896)
		(end 98.495104 -16.42745)
		(stroke
			(width 0.072898)
			(type default)
		)
		(layer "F.Cu")
	)
	(gr_line
		(start 98.236786 -20.242022)
		(end 98.484436 -19.994372)
		(stroke
			(width 0.072898)
			(type default)
		)
		(layer "F.Cu")
	)
	(gr_line
		(start 98.928174 -19.994372)
		(end 99.175824 -20.242022)
		(stroke
			(width 0.072898)
			(type default)
		)
		(layer "F.Cu")
	)
	(gr_line
		(start 98.938842 -19.277838)
		(end 99.193858 -19.022822)
		(stroke
			(width 0.072898)
			(type default)
		)
		(layer "F.Cu")
	)
	(gr_line
		(start 98.938842 -16.42745)
		(end 99.193858 -16.682466)
		(stroke
			(width 0.072898)
			(type default)
		)
		(layer "F.Cu")
	)
	(gr_line
		(start 99.193858 -18.74266)
		(end 99.193858 -19.022822)
		(stroke
			(width 0.072898)
			(type default)
		)
		(layer "F.Cu")
	)
	(gr_line
		(start 99.193858 -16.682466)
		(end 99.193858 -17.06626)
		(stroke
			(width 0.072898)
			(type default)
		)
		(layer "F.Cu")
	)
	(gr_line
		(start 101.65207 -41.124124)
		(end 101.89972 -40.876474)
		(stroke
			(width 0.072898)
			(type default)
		)
		(layer "F.Cu")
	)
	(gr_line
		(start 101.65207 -40.185086)
		(end 101.89972 -40.432736)
		(stroke
			(width 0.072898)
			(type default)
		)
		(layer "F.Cu")
	)
	(gr_line
		(start 114.3 -44.969684)
		(end 114.3 -45.39996)
		(stroke
			(width 0.072898)
			(type default)
		)
		(layer "F.Cu")
	)
	(gr_line
		(start 114.3 -44.969684)
		(end 114.360452 -44.909232)
		(stroke
			(width 0.072898)
			(type default)
		)
		(layer "F.Cu")
	)
	(gr_line
		(start 114.3 -44.405042)
		(end 114.360452 -44.465494)
		(stroke
			(width 0.072898)
			(type default)
		)
		(layer "F.Cu")
	)
	(gr_line
		(start 114.3 -44.000166)
		(end 114.3 -44.405042)
		(stroke
			(width 0.072898)
			(type default)
		)
		(layer "F.Cu")
	)
	(gr_line
		(start 132.0546 -26.611072)
		(end 132.205222 -26.761694)
		(stroke
			(width 0.072898)
			(type default)
		)
		(layer "F.Cu")
	)
	(gr_line
		(start 132.0546 -26.2001)
		(end 132.0546 -26.611072)
		(stroke
			(width 0.072898)
			(type default)
		)
		(layer "F.Cu")
	)
	(gr_line
		(start 132.08 -27.3304)
		(end 132.08 -27.6098)
		(stroke
			(width 0.072898)
			(type default)
		)
		(layer "F.Cu")
	)
	(gr_line
		(start 132.08 -27.3304)
		(end 132.205222 -27.205178)
		(stroke
			(width 0.072898)
			(type default)
		)
		(layer "F.Cu")
	)
	(gr_line
		(start 133.863842 -43.719242)
		(end 134.100062 -43.955462)
		(stroke
			(width 0.072898)
			(type default)
		)
		(layer "F.Cu")
	)
	(gr_line
		(start 133.863842 -43.275758)
		(end 134.100062 -43.039538)
		(stroke
			(width 0.072898)
			(type default)
		)
		(layer "F.Cu")
	)
	(gr_line
		(start 134.100062 -43.955462)
		(end 134.100062 -44.200064)
		(stroke
			(width 0.072898)
			(type default)
		)
		(layer "F.Cu")
	)
	(gr_line
		(start 134.100062 -42.800016)
		(end 134.100062 -43.039538)
		(stroke
			(width 0.072898)
			(type default)
		)
		(layer "F.Cu")
	)
	(gr_line
		(start 189.550802 -84.515198)
		(end 189.602364 -84.463636)
		(stroke
			(width 0.072898)
			(type default)
		)
		(layer "F.Cu")
	)
	(gr_arc
		(start 189.602364 -84.463636)
		(mid 189.665685 -84.311106)
		(end 189.602364 -84.158582)
		(stroke
			(width 0.072898)
			(type default)
		)
		(layer "F.Cu")
	)
	(gr_arc
		(start 189.822582 -83.938618)
		(mid 189.974982 -84.001744)
		(end 190.127382 -83.938618)
		(stroke
			(width 0.072898)
			(type default)
		)
		(layer "F.Cu")
	)
	(gr_line
		(start 190.127382 -83.938618)
		(end 190.179198 -83.886802)
		(stroke
			(width 0.072898)
			(type default)
		)
		(layer "F.Cu")
	)
	(gr_arc
		(start 191.100202 -87.309198)
		(mid 191.184858 -87.105106)
		(end 191.100202 -86.90102)
		(stroke
			(width 0.072898)
			(type default)
		)
		(layer "F.Cu")
	)
	(gr_line
		(start 191.177926 -76.2889)
		(end 191.177926 -76.49718)
		(stroke
			(width 0.072898)
			(type default)
		)
		(layer "F.Cu")
	)
	(gr_line
		(start 191.177926 -76.2889)
		(end 191.5668 -75.900026)
		(stroke
			(width 0.072898)
			(type default)
		)
		(layer "F.Cu")
	)
	(gr_arc
		(start 191.320166 -86.680802)
		(mid 191.524382 -86.765391)
		(end 191.728598 -86.680802)
		(stroke
			(width 0.072898)
			(type default)
		)
		(layer "F.Cu")
	)
	(gr_line
		(start 191.491616 -76.80833)
		(end 191.600074 -76.699872)
		(stroke
			(width 0.072898)
			(type default)
		)
		(layer "F.Cu")
	)
	(gr_line
		(start 191.5668 -75.900026)
		(end 191.600074 -75.900026)
		(stroke
			(width 0.072898)
			(type default)
		)
		(layer "F.Cu")
	)
	(gr_line
		(start 191.600074 -74.299826)
		(end 191.99987 -74.699622)
		(stroke
			(width 0.047498)
			(type default)
		)
		(layer "F.Cu")
	)
	(gr_line
		(start 191.600074 -73.49998)
		(end 191.99987 -73.899776)
		(stroke
			(width 0.047498)
			(type default)
		)
		(layer "F.Cu")
	)
	(gr_line
		(start 192.035938 -76.1746)
		(end 192.035938 -76.439014)
		(stroke
			(width 0.072898)
			(type default)
		)
		(layer "F.Cu")
	)
	(gr_line
		(start 192.035938 -76.1746)
		(end 192.310512 -75.900026)
		(stroke
			(width 0.072898)
			(type default)
		)
		(layer "F.Cu")
	)
	(gr_line
		(start 192.310512 -75.900026)
		(end 192.39992 -75.900026)
		(stroke
			(width 0.072898)
			(type default)
		)
		(layer "F.Cu")
	)
	(gr_line
		(start 192.349628 -76.750164)
		(end 192.39992 -76.699872)
		(stroke
			(width 0.072898)
			(type default)
		)
		(layer "F.Cu")
	)
	(gr_line
		(start 192.39992 -74.299826)
		(end 192.79997 -74.699876)
		(stroke
			(width 0.047498)
			(type default)
		)
		(layer "F.Cu")
	)
	(gr_line
		(start 192.39992 -73.49998)
		(end 192.799716 -73.899776)
		(stroke
			(width 0.047498)
			(type default)
		)
		(layer "F.Cu")
	)
	(gr_line
		(start 193.23685 -83.068922)
		(end 193.279522 -83.11134)
		(stroke
			(width 0.072898)
			(type default)
		)
		(layer "F.Cu")
	)
	(gr_line
		(start 193.561208 -76.275692)
		(end 193.561208 -76.51369)
		(stroke
			(width 0.072898)
			(type default)
		)
		(layer "F.Cu")
	)
	(gr_line
		(start 193.561208 -76.275692)
		(end 193.936874 -75.900026)
		(stroke
			(width 0.072898)
			(type default)
		)
		(layer "F.Cu")
	)
	(gr_arc
		(start 193.822574 -89.010998)
		(mid 193.907239 -88.806906)
		(end 193.822574 -88.60282)
		(stroke
			(width 0.072898)
			(type default)
		)
		(layer "F.Cu")
	)
	(gr_line
		(start 193.874898 -76.82484)
		(end 193.999866 -76.699872)
		(stroke
			(width 0.072898)
			(type default)
		)
		(layer "F.Cu")
	)
	(gr_line
		(start 193.936874 -75.900026)
		(end 193.999866 -75.900026)
		(stroke
			(width 0.072898)
			(type default)
		)
		(layer "F.Cu")
	)
	(gr_line
		(start 193.999866 -74.309224)
		(end 194.39255 -74.701908)
		(stroke
			(width 0.047498)
			(type default)
		)
		(layer "F.Cu")
	)
	(gr_line
		(start 193.999866 -74.299826)
		(end 193.999866 -74.309224)
		(stroke
			(width 0.047498)
			(type default)
		)
		(layer "F.Cu")
	)
	(gr_line
		(start 193.999866 -73.49998)
		(end 194.399662 -73.899776)
		(stroke
			(width 0.047498)
			(type default)
		)
		(layer "F.Cu")
	)
	(gr_arc
		(start 194.042538 -88.382602)
		(mid 194.246754 -88.467191)
		(end 194.45097 -88.382602)
		(stroke
			(width 0.072898)
			(type default)
		)
		(layer "F.Cu")
	)
	(gr_line
		(start 194.046602 -84.286598)
		(end 194.047364 -84.285836)
		(stroke
			(width 0.072898)
			(type default)
		)
		(layer "F.Cu")
	)
	(gr_arc
		(start 194.047364 -84.285836)
		(mid 194.131727 -84.082506)
		(end 194.047364 -83.879182)
		(stroke
			(width 0.072898)
			(type default)
		)
		(layer "F.Cu")
	)
	(gr_arc
		(start 194.267582 -83.659218)
		(mid 194.470782 -83.743386)
		(end 194.673982 -83.659218)
		(stroke
			(width 0.072898)
			(type default)
		)
		(layer "F.Cu")
	)
	(gr_line
		(start 194.392296 -76.270104)
		(end 194.392296 -76.482702)
		(stroke
			(width 0.072898)
			(type default)
		)
		(layer "F.Cu")
	)
	(gr_line
		(start 194.392296 -76.270104)
		(end 194.762374 -75.900026)
		(stroke
			(width 0.072898)
			(type default)
		)
		(layer "F.Cu")
	)
	(gr_line
		(start 194.673982 -83.659218)
		(end 194.674998 -83.658202)
		(stroke
			(width 0.072898)
			(type default)
		)
		(layer "F.Cu")
	)
	(gr_line
		(start 194.705986 -76.793852)
		(end 194.799966 -76.699872)
		(stroke
			(width 0.072898)
			(type default)
		)
		(layer "F.Cu")
	)
	(gr_line
		(start 194.762374 -75.900026)
		(end 194.799966 -75.900026)
		(stroke
			(width 0.072898)
			(type default)
		)
		(layer "F.Cu")
	)
	(gr_line
		(start 194.799966 -74.30897)
		(end 195.198492 -74.707496)
		(stroke
			(width 0.047498)
			(type default)
		)
		(layer "F.Cu")
	)
	(gr_line
		(start 194.799966 -74.299826)
		(end 194.799966 -74.30897)
		(stroke
			(width 0.047498)
			(type default)
		)
		(layer "F.Cu")
	)
	(gr_line
		(start 194.799966 -73.49998)
		(end 195.199762 -73.899776)
		(stroke
			(width 0.047498)
			(type default)
		)
		(layer "F.Cu")
	)
	(gr_line
		(start 196.018658 -76.2)
		(end 196.018658 -76.456286)
		(stroke
			(width 0.072898)
			(type default)
		)
		(layer "F.Cu")
	)
	(gr_line
		(start 196.018658 -76.2)
		(end 196.318632 -75.900026)
		(stroke
			(width 0.072898)
			(type default)
		)
		(layer "F.Cu")
	)
	(gr_line
		(start 196.318632 -75.900026)
		(end 196.399912 -75.900026)
		(stroke
			(width 0.072898)
			(type default)
		)
		(layer "F.Cu")
	)
	(gr_line
		(start 196.332348 -76.767436)
		(end 196.399912 -76.699872)
		(stroke
			(width 0.072898)
			(type default)
		)
		(layer "F.Cu")
	)
	(gr_line
		(start 196.399912 -74.299826)
		(end 196.409564 -74.299826)
		(stroke
			(width 0.047498)
			(type default)
		)
		(layer "F.Cu")
	)
	(gr_line
		(start 196.399912 -73.49998)
		(end 196.799708 -73.899776)
		(stroke
			(width 0.047498)
			(type default)
		)
		(layer "F.Cu")
	)
	(gr_line
		(start 196.409564 -74.299826)
		(end 196.80809 -74.698352)
		(stroke
			(width 0.047498)
			(type default)
		)
		(layer "F.Cu")
	)
	(gr_line
		(start 196.53885 -84.706968)
		(end 196.60235 -84.643468)
		(stroke
			(width 0.072898)
			(type default)
		)
		(layer "F.Cu")
	)
	(gr_line
		(start 196.818758 -76.2)
		(end 196.818758 -76.456286)
		(stroke
			(width 0.072898)
			(type default)
		)
		(layer "F.Cu")
	)
	(gr_line
		(start 196.818758 -76.2)
		(end 197.118732 -75.900026)
		(stroke
			(width 0.072898)
			(type default)
		)
		(layer "F.Cu")
	)
	(gr_arc
		(start 196.895974 -85.962998)
		(mid 196.980458 -85.758946)
		(end 196.895974 -85.55482)
		(stroke
			(width 0.072898)
			(type default)
		)
		(layer "F.Cu")
	)
	(gr_arc
		(start 197.115938 -85.334602)
		(mid 197.320154 -85.419191)
		(end 197.52437 -85.334602)
		(stroke
			(width 0.072898)
			(type default)
		)
		(layer "F.Cu")
	)
	(gr_line
		(start 197.118732 -75.900026)
		(end 197.200012 -75.900026)
		(stroke
			(width 0.072898)
			(type default)
		)
		(layer "F.Cu")
	)
	(gr_line
		(start 197.132448 -76.767436)
		(end 197.200012 -76.699872)
		(stroke
			(width 0.072898)
			(type default)
		)
		(layer "F.Cu")
	)
	(gr_line
		(start 197.200012 -74.299826)
		(end 197.20941 -74.299826)
		(stroke
			(width 0.047498)
			(type default)
		)
		(layer "F.Cu")
	)
	(gr_line
		(start 197.200012 -73.49998)
		(end 197.599808 -73.899776)
		(stroke
			(width 0.047498)
			(type default)
		)
		(layer "F.Cu")
	)
	(gr_line
		(start 197.20941 -74.299826)
		(end 197.609206 -74.699622)
		(stroke
			(width 0.047498)
			(type default)
		)
		(layer "F.Cu")
	)
	(gr_line
		(start 197.441566 -84.244434)
		(end 197.504304 -84.18195)
		(stroke
			(width 0.072898)
			(type default)
		)
		(layer "F.Cu")
	)
	(gr_line
		(start 198.186802 -89.087198)
		(end 198.187564 -89.086436)
		(stroke
			(width 0.072898)
			(type default)
		)
		(layer "F.Cu")
	)
	(gr_arc
		(start 198.187564 -89.086436)
		(mid 198.271927 -88.883106)
		(end 198.187564 -88.679782)
		(stroke
			(width 0.072898)
			(type default)
		)
		(layer "F.Cu")
	)
	(gr_arc
		(start 198.407782 -88.459818)
		(mid 198.610982 -88.543986)
		(end 198.814182 -88.459818)
		(stroke
			(width 0.072898)
			(type default)
		)
		(layer "F.Cu")
	)
	(gr_line
		(start 198.4248 -76.3778)
		(end 198.4248 -76.823316)
		(stroke
			(width 0.072898)
			(type default)
		)
		(layer "F.Cu")
	)
	(gr_line
		(start 198.4248 -76.3778)
		(end 198.799958 -75.900026)
		(stroke
			(width 0.072898)
			(type default)
		)
		(layer "F.Cu")
	)
	(gr_line
		(start 198.772526 -76.727304)
		(end 198.799958 -76.699872)
		(stroke
			(width 0.072898)
			(type default)
		)
		(layer "F.Cu")
	)
	(gr_line
		(start 198.799958 -74.299826)
		(end 198.809102 -74.299826)
		(stroke
			(width 0.047498)
			(type default)
		)
		(layer "F.Cu")
	)
	(gr_line
		(start 198.799958 -73.49998)
		(end 199.199754 -73.899776)
		(stroke
			(width 0.047498)
			(type default)
		)
		(layer "F.Cu")
	)
	(gr_line
		(start 198.809102 -74.299826)
		(end 199.201532 -74.692256)
		(stroke
			(width 0.047498)
			(type default)
		)
		(layer "F.Cu")
	)
	(gr_line
		(start 198.814182 -88.459818)
		(end 198.815198 -88.458802)
		(stroke
			(width 0.072898)
			(type default)
		)
		(layer "F.Cu")
	)
	(gr_line
		(start 199.2122 -76.804012)
		(end 199.286368 -76.87818)
		(stroke
			(width 0.072898)
			(type default)
		)
		(layer "F.Cu")
	)
	(gr_line
		(start 199.2122 -76.287884)
		(end 199.2122 -76.804012)
		(stroke
			(width 0.072898)
			(type default)
		)
		(layer "F.Cu")
	)
	(gr_line
		(start 199.2122 -76.287884)
		(end 199.600058 -75.900026)
		(stroke
			(width 0.072898)
			(type default)
		)
		(layer "F.Cu")
	)
	(gr_line
		(start 199.600058 -74.299826)
		(end 199.606662 -74.299826)
		(stroke
			(width 0.047498)
			(type default)
		)
		(layer "F.Cu")
	)
	(gr_line
		(start 199.600058 -73.49998)
		(end 199.999854 -73.899776)
		(stroke
			(width 0.047498)
			(type default)
		)
		(layer "F.Cu")
	)
	(gr_line
		(start 199.606662 -74.299826)
		(end 200.001632 -74.694796)
		(stroke
			(width 0.047498)
			(type default)
		)
		(layer "F.Cu")
	)
	(gr_line
		(start 200.121266 -84.593938)
		(end 200.163938 -84.636356)
		(stroke
			(width 0.072898)
			(type default)
		)
		(layer "F.Cu")
	)
	(gr_line
		(start 200.79843 -73.903586)
		(end 201.19467 -74.299826)
		(stroke
			(width 0.06223)
			(type default)
		)
		(layer "F.Cu")
	)
	(gr_line
		(start 201.19467 -74.299826)
		(end 201.200004 -74.299826)
		(stroke
			(width 0.06223)
			(type default)
		)
		(layer "F.Cu")
	)
	(gr_line
		(start 201.200004 -76.699872)
		(end 201.378058 -76.877926)
		(stroke
			(width 0.072898)
			(type default)
		)
		(layer "F.Cu")
	)
	(gr_line
		(start 201.200004 -75.099926)
		(end 201.5998 -75.499722)
		(stroke
			(width 0.06223)
			(type default)
		)
		(layer "F.Cu")
	)
	(gr_line
		(start 201.200004 -72.69988)
		(end 201.600562 -73.100438)
		(stroke
			(width 0.06223)
			(type default)
		)
		(layer "F.Cu")
	)
	(gr_line
		(start 201.200004 -71.900034)
		(end 201.59345 -72.29348)
		(stroke
			(width 0.06223)
			(type default)
		)
		(layer "F.Cu")
	)
	(gr_line
		(start 201.200004 -70.299834)
		(end 201.59345 -70.69328)
		(stroke
			(width 0.06223)
			(type default)
		)
		(layer "F.Cu")
	)
	(gr_line
		(start 201.200004 -69.499988)
		(end 201.5998 -69.899784)
		(stroke
			(width 0.06223)
			(type default)
		)
		(layer "F.Cu")
	)
	(gr_line
		(start 201.200004 -67.900042)
		(end 201.595228 -68.295266)
		(stroke
			(width 0.06223)
			(type default)
		)
		(layer "F.Cu")
	)
	(gr_line
		(start 201.200004 -67.099942)
		(end 201.593196 -67.493134)
		(stroke
			(width 0.06223)
			(type default)
		)
		(layer "F.Cu")
	)
	(gr_arc
		(start 201.209402 -86.089998)
		(mid 201.293886 -85.885946)
		(end 201.209402 -85.68182)
		(stroke
			(width 0.072898)
			(type default)
		)
		(layer "F.Cu")
	)
	(gr_arc
		(start 201.429366 -85.461602)
		(mid 201.633582 -85.546191)
		(end 201.837798 -85.461602)
		(stroke
			(width 0.072898)
			(type default)
		)
		(layer "F.Cu")
	)
	(gr_line
		(start 201.593196 -67.493134)
		(end 201.593196 -67.502532)
		(stroke
			(width 0.06223)
			(type default)
		)
		(layer "F.Cu")
	)
	(gr_line
		(start 201.59345 -72.29348)
		(end 201.59345 -72.297798)
		(stroke
			(width 0.06223)
			(type default)
		)
		(layer "F.Cu")
	)
	(gr_line
		(start 201.59345 -70.69328)
		(end 201.59345 -70.702678)
		(stroke
			(width 0.06223)
			(type default)
		)
		(layer "F.Cu")
	)
	(gr_line
		(start 201.594466 -71.503032)
		(end 201.602848 -71.503032)
		(stroke
			(width 0.06223)
			(type default)
		)
		(layer "F.Cu")
	)
	(gr_line
		(start 201.595228 -69.104256)
		(end 201.604118 -69.104256)
		(stroke
			(width 0.06223)
			(type default)
		)
		(layer "F.Cu")
	)
	(gr_line
		(start 201.595228 -68.295266)
		(end 201.595482 -68.295266)
		(stroke
			(width 0.06223)
			(type default)
		)
		(layer "F.Cu")
	)
	(gr_line
		(start 201.598276 -73.903586)
		(end 201.994516 -74.299826)
		(stroke
			(width 0.06223)
			(type default)
		)
		(layer "F.Cu")
	)
	(gr_line
		(start 201.599546 -66.709036)
		(end 201.608944 -66.709036)
		(stroke
			(width 0.06223)
			(type default)
		)
		(layer "F.Cu")
	)
	(gr_line
		(start 201.5998 -69.899784)
		(end 201.609198 -69.899784)
		(stroke
			(width 0.06223)
			(type default)
		)
		(layer "F.Cu")
	)
	(gr_line
		(start 201.602848 -71.503032)
		(end 201.99985 -71.900034)
		(stroke
			(width 0.06223)
			(type default)
		)
		(layer "F.Cu")
	)
	(gr_line
		(start 201.604118 -69.104256)
		(end 201.99985 -69.499988)
		(stroke
			(width 0.06223)
			(type default)
		)
		(layer "F.Cu")
	)
	(gr_line
		(start 201.608944 -66.709036)
		(end 201.99985 -67.099942)
		(stroke
			(width 0.06223)
			(type default)
		)
		(layer "F.Cu")
	)
	(gr_line
		(start 201.821796 -76.877926)
		(end 201.99985 -76.699872)
		(stroke
			(width 0.072898)
			(type default)
		)
		(layer "F.Cu")
	)
	(gr_line
		(start 201.994516 -74.299826)
		(end 201.99985 -74.299826)
		(stroke
			(width 0.06223)
			(type default)
		)
		(layer "F.Cu")
	)
	(gr_line
		(start 201.99985 -75.099926)
		(end 202.399646 -75.499722)
		(stroke
			(width 0.06223)
			(type default)
		)
		(layer "F.Cu")
	)
	(gr_line
		(start 201.99985 -72.69988)
		(end 202.397106 -73.097136)
		(stroke
			(width 0.06223)
			(type default)
		)
		(layer "F.Cu")
	)
	(gr_line
		(start 201.99985 -70.299834)
		(end 202.404472 -70.704456)
		(stroke
			(width 0.06223)
			(type default)
		)
		(layer "F.Cu")
	)
	(gr_line
		(start 201.99985 -67.900042)
		(end 202.3999 -68.300092)
		(stroke
			(width 0.06223)
			(type default)
		)
		(layer "F.Cu")
	)
	(gr_line
		(start 202.3999 -68.300092)
		(end 202.3999 -68.30314)
		(stroke
			(width 0.06223)
			(type default)
		)
		(layer "F.Cu")
	)
	(gr_line
		(start 202.946 -84.243672)
		(end 203.0095 -84.307172)
		(stroke
			(width 0.072898)
			(type default)
		)
		(layer "F.Cu")
	)
	(gr_line
		(start 203.60005 -75.099926)
		(end 204.2668 -74.693526)
		(stroke
			(width 0.06223)
			(type default)
		)
		(layer "F.Cu")
	)
	(gr_line
		(start 203.60005 -74.299826)
		(end 204.2922 -73.866248)
		(stroke
			(width 0.06223)
			(type default)
		)
		(layer "F.Cu")
	)
	(gr_line
		(start 203.60005 -72.599296)
		(end 203.60005 -72.69988)
		(stroke
			(width 0.06223)
			(type default)
		)
		(layer "F.Cu")
	)
	(gr_line
		(start 203.60005 -72.599296)
		(end 203.905866 -72.29348)
		(stroke
			(width 0.06223)
			(type default)
		)
		(layer "F.Cu")
	)
	(gr_line
		(start 203.60005 -71.81215)
		(end 203.60005 -71.900034)
		(stroke
			(width 0.06223)
			(type default)
		)
		(layer "F.Cu")
	)
	(gr_line
		(start 203.60005 -71.81215)
		(end 203.91882 -71.49338)
		(stroke
			(width 0.06223)
			(type default)
		)
		(layer "F.Cu")
	)
	(gr_line
		(start 203.60005 -70.23735)
		(end 203.60005 -70.299834)
		(stroke
			(width 0.06223)
			(type default)
		)
		(layer "F.Cu")
	)
	(gr_line
		(start 203.60005 -70.23735)
		(end 203.94422 -69.89318)
		(stroke
			(width 0.06223)
			(type default)
		)
		(layer "F.Cu")
	)
	(gr_line
		(start 203.60005 -69.499988)
		(end 204.092302 -69.230494)
		(stroke
			(width 0.06223)
			(type default)
		)
		(layer "F.Cu")
	)
	(gr_line
		(start 203.60005 -67.79895)
		(end 203.60005 -67.900042)
		(stroke
			(width 0.06223)
			(type default)
		)
		(layer "F.Cu")
	)
	(gr_line
		(start 203.60005 -67.79895)
		(end 203.840588 -67.558412)
		(stroke
			(width 0.06223)
			(type default)
		)
		(layer "F.Cu")
	)
	(gr_line
		(start 203.60005 -67.099942)
		(end 204.05852 -66.641472)
		(stroke
			(width 0.06223)
			(type default)
		)
		(layer "F.Cu")
	)
	(gr_line
		(start 203.800202 -85.505798)
		(end 203.82611 -85.47989)
		(stroke
			(width 0.072898)
			(type default)
		)
		(layer "F.Cu")
	)
	(gr_arc
		(start 203.82611 -85.47989)
		(mid 203.899757 -85.30209)
		(end 203.82611 -85.12429)
		(stroke
			(width 0.072898)
			(type default)
		)
		(layer "F.Cu")
	)
	(gr_line
		(start 203.840588 -67.558412)
		(end 203.99121 -67.558412)
		(stroke
			(width 0.06223)
			(type default)
		)
		(layer "F.Cu")
	)
	(gr_line
		(start 203.905866 -72.29348)
		(end 203.990956 -72.29348)
		(stroke
			(width 0.06223)
			(type default)
		)
		(layer "F.Cu")
	)
	(gr_line
		(start 203.91882 -71.49338)
		(end 203.990956 -71.49338)
		(stroke
			(width 0.06223)
			(type default)
		)
		(layer "F.Cu")
	)
	(gr_line
		(start 203.94422 -69.89318)
		(end 204.356716 -69.89318)
		(stroke
			(width 0.06223)
			(type default)
		)
		(layer "F.Cu")
	)
	(gr_line
		(start 203.99375 -67.558412)
		(end 204.166724 -67.558412)
		(stroke
			(width 0.06223)
			(type default)
		)
		(layer "F.Cu")
	)
	(gr_arc
		(start 204.046328 -84.904072)
		(mid 204.224128 -84.977719)
		(end 204.401928 -84.904072)
		(stroke
			(width 0.072898)
			(type default)
		)
		(layer "F.Cu")
	)
	(gr_line
		(start 204.05852 -66.641472)
		(end 204.541628 -66.641472)
		(stroke
			(width 0.06223)
			(type default)
		)
		(layer "F.Cu")
	)
	(gr_line
		(start 204.098906 -69.226938)
		(end 204.332586 -69.098922)
		(stroke
			(width 0.06223)
			(type default)
		)
		(layer "F.Cu")
	)
	(gr_line
		(start 204.339444 -69.095366)
		(end 204.343 -69.093334)
		(stroke
			(width 0.06223)
			(type default)
		)
		(layer "F.Cu")
	)
	(gr_line
		(start 204.401928 -84.904072)
		(end 204.428598 -84.877402)
		(stroke
			(width 0.072898)
			(type default)
		)
		(layer "F.Cu")
	)
	(gr_line
		(start 204.443076 -69.89318)
		(end 204.568044 -69.89318)
		(stroke
			(width 0.06223)
			(type default)
		)
		(layer "F.Cu")
	)
	(gr_line
		(start 204.541628 -66.641472)
		(end 204.615288 -66.715132)
		(stroke
			(width 0.06223)
			(type default)
		)
		(layer "F.Cu")
	)
	(gr_line
		(start 204.895704 -71.575676)
		(end 205.05166 -71.575676)
		(stroke
			(width 0.06223)
			(type default)
		)
		(layer "F.Cu")
	)
	(gr_line
		(start 206.9084 -69.623178)
		(end 206.996284 -69.535294)
		(stroke
			(width 0.06223)
			(type default)
		)
		(layer "F.Cu")
	)
	(gr_line
		(start 207.0735 -81.915)
		(end 207.423258 -81.565242)
		(stroke
			(width 0.072898)
			(type default)
		)
		(layer "F.Cu")
	)
	(gr_line
		(start 207.0735 -81.915)
		(end 207.458564 -82.300064)
		(stroke
			(width 0.072898)
			(type default)
		)
		(layer "F.Cu")
	)
	(gr_line
		(start 207.458564 -83.39074)
		(end 207.522064 -83.45424)
		(stroke
			(width 0.072898)
			(type default)
		)
		(layer "F.Cu")
	)
	(gr_line
		(start 207.772254 -82.358992)
		(end 208.2165 -81.915)
		(stroke
			(width 0.072898)
			(type default)
		)
		(layer "F.Cu")
	)
	(gr_line
		(start 207.866742 -81.565242)
		(end 208.2165 -81.915)
		(stroke
			(width 0.072898)
			(type default)
		)
		(layer "F.Cu")
	)
	(gr_arc
		(start 208.367122 -84.707984)
		(mid 208.451606 -84.503932)
		(end 208.367122 -84.299806)
		(stroke
			(width 0.072898)
			(type default)
		)
		(layer "F.Cu")
	)
	(gr_arc
		(start 208.58734 -84.079588)
		(mid 208.791429 -84.164072)
		(end 208.995518 -84.079588)
		(stroke
			(width 0.072898)
			(type default)
		)
		(layer "F.Cu")
	)
	(gr_line
		(start 209.165444 -64.89319)
		(end 209.25282 -64.806068)
		(stroke
			(width 0.06223)
			(type default)
		)
		(layer "F.Cu")
	)
	(gr_line
		(start 209.869532 -64.189356)
		(end 209.957416 -64.101472)
		(stroke
			(width 0.06223)
			(type default)
		)
		(layer "F.Cu")
	)
	(gr_line
		(start 211.06003 -63.924688)
		(end 211.231226 -63.753492)
		(stroke
			(width 0.06223)
			(type default)
		)
		(layer "F.Cu")
	)
	(gr_line
		(start 211.228686 -66.367914)
		(end 211.399882 -66.196718)
		(stroke
			(width 0.06223)
			(type default)
		)
		(layer "F.Cu")
	)
	(gr_arc
		(start 211.231226 -63.753492)
		(mid 211.268195 -63.664475)
		(end 211.231226 -63.575438)
		(stroke
			(width 0.06223)
			(type default)
		)
		(layer "F.Cu")
	)
	(gr_arc
		(start 211.399882 -66.196718)
		(mid 211.436706 -66.107728)
		(end 211.399882 -66.018664)
		(stroke
			(width 0.06223)
			(type default)
		)
		(layer "F.Cu")
	)
	(gr_arc
		(start 211.518754 -63.288164)
		(mid 211.607654 -63.324988)
		(end 211.696554 -63.288164)
		(stroke
			(width 0.06223)
			(type default)
		)
		(layer "F.Cu")
	)
	(gr_arc
		(start 211.68741 -65.73139)
		(mid 211.77631 -65.768214)
		(end 211.86521 -65.73139)
		(stroke
			(width 0.06223)
			(type default)
		)
		(layer "F.Cu")
	)
	(gr_line
		(start 211.696554 -63.288164)
		(end 211.868258 -63.11646)
		(stroke
			(width 0.06223)
			(type default)
		)
		(layer "F.Cu")
	)
	(gr_line
		(start 211.86521 -65.73139)
		(end 212.036914 -65.559686)
		(stroke
			(width 0.06223)
			(type default)
		)
		(layer "F.Cu")
	)
	(gr_line
		(start 212.701886 -68.018914)
		(end 212.835744 -67.885056)
		(stroke
			(width 0.06223)
			(type default)
		)
		(layer "F.Cu")
	)
	(gr_arc
		(start 212.835744 -67.885056)
		(mid 212.88841 -67.758188)
		(end 212.835744 -67.63131)
		(stroke
			(width 0.06223)
			(type default)
		)
		(layer "F.Cu")
	)
	(gr_arc
		(start 213.123018 -67.343782)
		(mid 213.250018 -67.396387)
		(end 213.377018 -67.343782)
		(stroke
			(width 0.06223)
			(type default)
		)
		(layer "F.Cu")
	)
	(gr_line
		(start 213.377018 -67.343782)
		(end 213.510114 -67.210686)
		(stroke
			(width 0.06223)
			(type default)
		)
		(layer "F.Cu")
	)
	(gr_line
		(start 213.717886 -72.794114)
		(end 213.85149 -72.66051)
		(stroke
			(width 0.06223)
			(type default)
		)
		(layer "F.Cu")
	)
	(gr_arc
		(start 213.85149 -72.66051)
		(mid 213.904095 -72.53342)
		(end 213.85149 -72.406256)
		(stroke
			(width 0.06223)
			(type default)
		)
		(layer "F.Cu")
	)
	(gr_arc
		(start 214.139018 -72.118982)
		(mid 214.266018 -72.171587)
		(end 214.393018 -72.118982)
		(stroke
			(width 0.06223)
			(type default)
		)
		(layer "F.Cu")
	)
	(gr_line
		(start 214.225886 -69.492114)
		(end 214.359744 -69.358256)
		(stroke
			(width 0.06223)
			(type default)
		)
		(layer "F.Cu")
	)
	(gr_arc
		(start 214.359744 -69.358256)
		(mid 214.41241 -69.231388)
		(end 214.359744 -69.10451)
		(stroke
			(width 0.06223)
			(type default)
		)
		(layer "F.Cu")
	)
	(gr_line
		(start 214.393018 -72.118982)
		(end 214.526114 -71.985886)
		(stroke
			(width 0.06223)
			(type default)
		)
		(layer "F.Cu")
	)
	(gr_arc
		(start 214.647018 -68.816982)
		(mid 214.774018 -68.869587)
		(end 214.901018 -68.816982)
		(stroke
			(width 0.06223)
			(type default)
		)
		(layer "F.Cu")
	)
	(gr_line
		(start 214.901018 -68.816982)
		(end 215.034114 -68.683886)
		(stroke
			(width 0.06223)
			(type default)
		)
		(layer "F.Cu")
	)
	(gr_line
		(start 215.114886 -74.191114)
		(end 215.248744 -74.057256)
		(stroke
			(width 0.06223)
			(type default)
		)
		(layer "F.Cu")
	)
	(gr_arc
		(start 215.248744 -74.057256)
		(mid 215.301244 -73.93042)
		(end 215.248744 -73.80351)
		(stroke
			(width 0.06223)
			(type default)
		)
		(layer "F.Cu")
	)
	(gr_line
		(start 215.495886 -79.652114)
		(end 215.616282 -79.531718)
		(stroke
			(width 0.06223)
			(type default)
		)
		(layer "F.Cu")
	)
	(gr_arc
		(start 215.536018 -73.515982)
		(mid 215.663018 -73.568587)
		(end 215.790018 -73.515982)
		(stroke
			(width 0.06223)
			(type default)
		)
		(layer "F.Cu")
	)
	(gr_arc
		(start 215.616282 -79.531718)
		(mid 215.674148 -79.392018)
		(end 215.616282 -79.252318)
		(stroke
			(width 0.06223)
			(type default)
		)
		(layer "F.Cu")
	)
	(gr_line
		(start 215.790018 -73.515982)
		(end 215.923114 -73.382886)
		(stroke
			(width 0.06223)
			(type default)
		)
		(layer "F.Cu")
	)
	(gr_arc
		(start 215.90381 -78.96479)
		(mid 216.04351 -79.022656)
		(end 216.18321 -78.96479)
		(stroke
			(width 0.06223)
			(type default)
		)
		(layer "F.Cu")
	)
	(gr_line
		(start 216.18321 -78.96479)
		(end 216.304114 -78.843886)
		(stroke
			(width 0.06223)
			(type default)
		)
		(layer "F.Cu")
	)
	(gr_line
		(start 216.638886 -75.715114)
		(end 216.77249 -75.58151)
		(stroke
			(width 0.06223)
			(type default)
		)
		(layer "F.Cu")
	)
	(gr_arc
		(start 216.77249 -75.58151)
		(mid 216.825264 -75.454388)
		(end 216.77249 -75.327256)
		(stroke
			(width 0.06223)
			(type default)
		)
		(layer "F.Cu")
	)
	(gr_arc
		(start 217.060018 -75.039982)
		(mid 217.187018 -75.092587)
		(end 217.314018 -75.039982)
		(stroke
			(width 0.06223)
			(type default)
		)
		(layer "F.Cu")
	)
	(gr_line
		(start 217.314018 -75.039982)
		(end 217.447114 -74.906886)
		(stroke
			(width 0.06223)
			(type default)
		)
		(layer "F.Cu")
	)
	(gr_line
		(start 20.821396 -141.833092)
		(end 21.044916 -141.609572)
		(stroke
			(width 0.06223)
			(type default)
		)
		(layer "B.Cu")
	)
	(gr_line
		(start 20.82165 -140.808202)
		(end 21.044916 -141.031468)
		(stroke
			(width 0.06223)
			(type default)
		)
		(layer "B.Cu")
	)
	(gr_line
		(start 21.923502 -141.650212)
		(end 22.0345 -141.76121)
		(stroke
			(width 0.06223)
			(type default)
		)
		(layer "B.Cu")
	)
	(gr_line
		(start 21.923502 -141.072108)
		(end 22.0345 -140.96111)
		(stroke
			(width 0.06223)
			(type default)
		)
		(layer "B.Cu")
	)
	(gr_arc
		(start 76.985876 -67.61099)
		(mid 77.1901 -67.526411)
		(end 77.274674 -67.322192)
		(stroke
			(width 0.072898)
			(type default)
		)
		(layer "B.Cu")
	)
	(gr_arc
		(start 77.274674 -68.211192)
		(mid 77.190011 -68.006799)
		(end 76.985622 -67.92214)
		(stroke
			(width 0.072898)
			(type default)
		)
		(layer "B.Cu")
	)
	(gr_line
		(start 77.283818 -93.743526)
		(end 77.283818 -93.800168)
		(stroke
			(width 0.072898)
			(type default)
		)
		(layer "B.Cu")
	)
	(gr_arc
		(start 77.283818 -92.967556)
		(mid 77.351875 -93.131913)
		(end 77.516228 -93.199966)
		(stroke
			(width 0.072898)
			(type default)
		)
		(layer "B.Cu")
	)
	(gr_line
		(start 77.283818 -92.911168)
		(end 77.283818 -92.967556)
		(stroke
			(width 0.072898)
			(type default)
		)
		(layer "B.Cu")
	)
	(gr_arc
		(start 77.283818 -86.510368)
		(mid 77.368395 -86.714594)
		(end 77.572616 -86.799166)
		(stroke
			(width 0.072898)
			(type default)
		)
		(layer "B.Cu")
	)
	(gr_line
		(start 77.283818 -80.916526)
		(end 77.283818 -80.998568)
		(stroke
			(width 0.072898)
			(type default)
		)
		(layer "B.Cu")
	)
	(gr_arc
		(start 77.283818 -80.191356)
		(mid 77.344436 -80.337753)
		(end 77.490828 -80.398366)
		(stroke
			(width 0.072898)
			(type default)
		)
		(layer "B.Cu")
	)
	(gr_line
		(start 77.283818 -80.109568)
		(end 77.283818 -80.191356)
		(stroke
			(width 0.072898)
			(type default)
		)
		(layer "B.Cu")
	)
	(gr_line
		(start 77.283818 -74.541126)
		(end 77.283818 -74.597768)
		(stroke
			(width 0.072898)
			(type default)
		)
		(layer "B.Cu")
	)
	(gr_arc
		(start 77.283818 -73.765156)
		(mid 77.351875 -73.929513)
		(end 77.516228 -73.997566)
		(stroke
			(width 0.072898)
			(type default)
		)
		(layer "B.Cu")
	)
	(gr_line
		(start 77.283818 -73.708768)
		(end 77.283818 -73.765156)
		(stroke
			(width 0.072898)
			(type default)
		)
		(layer "B.Cu")
	)
	(gr_arc
		(start 77.490828 -80.709516)
		(mid 77.34445 -80.770148)
		(end 77.283818 -80.916526)
		(stroke
			(width 0.072898)
			(type default)
		)
		(layer "B.Cu")
	)
	(gr_arc
		(start 77.516228 -93.511116)
		(mid 77.351889 -93.579187)
		(end 77.283818 -93.743526)
		(stroke
			(width 0.072898)
			(type default)
		)
		(layer "B.Cu")
	)
	(gr_arc
		(start 77.516228 -74.308716)
		(mid 77.351889 -74.376787)
		(end 77.283818 -74.541126)
		(stroke
			(width 0.072898)
			(type default)
		)
		(layer "B.Cu")
	)
	(gr_arc
		(start 77.57287 -87.110316)
		(mid 77.368479 -87.194977)
		(end 77.283818 -87.399368)
		(stroke
			(width 0.072898)
			(type default)
		)
		(layer "B.Cu")
	)
	(gr_arc
		(start 78.122018 -89.710768)
		(mid 78.206595 -89.914994)
		(end 78.410816 -89.999566)
		(stroke
			(width 0.072898)
			(type default)
		)
		(layer "B.Cu")
	)
	(gr_arc
		(start 78.122018 -83.335368)
		(mid 78.206595 -83.539594)
		(end 78.410816 -83.624166)
		(stroke
			(width 0.072898)
			(type default)
		)
		(layer "B.Cu")
	)
	(gr_arc
		(start 78.122018 -76.909168)
		(mid 78.206595 -77.113394)
		(end 78.410816 -77.197966)
		(stroke
			(width 0.072898)
			(type default)
		)
		(layer "B.Cu")
	)
	(gr_line
		(start 78.122018 -71.366126)
		(end 78.122018 -71.397368)
		(stroke
			(width 0.072898)
			(type default)
		)
		(layer "B.Cu")
	)
	(gr_arc
		(start 78.122018 -70.539356)
		(mid 78.197515 -70.721674)
		(end 78.379828 -70.797166)
		(stroke
			(width 0.072898)
			(type default)
		)
		(layer "B.Cu")
	)
	(gr_line
		(start 78.122018 -70.508368)
		(end 78.122018 -70.539356)
		(stroke
			(width 0.072898)
			(type default)
		)
		(layer "B.Cu")
	)
	(gr_arc
		(start 78.379828 -71.108316)
		(mid 78.197529 -71.183827)
		(end 78.122018 -71.366126)
		(stroke
			(width 0.072898)
			(type default)
		)
		(layer "B.Cu")
	)
	(gr_arc
		(start 78.41107 -90.310716)
		(mid 78.206679 -90.395377)
		(end 78.122018 -90.599768)
		(stroke
			(width 0.072898)
			(type default)
		)
		(layer "B.Cu")
	)
	(gr_arc
		(start 78.41107 -83.935316)
		(mid 78.206679 -84.019977)
		(end 78.122018 -84.224368)
		(stroke
			(width 0.072898)
			(type default)
		)
		(layer "B.Cu")
	)
	(gr_arc
		(start 78.41107 -77.509116)
		(mid 78.206679 -77.593777)
		(end 78.122018 -77.798168)
		(stroke
			(width 0.072898)
			(type default)
		)
		(layer "B.Cu")
	)
	(gr_line
		(start 78.802992 -66.665856)
		(end 78.952852 -66.815716)
		(stroke
			(width 0.072898)
			(type default)
		)
		(layer "B.Cu")
	)
	(gr_line
		(start 78.952852 -66.815716)
		(end 79.391002 -66.815716)
		(stroke
			(width 0.072898)
			(type default)
		)
		(layer "B.Cu")
	)
	(gr_line
		(start 79.114142 -66.352166)
		(end 79.229712 -66.352166)
		(stroke
			(width 0.072898)
			(type default)
		)
		(layer "B.Cu")
	)
	(gr_line
		(start 79.391002 -66.815716)
		(end 79.540862 -66.665856)
		(stroke
			(width 0.072898)
			(type default)
		)
		(layer "B.Cu")
	)
	(gr_line
		(start 79.984092 -66.665856)
		(end 80.133952 -66.815716)
		(stroke
			(width 0.072898)
			(type default)
		)
		(layer "B.Cu")
	)
	(gr_line
		(start 80.133952 -66.815716)
		(end 80.572102 -66.815716)
		(stroke
			(width 0.072898)
			(type default)
		)
		(layer "B.Cu")
	)
	(gr_line
		(start 80.295242 -66.352166)
		(end 80.410812 -66.352166)
		(stroke
			(width 0.072898)
			(type default)
		)
		(layer "B.Cu")
	)
	(gr_line
		(start 80.572102 -66.815716)
		(end 80.721962 -66.665856)
		(stroke
			(width 0.072898)
			(type default)
		)
		(layer "B.Cu")
	)
	(gr_line
		(start 81.432654 -84.74075)
		(end 81.495138 -84.803488)
		(stroke
			(width 0.072898)
			(type default)
		)
		(layer "B.Cu")
	)
	(gr_line
		(start 85.71611 -63.264288)
		(end 85.71992 -63.243968)
		(stroke
			(width 0.072898)
			(type default)
		)
		(layer "B.Cu")
	)
	(gr_line
		(start 85.71611 -63.264288)
		(end 85.720174 -63.284354)
		(stroke
			(width 0.072898)
			(type default)
		)
		(layer "B.Cu")
	)
	(gr_line
		(start 85.726524 -63.211456)
		(end 85.728556 -63.200534)
		(stroke
			(width 0.072898)
			(type default)
		)
		(layer "B.Cu")
	)
	(gr_line
		(start 85.726778 -63.208916)
		(end 85.728556 -63.200534)
		(stroke
			(width 0.072898)
			(type default)
		)
		(layer "B.Cu")
	)
	(gr_line
		(start 85.88883 -62.375796)
		(end 86.015068 -61.725556)
		(stroke
			(width 0.072898)
			(type default)
		)
		(layer "B.Cu")
	)
	(gr_line
		(start 86.033102 -63.264034)
		(end 86.1441 -62.69355)
		(stroke
			(width 0.072898)
			(type default)
		)
		(layer "B.Cu")
	)
	(gr_line
		(start 86.114128 -61.216286)
		(end 86.240366 -60.567062)
		(stroke
			(width 0.072898)
			(type default)
		)
		(layer "B.Cu")
	)
	(gr_line
		(start 86.189566 -62.472824)
		(end 86.365334 -62.354206)
		(stroke
			(width 0.072898)
			(type default)
		)
		(layer "B.Cu")
	)
	(gr_line
		(start 86.198964 -67.031616)
		(end 86.209632 -66.975736)
		(stroke
			(width 0.072898)
			(type default)
		)
		(layer "B.Cu")
	)
	(gr_line
		(start 86.32825 -61.745368)
		(end 86.411816 -61.315346)
		(stroke
			(width 0.072898)
			(type default)
		)
		(layer "B.Cu")
	)
	(gr_line
		(start 86.330282 -61.748416)
		(end 86.4489 -61.924184)
		(stroke
			(width 0.072898)
			(type default)
		)
		(layer "B.Cu")
	)
	(gr_line
		(start 86.339934 -60.056014)
		(end 86.465918 -59.407044)
		(stroke
			(width 0.072898)
			(type default)
		)
		(layer "B.Cu")
	)
	(gr_line
		(start 86.365334 -62.354206)
		(end 86.4489 -61.924184)
		(stroke
			(width 0.072898)
			(type default)
		)
		(layer "B.Cu")
	)
	(gr_line
		(start 86.414864 -61.313314)
		(end 86.590632 -61.19495)
		(stroke
			(width 0.072898)
			(type default)
		)
		(layer "B.Cu")
	)
	(gr_line
		(start 86.47811 -65.59804)
		(end 86.482428 -65.575688)
		(stroke
			(width 0.072898)
			(type default)
		)
		(layer "B.Cu")
	)
	(gr_line
		(start 86.47811 -65.553082)
		(end 86.482428 -65.575688)
		(stroke
			(width 0.072898)
			(type default)
		)
		(layer "B.Cu")
	)
	(gr_line
		(start 86.553548 -60.586112)
		(end 86.637114 -60.15609)
		(stroke
			(width 0.072898)
			(type default)
		)
		(layer "B.Cu")
	)
	(gr_line
		(start 86.55558 -60.58916)
		(end 86.674198 -60.764674)
		(stroke
			(width 0.072898)
			(type default)
		)
		(layer "B.Cu")
	)
	(gr_line
		(start 86.564724 -58.898282)
		(end 86.69147 -58.247026)
		(stroke
			(width 0.072898)
			(type default)
		)
		(layer "B.Cu")
	)
	(gr_line
		(start 86.590632 -61.19495)
		(end 86.674198 -60.764674)
		(stroke
			(width 0.072898)
			(type default)
		)
		(layer "B.Cu")
	)
	(gr_line
		(start 86.640162 -60.154058)
		(end 86.81593 -60.03544)
		(stroke
			(width 0.072898)
			(type default)
		)
		(layer "B.Cu")
	)
	(gr_line
		(start 86.756748 -47.602902)
		(end 86.757002 -47.602902)
		(stroke
			(width 0.072898)
			(type default)
		)
		(layer "B.Cu")
	)
	(gr_line
		(start 86.756748 -47.602394)
		(end 86.756748 -47.602902)
		(stroke
			(width 0.072898)
			(type default)
		)
		(layer "B.Cu")
	)
	(gr_line
		(start 86.756748 -47.602394)
		(end 86.761066 -47.580042)
		(stroke
			(width 0.072898)
			(type default)
		)
		(layer "B.Cu")
	)
	(gr_line
		(start 86.757002 -47.602902)
		(end 86.761066 -47.623222)
		(stroke
			(width 0.072898)
			(type default)
		)
		(layer "B.Cu")
	)
	(gr_line
		(start 86.761066 -47.579788)
		(end 86.761066 -47.580042)
		(stroke
			(width 0.072898)
			(type default)
		)
		(layer "B.Cu")
	)
	(gr_line
		(start 86.780878 -59.429396)
		(end 86.899496 -59.605418)
		(stroke
			(width 0.072898)
			(type default)
		)
		(layer "B.Cu")
	)
	(gr_line
		(start 86.81593 -60.03544)
		(end 86.899496 -59.605418)
		(stroke
			(width 0.072898)
			(type default)
		)
		(layer "B.Cu")
	)
	(gr_line
		(start 86.86546 -58.994802)
		(end 87.041228 -58.87593)
		(stroke
			(width 0.072898)
			(type default)
		)
		(layer "B.Cu")
	)
	(gr_line
		(start 87.006176 -58.27014)
		(end 87.124794 -58.445908)
		(stroke
			(width 0.072898)
			(type default)
		)
		(layer "B.Cu")
	)
	(gr_line
		(start 87.041228 -58.87593)
		(end 87.124794 -58.445908)
		(stroke
			(width 0.072898)
			(type default)
		)
		(layer "B.Cu")
	)
	(gr_line
		(start 87.08644 -49.28743)
		(end 87.214964 -49.94402)
		(stroke
			(width 0.072898)
			(type default)
		)
		(layer "B.Cu")
	)
	(gr_line
		(start 87.305388 -68.587874)
		(end 87.316818 -68.54063)
		(stroke
			(width 0.072898)
			(type default)
		)
		(layer "B.Cu")
	)
	(gr_line
		(start 87.31377 -50.447702)
		(end 87.441786 -51.103022)
		(stroke
			(width 0.072898)
			(type default)
		)
		(layer "B.Cu")
	)
	(gr_line
		(start 87.350346 -62.546484)
		(end 87.352378 -62.560454)
		(stroke
			(width 0.072898)
			(type default)
		)
		(layer "B.Cu")
	)
	(gr_line
		(start 87.350346 -62.546484)
		(end 87.35314 -62.531752)
		(stroke
			(width 0.072898)
			(type default)
		)
		(layer "B.Cu")
	)
	(gr_line
		(start 87.365586 -64.540892)
		(end 87.36584 -64.540892)
		(stroke
			(width 0.072898)
			(type default)
		)
		(layer "B.Cu")
	)
	(gr_line
		(start 87.365586 -64.540892)
		(end 87.367872 -64.555878)
		(stroke
			(width 0.072898)
			(type default)
		)
		(layer "B.Cu")
	)
	(gr_line
		(start 87.36584 -64.540892)
		(end 87.36838 -64.527684)
		(stroke
			(width 0.072898)
			(type default)
		)
		(layer "B.Cu")
	)
	(gr_line
		(start 87.387938 -49.193196)
		(end 87.56396 -49.311814)
		(stroke
			(width 0.072898)
			(type default)
		)
		(layer "B.Cu")
	)
	(gr_line
		(start 87.52967 -49.918112)
		(end 87.648034 -49.741836)
		(stroke
			(width 0.072898)
			(type default)
		)
		(layer "B.Cu")
	)
	(gr_line
		(start 87.56396 -49.311814)
		(end 87.648034 -49.741836)
		(stroke
			(width 0.072898)
			(type default)
		)
		(layer "B.Cu")
	)
	(gr_line
		(start 87.61476 -50.352452)
		(end 87.790782 -50.470816)
		(stroke
			(width 0.072898)
			(type default)
		)
		(layer "B.Cu")
	)
	(gr_line
		(start 87.756492 -51.077114)
		(end 87.874856 -50.900838)
		(stroke
			(width 0.072898)
			(type default)
		)
		(layer "B.Cu")
	)
	(gr_line
		(start 87.790782 -50.470816)
		(end 87.874856 -50.900838)
		(stroke
			(width 0.072898)
			(type default)
		)
		(layer "B.Cu")
	)
	(gr_line
		(start 87.840312 -63.713106)
		(end 87.842852 -63.699136)
		(stroke
			(width 0.072898)
			(type default)
		)
		(layer "B.Cu")
	)
	(gr_line
		(start 87.840566 -63.684404)
		(end 87.842852 -63.699136)
		(stroke
			(width 0.072898)
			(type default)
		)
		(layer "B.Cu")
	)
	(gr_line
		(start 87.90813 -66.070988)
		(end 87.91321 -66.049906)
		(stroke
			(width 0.072898)
			(type default)
		)
		(layer "B.Cu")
	)
	(gr_line
		(start 87.909654 -66.027808)
		(end 87.91321 -66.049906)
		(stroke
			(width 0.072898)
			(type default)
		)
		(layer "B.Cu")
	)
	(gr_line
		(start 88.074754 -52.760372)
		(end 88.079072 -52.73802)
		(stroke
			(width 0.072898)
			(type default)
		)
		(layer "B.Cu")
	)
	(gr_line
		(start 88.074754 -52.715414)
		(end 88.079072 -52.73802)
		(stroke
			(width 0.072898)
			(type default)
		)
		(layer "B.Cu")
	)
	(gr_line
		(start 88.074754 -52.71516)
		(end 88.074754 -52.715668)
		(stroke
			(width 0.072898)
			(type default)
		)
		(layer "B.Cu")
	)
	(gr_line
		(start 88.138254 -72.880728)
		(end 88.149176 -72.826372)
		(stroke
			(width 0.072898)
			(type default)
		)
		(layer "B.Cu")
	)
	(gr_line
		(start 88.697562 -62.110112)
		(end 88.70442 -62.075568)
		(stroke
			(width 0.072898)
			(type default)
		)
		(layer "B.Cu")
	)
	(gr_line
		(start 88.697562 -62.110112)
		(end 88.70696 -62.144148)
		(stroke
			(width 0.072898)
			(type default)
		)
		(layer "B.Cu")
	)
	(gr_line
		(start 88.80221 -44.036742)
		(end 88.806782 -44.06011)
		(stroke
			(width 0.072898)
			(type default)
		)
		(layer "B.Cu")
	)
	(gr_line
		(start 88.80221 -44.036742)
		(end 88.807036 -44.01312)
		(stroke
			(width 0.072898)
			(type default)
		)
		(layer "B.Cu")
	)
	(gr_line
		(start 88.806782 -44.01312)
		(end 88.807036 -44.012104)
		(stroke
			(width 0.072898)
			(type default)
		)
		(layer "B.Cu")
	)
	(gr_line
		(start 88.83142 -90.51544)
		(end 88.84285 -90.467688)
		(stroke
			(width 0.072898)
			(type default)
		)
		(layer "B.Cu")
	)
	(gr_line
		(start 88.84793 -75.193652)
		(end 88.858852 -75.139296)
		(stroke
			(width 0.072898)
			(type default)
		)
		(layer "B.Cu")
	)
	(gr_line
		(start 88.930734 -50.761646)
		(end 88.935052 -50.783998)
		(stroke
			(width 0.072898)
			(type default)
		)
		(layer "B.Cu")
	)
	(gr_line
		(start 88.930734 -50.761646)
		(end 88.935052 -50.739548)
		(stroke
			(width 0.072898)
			(type default)
		)
		(layer "B.Cu")
	)
	(gr_line
		(start 88.935052 -50.738786)
		(end 88.935052 -50.739294)
		(stroke
			(width 0.072898)
			(type default)
		)
		(layer "B.Cu")
	)
	(gr_line
		(start 89.344754 -87.00008)
		(end 89.348818 -86.983062)
		(stroke
			(width 0.072898)
			(type default)
		)
		(layer "B.Cu")
	)
	(gr_line
		(start 89.348818 -86.983062)
		(end 89.35847 -86.968838)
		(stroke
			(width 0.072898)
			(type default)
		)
		(layer "B.Cu")
	)
	(gr_line
		(start 89.351104 -32.4231)
		(end 89.357962 -32.458406)
		(stroke
			(width 0.072898)
			(type default)
		)
		(layer "B.Cu")
	)
	(gr_line
		(start 89.351104 -32.4231)
		(end 89.360756 -32.38881)
		(stroke
			(width 0.072898)
			(type default)
		)
		(layer "B.Cu")
	)
	(gr_line
		(start 89.360756 -32.388302)
		(end 89.36101 -32.387286)
		(stroke
			(width 0.072898)
			(type default)
		)
		(layer "B.Cu")
	)
	(gr_line
		(start 89.366852 -78.56093)
		(end 89.377774 -78.506574)
		(stroke
			(width 0.072898)
			(type default)
		)
		(layer "B.Cu")
	)
	(gr_line
		(start 89.57818 -52.460398)
		(end 89.582244 -52.481226)
		(stroke
			(width 0.072898)
			(type default)
		)
		(layer "B.Cu")
	)
	(gr_line
		(start 89.578434 -52.501292)
		(end 89.582244 -52.481226)
		(stroke
			(width 0.072898)
			(type default)
		)
		(layer "B.Cu")
	)
	(gr_line
		(start 89.750392 -64.740282)
		(end 89.75979 -64.774572)
		(stroke
			(width 0.072898)
			(type default)
		)
		(layer "B.Cu")
	)
	(gr_line
		(start 89.752932 -64.80937)
		(end 89.75979 -64.774572)
		(stroke
			(width 0.072898)
			(type default)
		)
		(layer "B.Cu")
	)
	(gr_line
		(start 89.842086 -33.317434)
		(end 89.84615 -33.338008)
		(stroke
			(width 0.072898)
			(type default)
		)
		(layer "B.Cu")
	)
	(gr_line
		(start 89.84234 -33.357566)
		(end 89.84615 -33.338008)
		(stroke
			(width 0.072898)
			(type default)
		)
		(layer "B.Cu")
	)
	(gr_line
		(start 89.845642 -47.709328)
		(end 89.84996 -47.687992)
		(stroke
			(width 0.072898)
			(type default)
		)
		(layer "B.Cu")
	)
	(gr_line
		(start 89.845642 -47.66564)
		(end 89.84996 -47.687992)
		(stroke
			(width 0.072898)
			(type default)
		)
		(layer "B.Cu")
	)
	(gr_line
		(start 90.036396 -44.02074)
		(end 90.040968 -44.044108)
		(stroke
			(width 0.072898)
			(type default)
		)
		(layer "B.Cu")
	)
	(gr_line
		(start 90.036396 -44.02074)
		(end 90.041222 -43.997118)
		(stroke
			(width 0.072898)
			(type default)
		)
		(layer "B.Cu")
	)
	(gr_line
		(start 90.040968 -43.997118)
		(end 90.041222 -43.996102)
		(stroke
			(width 0.072898)
			(type default)
		)
		(layer "B.Cu")
	)
	(gr_line
		(start 90.072464 -61.589158)
		(end 90.080338 -61.552074)
		(stroke
			(width 0.072898)
			(type default)
		)
		(layer "B.Cu")
	)
	(gr_line
		(start 90.072464 -61.589158)
		(end 90.08237 -61.625226)
		(stroke
			(width 0.072898)
			(type default)
		)
		(layer "B.Cu")
	)
	(gr_line
		(start 90.094562 -29.784294)
		(end 90.115644 -29.709872)
		(stroke
			(width 0.072898)
			(type default)
		)
		(layer "B.Cu")
	)
	(gr_line
		(start 90.115644 -29.709872)
		(end 90.18016 -29.666692)
		(stroke
			(width 0.072898)
			(type default)
		)
		(layer "B.Cu")
	)
	(gr_line
		(start 90.14079 -50.687478)
		(end 90.145108 -50.709322)
		(stroke
			(width 0.072898)
			(type default)
		)
		(layer "B.Cu")
	)
	(gr_line
		(start 90.14079 -50.687478)
		(end 90.145108 -50.665634)
		(stroke
			(width 0.072898)
			(type default)
		)
		(layer "B.Cu")
	)
	(gr_line
		(start 90.359738 -79.473044)
		(end 90.37066 -79.418688)
		(stroke
			(width 0.072898)
			(type default)
		)
		(layer "B.Cu")
	)
	(gr_line
		(start 90.742008 -32.33928)
		(end 90.747088 -32.313372)
		(stroke
			(width 0.072898)
			(type default)
		)
		(layer "B.Cu")
	)
	(gr_line
		(start 90.742008 -32.33928)
		(end 90.747596 -32.364426)
		(stroke
			(width 0.072898)
			(type default)
		)
		(layer "B.Cu")
	)
	(gr_line
		(start 90.747088 -32.313626)
		(end 90.747342 -32.312864)
		(stroke
			(width 0.072898)
			(type default)
		)
		(layer "B.Cu")
	)
	(gr_line
		(start 90.875104 -52.771294)
		(end 90.87993 -52.795424)
		(stroke
			(width 0.072898)
			(type default)
		)
		(layer "B.Cu")
	)
	(gr_line
		(start 90.875358 -52.818792)
		(end 90.87993 -52.795424)
		(stroke
			(width 0.072898)
			(type default)
		)
		(layer "B.Cu")
	)
	(gr_line
		(start 91.063572 -47.615348)
		(end 91.06789 -47.592996)
		(stroke
			(width 0.072898)
			(type default)
		)
		(layer "B.Cu")
	)
	(gr_line
		(start 91.063572 -47.571152)
		(end 91.06789 -47.592996)
		(stroke
			(width 0.072898)
			(type default)
		)
		(layer "B.Cu")
	)
	(gr_line
		(start 91.068144 -64.013334)
		(end 91.077542 -64.047624)
		(stroke
			(width 0.072898)
			(type default)
		)
		(layer "B.Cu")
	)
	(gr_line
		(start 91.070684 -64.082422)
		(end 91.077542 -64.047624)
		(stroke
			(width 0.072898)
			(type default)
		)
		(layer "B.Cu")
	)
	(gr_line
		(start 91.240356 -30.574488)
		(end 91.260676 -30.50413)
		(stroke
			(width 0.072898)
			(type default)
		)
		(layer "B.Cu")
	)
	(gr_line
		(start 91.247976 -43.943016)
		(end 91.252802 -43.918632)
		(stroke
			(width 0.072898)
			(type default)
		)
		(layer "B.Cu")
	)
	(gr_line
		(start 91.247976 -43.943016)
		(end 91.253056 -43.967654)
		(stroke
			(width 0.072898)
			(type default)
		)
		(layer "B.Cu")
	)
	(gr_line
		(start 91.252802 -43.918124)
		(end 91.252802 -43.918632)
		(stroke
			(width 0.072898)
			(type default)
		)
		(layer "B.Cu")
	)
	(gr_line
		(start 91.260676 -30.50413)
		(end 91.322398 -30.462982)
		(stroke
			(width 0.072898)
			(type default)
		)
		(layer "B.Cu")
	)
	(gr_line
		(start 91.261184 -33.25368)
		(end 91.266772 -33.279588)
		(stroke
			(width 0.072898)
			(type default)
		)
		(layer "B.Cu")
	)
	(gr_line
		(start 91.261692 -33.305242)
		(end 91.266772 -33.279588)
		(stroke
			(width 0.072898)
			(type default)
		)
		(layer "B.Cu")
	)
	(gr_line
		(start 91.359482 -80.322928)
		(end 91.37269 -80.30337)
		(stroke
			(width 0.072898)
			(type default)
		)
		(layer "B.Cu")
	)
	(gr_line
		(start 91.37269 -80.30337)
		(end 91.377262 -80.28051)
		(stroke
			(width 0.072898)
			(type default)
		)
		(layer "B.Cu")
	)
	(gr_line
		(start 91.96959 -34.335974)
		(end 91.973908 -34.314384)
		(stroke
			(width 0.072898)
			(type default)
		)
		(layer "B.Cu")
	)
	(gr_line
		(start 91.973908 -34.314384)
		(end 91.9861 -34.29635)
		(stroke
			(width 0.072898)
			(type default)
		)
		(layer "B.Cu")
	)
	(gr_line
		(start 92.035884 -51.492658)
		(end 92.041472 -51.51882)
		(stroke
			(width 0.072898)
			(type default)
		)
		(layer "B.Cu")
	)
	(gr_line
		(start 92.035884 -51.492658)
		(end 92.041726 -51.465734)
		(stroke
			(width 0.072898)
			(type default)
		)
		(layer "B.Cu")
	)
	(gr_line
		(start 92.437712 -51.885596)
		(end 92.443554 -51.91252)
		(stroke
			(width 0.072898)
			(type default)
		)
		(layer "B.Cu")
	)
	(gr_line
		(start 92.437966 -51.938936)
		(end 92.443554 -51.91252)
		(stroke
			(width 0.072898)
			(type default)
		)
		(layer "B.Cu")
	)
	(gr_line
		(start 92.489528 -43.577764)
		(end 92.4941 -43.601132)
		(stroke
			(width 0.072898)
			(type default)
		)
		(layer "B.Cu")
	)
	(gr_line
		(start 92.489528 -43.577764)
		(end 92.494354 -43.553634)
		(stroke
			(width 0.072898)
			(type default)
		)
		(layer "B.Cu")
	)
	(gr_line
		(start 92.756736 -49.54778)
		(end 92.762578 -49.574958)
		(stroke
			(width 0.072898)
			(type default)
		)
		(layer "B.Cu")
	)
	(gr_line
		(start 92.75699 -49.60112)
		(end 92.762578 -49.574958)
		(stroke
			(width 0.072898)
			(type default)
		)
		(layer "B.Cu")
	)
	(gr_line
		(start 92.787978 -36.24961)
		(end 92.792296 -36.227004)
		(stroke
			(width 0.072898)
			(type default)
		)
		(layer "B.Cu")
	)
	(gr_line
		(start 92.792296 -36.227004)
		(end 92.805504 -36.207192)
		(stroke
			(width 0.072898)
			(type default)
		)
		(layer "B.Cu")
	)
	(gr_line
		(start 93.010482 -79.967582)
		(end 93.022674 -79.949548)
		(stroke
			(width 0.072898)
			(type default)
		)
		(layer "B.Cu")
	)
	(gr_line
		(start 93.022674 -79.949548)
		(end 93.026992 -79.927958)
		(stroke
			(width 0.072898)
			(type default)
		)
		(layer "B.Cu")
	)
	(gr_line
		(start 93.317568 -51.911758)
		(end 93.32214 -51.935126)
		(stroke
			(width 0.072898)
			(type default)
		)
		(layer "B.Cu")
	)
	(gr_line
		(start 93.317568 -51.911758)
		(end 93.32214 -51.88839)
		(stroke
			(width 0.072898)
			(type default)
		)
		(layer "B.Cu")
	)
	(gr_line
		(start 93.763846 -37.211254)
		(end 93.768164 -37.188648)
		(stroke
			(width 0.072898)
			(type default)
		)
		(layer "B.Cu")
	)
	(gr_line
		(start 93.768164 -37.188648)
		(end 93.781372 -37.168836)
		(stroke
			(width 0.072898)
			(type default)
		)
		(layer "B.Cu")
	)
	(gr_line
		(start 94.050358 -49.790858)
		(end 94.055184 -49.814988)
		(stroke
			(width 0.072898)
			(type default)
		)
		(layer "B.Cu")
	)
	(gr_line
		(start 94.050612 -49.838356)
		(end 94.055184 -49.814988)
		(stroke
			(width 0.072898)
			(type default)
		)
		(layer "B.Cu")
	)
	(gr_line
		(start 94.160086 -54.551072)
		(end 94.16034 -54.551834)
		(stroke
			(width 0.072898)
			(type default)
		)
		(layer "B.Cu")
	)
	(gr_line
		(start 94.16034 -54.598062)
		(end 94.164912 -54.575202)
		(stroke
			(width 0.072898)
			(type default)
		)
		(layer "B.Cu")
	)
	(gr_line
		(start 94.16034 -54.55158)
		(end 94.164912 -54.575202)
		(stroke
			(width 0.072898)
			(type default)
		)
		(layer "B.Cu")
	)
	(gr_line
		(start 94.230698 -44.06646)
		(end 94.23527 -44.089828)
		(stroke
			(width 0.072898)
			(type default)
		)
		(layer "B.Cu")
	)
	(gr_line
		(start 94.230698 -44.06646)
		(end 94.235524 -44.04233)
		(stroke
			(width 0.072898)
			(type default)
		)
		(layer "B.Cu")
	)
	(gr_line
		(start 94.239588 -80.206596)
		(end 94.25178 -80.188562)
		(stroke
			(width 0.072898)
			(type default)
		)
		(layer "B.Cu")
	)
	(gr_line
		(start 94.25178 -80.188562)
		(end 94.256098 -80.166972)
		(stroke
			(width 0.072898)
			(type default)
		)
		(layer "B.Cu")
	)
	(gr_line
		(start 94.590616 -30.389068)
		(end 94.604078 -30.369002)
		(stroke
			(width 0.072898)
			(type default)
		)
		(layer "B.Cu")
	)
	(gr_line
		(start 94.604078 -30.369002)
		(end 94.62389 -30.356048)
		(stroke
			(width 0.072898)
			(type default)
		)
		(layer "B.Cu")
	)
	(gr_line
		(start 94.706694 -83.322414)
		(end 94.788228 -83.24088)
		(stroke
			(width 0.072898)
			(type default)
		)
		(layer "B.Cu")
	)
	(gr_line
		(start 94.708472 -83.764374)
		(end 94.920562 -83.764374)
		(stroke
			(width 0.072898)
			(type default)
		)
		(layer "B.Cu")
	)
	(gr_line
		(start 94.920562 -83.764374)
		(end 95.230188 -83.454494)
		(stroke
			(width 0.072898)
			(type default)
		)
		(layer "B.Cu")
	)
	(gr_line
		(start 95.230188 -83.242658)
		(end 95.230188 -83.454494)
		(stroke
			(width 0.072898)
			(type default)
		)
		(layer "B.Cu")
	)
	(gr_line
		(start 95.429324 -44.147994)
		(end 95.433896 -44.171362)
		(stroke
			(width 0.072898)
			(type default)
		)
		(layer "B.Cu")
	)
	(gr_line
		(start 95.429324 -44.147994)
		(end 95.433896 -44.12488)
		(stroke
			(width 0.072898)
			(type default)
		)
		(layer "B.Cu")
	)
	(gr_line
		(start 95.433896 -44.124626)
		(end 95.43415 -44.123864)
		(stroke
			(width 0.072898)
			(type default)
		)
		(layer "B.Cu")
	)
	(gr_line
		(start 95.541846 -82.487262)
		(end 95.62338 -82.405728)
		(stroke
			(width 0.072898)
			(type default)
		)
		(layer "B.Cu")
	)
	(gr_line
		(start 95.543624 -82.929222)
		(end 95.755714 -82.929222)
		(stroke
			(width 0.072898)
			(type default)
		)
		(layer "B.Cu")
	)
	(gr_line
		(start 95.69069 -36.779454)
		(end 95.694754 -36.758118)
		(stroke
			(width 0.072898)
			(type default)
		)
		(layer "B.Cu")
	)
	(gr_line
		(start 95.694754 -36.758118)
		(end 95.7072 -36.739322)
		(stroke
			(width 0.072898)
			(type default)
		)
		(layer "B.Cu")
	)
	(gr_line
		(start 95.755714 -82.929222)
		(end 96.06534 -82.619342)
		(stroke
			(width 0.072898)
			(type default)
		)
		(layer "B.Cu")
	)
	(gr_line
		(start 95.991426 -51.271424)
		(end 95.996252 -51.295554)
		(stroke
			(width 0.072898)
			(type default)
		)
		(layer "B.Cu")
	)
	(gr_line
		(start 95.99168 -51.318922)
		(end 95.996252 -51.295554)
		(stroke
			(width 0.072898)
			(type default)
		)
		(layer "B.Cu")
	)
	(gr_line
		(start 96.0501 -31.363158)
		(end 96.063308 -31.3436)
		(stroke
			(width 0.072898)
			(type default)
		)
		(layer "B.Cu")
	)
	(gr_line
		(start 96.063308 -31.3436)
		(end 96.082866 -31.330392)
		(stroke
			(width 0.072898)
			(type default)
		)
		(layer "B.Cu")
	)
	(gr_line
		(start 96.06534 -82.407506)
		(end 96.06534 -82.619342)
		(stroke
			(width 0.072898)
			(type default)
		)
		(layer "B.Cu")
	)
	(gr_line
		(start 96.376998 -81.65211)
		(end 96.458532 -81.570576)
		(stroke
			(width 0.072898)
			(type default)
		)
		(layer "B.Cu")
	)
	(gr_line
		(start 96.378776 -82.09407)
		(end 96.590866 -82.09407)
		(stroke
			(width 0.072898)
			(type default)
		)
		(layer "B.Cu")
	)
	(gr_line
		(start 96.53397 -33.059116)
		(end 96.547686 -33.038796)
		(stroke
			(width 0.072898)
			(type default)
		)
		(layer "B.Cu")
	)
	(gr_line
		(start 96.547686 -33.038796)
		(end 96.568006 -33.025334)
		(stroke
			(width 0.072898)
			(type default)
		)
		(layer "B.Cu")
	)
	(gr_line
		(start 96.590866 -82.09407)
		(end 96.900492 -81.78419)
		(stroke
			(width 0.072898)
			(type default)
		)
		(layer "B.Cu")
	)
	(gr_line
		(start 96.632522 -162.07867)
		(end 96.882458 -162.328606)
		(stroke
			(width 0.072898)
			(type default)
		)
		(layer "B.Cu")
	)
	(gr_line
		(start 96.647 -44.280328)
		(end 96.651572 -44.256198)
		(stroke
			(width 0.072898)
			(type default)
		)
		(layer "B.Cu")
	)
	(gr_line
		(start 96.647 -44.280328)
		(end 96.651826 -44.30395)
		(stroke
			(width 0.072898)
			(type default)
		)
		(layer "B.Cu")
	)
	(gr_line
		(start 96.651572 -44.255944)
		(end 96.651572 -44.256452)
		(stroke
			(width 0.072898)
			(type default)
		)
		(layer "B.Cu")
	)
	(gr_line
		(start 96.75368 -37.522658)
		(end 96.758506 -37.498528)
		(stroke
			(width 0.072898)
			(type default)
		)
		(layer "B.Cu")
	)
	(gr_line
		(start 96.758506 -37.498528)
		(end 96.772476 -37.4777)
		(stroke
			(width 0.072898)
			(type default)
		)
		(layer "B.Cu")
	)
	(gr_line
		(start 96.900492 -81.572354)
		(end 96.900492 -81.78419)
		(stroke
			(width 0.072898)
			(type default)
		)
		(layer "B.Cu")
	)
	(gr_line
		(start 97.170748 -51.26482)
		(end 97.175574 -51.28895)
		(stroke
			(width 0.072898)
			(type default)
		)
		(layer "B.Cu")
	)
	(gr_line
		(start 97.171002 -51.312318)
		(end 97.175574 -51.28895)
		(stroke
			(width 0.072898)
			(type default)
		)
		(layer "B.Cu")
	)
	(gr_line
		(start 97.21215 -80.816958)
		(end 97.293938 -80.73517)
		(stroke
			(width 0.072898)
			(type default)
		)
		(layer "B.Cu")
	)
	(gr_line
		(start 97.213928 -81.258918)
		(end 97.426018 -81.258918)
		(stroke
			(width 0.072898)
			(type default)
		)
		(layer "B.Cu")
	)
	(gr_line
		(start 97.326196 -162.328606)
		(end 97.576132 -162.07867)
		(stroke
			(width 0.072898)
			(type default)
		)
		(layer "B.Cu")
	)
	(gr_line
		(start 97.426018 -81.258918)
		(end 97.735898 -80.949038)
		(stroke
			(width 0.072898)
			(type default)
		)
		(layer "B.Cu")
	)
	(gr_line
		(start 97.610676 -33.881568)
		(end 97.623376 -33.862518)
		(stroke
			(width 0.072898)
			(type default)
		)
		(layer "B.Cu")
	)
	(gr_line
		(start 97.623376 -33.862518)
		(end 97.642172 -33.849818)
		(stroke
			(width 0.072898)
			(type default)
		)
		(layer "B.Cu")
	)
	(gr_line
		(start 97.735898 -80.736948)
		(end 97.735898 -80.949038)
		(stroke
			(width 0.072898)
			(type default)
		)
		(layer "B.Cu")
	)
	(gr_line
		(start 97.85858 -38.05174)
		(end 97.863152 -38.028372)
		(stroke
			(width 0.072898)
			(type default)
		)
		(layer "B.Cu")
	)
	(gr_line
		(start 97.863152 -38.028372)
		(end 97.876614 -38.008306)
		(stroke
			(width 0.072898)
			(type default)
		)
		(layer "B.Cu")
	)
	(gr_line
		(start 98.347276 -44.92625)
		(end 98.351848 -44.949618)
		(stroke
			(width 0.072898)
			(type default)
		)
		(layer "B.Cu")
	)
	(gr_line
		(start 98.347276 -44.92625)
		(end 98.352102 -44.902628)
		(stroke
			(width 0.072898)
			(type default)
		)
		(layer "B.Cu")
	)
	(gr_line
		(start 98.351848 -44.902628)
		(end 98.352102 -44.901612)
		(stroke
			(width 0.072898)
			(type default)
		)
		(layer "B.Cu")
	)
	(gr_line
		(start 98.557842 -52.22875)
		(end 98.562668 -52.25288)
		(stroke
			(width 0.072898)
			(type default)
		)
		(layer "B.Cu")
	)
	(gr_line
		(start 98.558096 -52.276248)
		(end 98.562668 -52.25288)
		(stroke
			(width 0.072898)
			(type default)
		)
		(layer "B.Cu")
	)
	(gr_line
		(start 98.706686 -34.610294)
		(end 98.71964 -34.591244)
		(stroke
			(width 0.072898)
			(type default)
		)
		(layer "B.Cu")
	)
	(gr_line
		(start 98.71964 -34.591244)
		(end 98.738436 -34.578798)
		(stroke
			(width 0.072898)
			(type default)
		)
		(layer "B.Cu")
	)
	(gr_line
		(start 99.644454 -35.388296)
		(end 99.657662 -35.368738)
		(stroke
			(width 0.072898)
			(type default)
		)
		(layer "B.Cu")
	)
	(gr_line
		(start 99.657662 -35.368738)
		(end 99.678236 -35.355022)
		(stroke
			(width 0.072898)
			(type default)
		)
		(layer "B.Cu")
	)
	(gr_line
		(start 99.894644 -37.173408)
		(end 99.899216 -37.150548)
		(stroke
			(width 0.072898)
			(type default)
		)
		(layer "B.Cu")
	)
	(gr_line
		(start 99.899216 -37.150548)
		(end 99.912424 -37.130736)
		(stroke
			(width 0.072898)
			(type default)
		)
		(layer "B.Cu")
	)
	(gr_line
		(start 99.97948 -51.501294)
		(end 99.979734 -51.502056)
		(stroke
			(width 0.072898)
			(type default)
		)
		(layer "B.Cu")
	)
	(gr_line
		(start 99.979734 -51.548792)
		(end 99.984306 -51.525424)
		(stroke
			(width 0.072898)
			(type default)
		)
		(layer "B.Cu")
	)
	(gr_line
		(start 99.979734 -51.50231)
		(end 99.984306 -51.525424)
		(stroke
			(width 0.072898)
			(type default)
		)
		(layer "B.Cu")
	)
	(gr_line
		(start 100.215192 -36.679124)
		(end 100.228908 -36.658804)
		(stroke
			(width 0.072898)
			(type default)
		)
		(layer "B.Cu")
	)
	(gr_line
		(start 100.228908 -36.658804)
		(end 100.24872 -36.645596)
		(stroke
			(width 0.072898)
			(type default)
		)
		(layer "B.Cu")
	)
	(gr_line
		(start 101.40442 -40.876474)
		(end 101.65207 -41.124124)
		(stroke
			(width 0.072898)
			(type default)
		)
		(layer "B.Cu")
	)
	(gr_line
		(start 101.40442 -40.432736)
		(end 101.65207 -40.185086)
		(stroke
			(width 0.072898)
			(type default)
		)
		(layer "B.Cu")
	)
	(gr_line
		(start 101.432868 -22.16404)
		(end 101.477572 -22.134068)
		(stroke
			(width 0.072898)
			(type default)
		)
		(layer "B.Cu")
	)
	(gr_line
		(start 101.567742 -23.631906)
		(end 101.612446 -23.601934)
		(stroke
			(width 0.072898)
			(type default)
		)
		(layer "B.Cu")
	)
	(gr_line
		(start 102.370382 -22.447758)
		(end 102.520242 -22.597618)
		(stroke
			(width 0.072898)
			(type default)
		)
		(layer "B.Cu")
	)
	(gr_line
		(start 102.520242 -22.597618)
		(end 102.958392 -22.597618)
		(stroke
			(width 0.072898)
			(type default)
		)
		(layer "B.Cu")
	)
	(gr_line
		(start 102.681532 -22.134068)
		(end 102.797102 -22.134068)
		(stroke
			(width 0.072898)
			(type default)
		)
		(layer "B.Cu")
	)
	(gr_line
		(start 102.88143 -24.84882)
		(end 102.926896 -24.81834)
		(stroke
			(width 0.072898)
			(type default)
		)
		(layer "B.Cu")
	)
	(gr_line
		(start 102.958392 -22.597618)
		(end 103.108252 -22.447758)
		(stroke
			(width 0.072898)
			(type default)
		)
		(layer "B.Cu")
	)
	(gr_line
		(start 103.412798 -26.386282)
		(end 103.458518 -26.355294)
		(stroke
			(width 0.072898)
			(type default)
		)
		(layer "B.Cu")
	)
	(gr_line
		(start 103.551482 -22.447758)
		(end 103.701342 -22.597618)
		(stroke
			(width 0.072898)
			(type default)
		)
		(layer "B.Cu")
	)
	(gr_line
		(start 103.701342 -22.597618)
		(end 104.139492 -22.597618)
		(stroke
			(width 0.072898)
			(type default)
		)
		(layer "B.Cu")
	)
	(gr_line
		(start 103.862632 -22.134068)
		(end 103.978202 -22.134068)
		(stroke
			(width 0.072898)
			(type default)
		)
		(layer "B.Cu")
	)
	(gr_line
		(start 104.139492 -22.597618)
		(end 104.289352 -22.447758)
		(stroke
			(width 0.072898)
			(type default)
		)
		(layer "B.Cu")
	)
	(gr_line
		(start 104.16032 -34.038286)
		(end 104.178354 -34.026094)
		(stroke
			(width 0.072898)
			(type default)
		)
		(layer "B.Cu")
	)
	(gr_line
		(start 104.178354 -34.026094)
		(end 104.19969 -34.02203)
		(stroke
			(width 0.072898)
			(type default)
		)
		(layer "B.Cu")
	)
	(gr_line
		(start 104.732582 -22.447758)
		(end 104.882442 -22.597618)
		(stroke
			(width 0.072898)
			(type default)
		)
		(layer "B.Cu")
	)
	(gr_line
		(start 104.801924 -27.528774)
		(end 104.847644 -27.498294)
		(stroke
			(width 0.072898)
			(type default)
		)
		(layer "B.Cu")
	)
	(gr_line
		(start 104.882442 -22.597618)
		(end 105.320592 -22.597618)
		(stroke
			(width 0.072898)
			(type default)
		)
		(layer "B.Cu")
	)
	(gr_line
		(start 105.043732 -22.134068)
		(end 105.159302 -22.134068)
		(stroke
			(width 0.072898)
			(type default)
		)
		(layer "B.Cu")
	)
	(gr_line
		(start 105.320592 -22.597618)
		(end 105.470452 -22.447758)
		(stroke
			(width 0.072898)
			(type default)
		)
		(layer "B.Cu")
	)
	(gr_line
		(start 105.410254 -28.671266)
		(end 105.454958 -28.641294)
		(stroke
			(width 0.072898)
			(type default)
		)
		(layer "B.Cu")
	)
	(gr_line
		(start 105.913682 -22.447758)
		(end 106.063542 -22.597618)
		(stroke
			(width 0.072898)
			(type default)
		)
		(layer "B.Cu")
	)
	(gr_line
		(start 105.924604 -29.814266)
		(end 105.969562 -29.784294)
		(stroke
			(width 0.072898)
			(type default)
		)
		(layer "B.Cu")
	)
	(gr_line
		(start 106.063542 -22.597618)
		(end 106.501692 -22.597618)
		(stroke
			(width 0.072898)
			(type default)
		)
		(layer "B.Cu")
	)
	(gr_line
		(start 106.085894 -31.096712)
		(end 106.105452 -31.083758)
		(stroke
			(width 0.072898)
			(type default)
		)
		(layer "B.Cu")
	)
	(gr_line
		(start 106.105452 -31.083758)
		(end 106.128312 -31.079186)
		(stroke
			(width 0.072898)
			(type default)
		)
		(layer "B.Cu")
	)
	(gr_line
		(start 106.224832 -22.134068)
		(end 106.340402 -22.134068)
		(stroke
			(width 0.072898)
			(type default)
		)
		(layer "B.Cu")
	)
	(gr_line
		(start 106.501692 -22.597618)
		(end 106.651552 -22.447758)
		(stroke
			(width 0.072898)
			(type default)
		)
		(layer "B.Cu")
	)
	(gr_arc
		(start 106.942382 -33.744408)
		(mid 107.002745 -33.732415)
		(end 107.053888 -33.69818)
		(stroke
			(width 0.072898)
			(type default)
		)
		(layer "B.Cu")
	)
	(gr_arc
		(start 107.015534 -34.098484)
		(mid 106.968001 -34.06669)
		(end 106.911902 -34.055558)
		(stroke
			(width 0.072898)
			(type default)
		)
		(layer "B.Cu")
	)
	(gr_line
		(start 107.015534 -34.098484)
		(end 107.036108 -34.119312)
		(stroke
			(width 0.072898)
			(type default)
		)
		(layer "B.Cu")
	)
	(gr_arc
		(start 107.053888 -33.69818)
		(mid 107.087912 -33.647253)
		(end 107.099862 -33.587182)
		(stroke
			(width 0.072898)
			(type default)
		)
		(layer "B.Cu")
	)
	(gr_arc
		(start 107.099862 -34.272728)
		(mid 107.083248 -34.189674)
		(end 107.036108 -34.119312)
		(stroke
			(width 0.072898)
			(type default)
		)
		(layer "B.Cu")
	)
	(gr_line
		(start 107.099862 -34.272728)
		(end 107.099862 -34.600134)
		(stroke
			(width 0.072898)
			(type default)
		)
		(layer "B.Cu")
	)
	(gr_line
		(start 107.099862 -33.200086)
		(end 107.099862 -33.587182)
		(stroke
			(width 0.072898)
			(type default)
		)
		(layer "B.Cu")
	)
	(gr_arc
		(start 108.674154 -32.544258)
		(mid 108.760489 -32.527125)
		(end 108.833666 -32.478218)
		(stroke
			(width 0.072898)
			(type default)
		)
		(layer "B.Cu")
	)
	(gr_arc
		(start 108.833666 -32.478218)
		(mid 108.882733 -32.404803)
		(end 108.89996 -32.318198)
		(stroke
			(width 0.072898)
			(type default)
		)
		(layer "B.Cu")
	)
	(gr_arc
		(start 108.849922 -32.9057)
		(mid 108.794218 -32.86848)
		(end 108.72851 -32.855408)
		(stroke
			(width 0.072898)
			(type default)
		)
		(layer "B.Cu")
	)
	(gr_arc
		(start 108.89996 -33.026604)
		(mid 108.886963 -32.961173)
		(end 108.849922 -32.9057)
		(stroke
			(width 0.072898)
			(type default)
		)
		(layer "B.Cu")
	)
	(gr_line
		(start 108.89996 -33.026604)
		(end 108.89996 -33.399984)
		(stroke
			(width 0.072898)
			(type default)
		)
		(layer "B.Cu")
	)
	(gr_line
		(start 108.89996 -32.00019)
		(end 108.89996 -32.318198)
		(stroke
			(width 0.072898)
			(type default)
		)
		(layer "B.Cu")
	)
	(gr_arc
		(start 110.474252 -33.744408)
		(mid 110.56059 -33.727279)
		(end 110.633764 -33.678368)
		(stroke
			(width 0.072898)
			(type default)
		)
		(layer "B.Cu")
	)
	(gr_arc
		(start 110.633764 -33.678368)
		(mid 110.682815 -33.60495)
		(end 110.700058 -33.518348)
		(stroke
			(width 0.072898)
			(type default)
		)
		(layer "B.Cu")
	)
	(gr_arc
		(start 110.65002 -34.10585)
		(mid 110.594316 -34.06863)
		(end 110.528608 -34.055558)
		(stroke
			(width 0.072898)
			(type default)
		)
		(layer "B.Cu")
	)
	(gr_arc
		(start 110.700058 -34.226754)
		(mid 110.687061 -34.161323)
		(end 110.65002 -34.10585)
		(stroke
			(width 0.072898)
			(type default)
		)
		(layer "B.Cu")
	)
	(gr_line
		(start 110.700058 -34.226754)
		(end 110.700058 -34.600134)
		(stroke
			(width 0.072898)
			(type default)
		)
		(layer "B.Cu")
	)
	(gr_line
		(start 110.700058 -33.200086)
		(end 110.700058 -33.518348)
		(stroke
			(width 0.072898)
			(type default)
		)
		(layer "B.Cu")
	)
	(gr_arc
		(start 112.274096 -32.544258)
		(mid 112.360422 -32.527111)
		(end 112.433608 -32.478218)
		(stroke
			(width 0.072898)
			(type default)
		)
		(layer "B.Cu")
	)
	(gr_arc
		(start 112.433608 -32.478218)
		(mid 112.482687 -32.404806)
		(end 112.499902 -32.318198)
		(stroke
			(width 0.072898)
			(type default)
		)
		(layer "B.Cu")
	)
	(gr_arc
		(start 112.449864 -32.9057)
		(mid 112.39416 -32.86848)
		(end 112.328452 -32.855408)
		(stroke
			(width 0.072898)
			(type default)
		)
		(layer "B.Cu")
	)
	(gr_arc
		(start 112.499902 -33.026604)
		(mid 112.486905 -32.961173)
		(end 112.449864 -32.9057)
		(stroke
			(width 0.072898)
			(type default)
		)
		(layer "B.Cu")
	)
	(gr_line
		(start 112.499902 -33.026604)
		(end 112.499902 -33.399984)
		(stroke
			(width 0.072898)
			(type default)
		)
		(layer "B.Cu")
	)
	(gr_line
		(start 112.499902 -32.00019)
		(end 112.499902 -32.318198)
		(stroke
			(width 0.072898)
			(type default)
		)
		(layer "B.Cu")
	)
	(gr_arc
		(start 114.074194 -33.744408)
		(mid 114.160523 -33.727265)
		(end 114.233706 -33.678368)
		(stroke
			(width 0.072898)
			(type default)
		)
		(layer "B.Cu")
	)
	(gr_arc
		(start 114.233706 -33.678368)
		(mid 114.282769 -33.604954)
		(end 114.3 -33.518348)
		(stroke
			(width 0.072898)
			(type default)
		)
		(layer "B.Cu")
	)
	(gr_arc
		(start 114.249962 -34.10585)
		(mid 114.194258 -34.06863)
		(end 114.12855 -34.055558)
		(stroke
			(width 0.072898)
			(type default)
		)
		(layer "B.Cu")
	)
	(gr_arc
		(start 114.3 -34.226754)
		(mid 114.287003 -34.161323)
		(end 114.249962 -34.10585)
		(stroke
			(width 0.072898)
			(type default)
		)
		(layer "B.Cu")
	)
	(gr_line
		(start 114.3 -34.226754)
		(end 114.3 -34.600134)
		(stroke
			(width 0.072898)
			(type default)
		)
		(layer "B.Cu")
	)
	(gr_line
		(start 114.3 -33.200086)
		(end 114.3 -33.518348)
		(stroke
			(width 0.072898)
			(type default)
		)
		(layer "B.Cu")
	)
	(gr_arc
		(start 115.874038 -32.544258)
		(mid 115.960376 -32.52713)
		(end 116.03355 -32.478218)
		(stroke
			(width 0.072898)
			(type default)
		)
		(layer "B.Cu")
	)
	(gr_arc
		(start 116.03355 -32.478218)
		(mid 116.08262 -32.404804)
		(end 116.099844 -32.318198)
		(stroke
			(width 0.072898)
			(type default)
		)
		(layer "B.Cu")
	)
	(gr_arc
		(start 116.049806 -32.9057)
		(mid 115.994102 -32.86848)
		(end 115.928394 -32.855408)
		(stroke
			(width 0.072898)
			(type default)
		)
		(layer "B.Cu")
	)
	(gr_line
		(start 116.081048 -23.91791)
		(end 116.390928 -24.22779)
		(stroke
			(width 0.072898)
			(type default)
		)
		(layer "B.Cu")
	)
	(gr_line
		(start 116.081048 -23.70582)
		(end 116.081048 -23.91791)
		(stroke
			(width 0.072898)
			(type default)
		)
		(layer "B.Cu")
	)
	(gr_arc
		(start 116.099844 -33.026604)
		(mid 116.086847 -32.961173)
		(end 116.049806 -32.9057)
		(stroke
			(width 0.072898)
			(type default)
		)
		(layer "B.Cu")
	)
	(gr_line
		(start 116.099844 -33.026604)
		(end 116.099844 -33.399984)
		(stroke
			(width 0.072898)
			(type default)
		)
		(layer "B.Cu")
	)
	(gr_line
		(start 116.099844 -32.00019)
		(end 116.099844 -32.318198)
		(stroke
			(width 0.072898)
			(type default)
		)
		(layer "B.Cu")
	)
	(gr_line
		(start 116.390928 -24.22779)
		(end 116.603018 -24.22779)
		(stroke
			(width 0.072898)
			(type default)
		)
		(layer "B.Cu")
	)
	(gr_line
		(start 116.523008 -23.704042)
		(end 116.604796 -23.78583)
		(stroke
			(width 0.072898)
			(type default)
		)
		(layer "B.Cu")
	)
	(gr_line
		(start 116.9162 -24.753062)
		(end 117.22608 -25.062942)
		(stroke
			(width 0.072898)
			(type default)
		)
		(layer "B.Cu")
	)
	(gr_line
		(start 116.9162 -24.540972)
		(end 116.9162 -24.753062)
		(stroke
			(width 0.072898)
			(type default)
		)
		(layer "B.Cu")
	)
	(gr_line
		(start 117.22608 -25.062942)
		(end 117.43817 -25.062942)
		(stroke
			(width 0.072898)
			(type default)
		)
		(layer "B.Cu")
	)
	(gr_line
		(start 117.35816 -24.539194)
		(end 117.439948 -24.620982)
		(stroke
			(width 0.072898)
			(type default)
		)
		(layer "B.Cu")
	)
	(gr_arc
		(start 117.674136 -33.744408)
		(mid 117.760478 -33.727284)
		(end 117.833648 -33.678368)
		(stroke
			(width 0.072898)
			(type default)
		)
		(layer "B.Cu")
	)
	(gr_line
		(start 117.751352 -25.588214)
		(end 118.061232 -25.898094)
		(stroke
			(width 0.072898)
			(type default)
		)
		(layer "B.Cu")
	)
	(gr_line
		(start 117.751352 -25.376124)
		(end 117.751352 -25.588214)
		(stroke
			(width 0.072898)
			(type default)
		)
		(layer "B.Cu")
	)
	(gr_arc
		(start 117.833648 -33.678368)
		(mid 117.882702 -33.604951)
		(end 117.899942 -33.518348)
		(stroke
			(width 0.072898)
			(type default)
		)
		(layer "B.Cu")
	)
	(gr_arc
		(start 117.849904 -34.10585)
		(mid 117.7942 -34.06863)
		(end 117.728492 -34.055558)
		(stroke
			(width 0.072898)
			(type default)
		)
		(layer "B.Cu")
	)
	(gr_arc
		(start 117.899942 -34.226754)
		(mid 117.886945 -34.161323)
		(end 117.849904 -34.10585)
		(stroke
			(width 0.072898)
			(type default)
		)
		(layer "B.Cu")
	)
	(gr_line
		(start 117.899942 -34.226754)
		(end 117.899942 -34.600134)
		(stroke
			(width 0.072898)
			(type default)
		)
		(layer "B.Cu")
	)
	(gr_line
		(start 117.899942 -33.200086)
		(end 117.899942 -33.518348)
		(stroke
			(width 0.072898)
			(type default)
		)
		(layer "B.Cu")
	)
	(gr_line
		(start 118.061232 -25.898094)
		(end 118.273322 -25.898094)
		(stroke
			(width 0.072898)
			(type default)
		)
		(layer "B.Cu")
	)
	(gr_line
		(start 118.193312 -25.374346)
		(end 118.2751 -25.456134)
		(stroke
			(width 0.072898)
			(type default)
		)
		(layer "B.Cu")
	)
	(gr_line
		(start 118.586504 -26.423366)
		(end 118.896384 -26.733246)
		(stroke
			(width 0.072898)
			(type default)
		)
		(layer "B.Cu")
	)
	(gr_line
		(start 118.586504 -26.211276)
		(end 118.586504 -26.423366)
		(stroke
			(width 0.072898)
			(type default)
		)
		(layer "B.Cu")
	)
	(gr_line
		(start 118.896384 -26.733246)
		(end 119.108474 -26.733246)
		(stroke
			(width 0.072898)
			(type default)
		)
		(layer "B.Cu")
	)
	(gr_line
		(start 119.028464 -26.209498)
		(end 119.110252 -26.291286)
		(stroke
			(width 0.072898)
			(type default)
		)
		(layer "B.Cu")
	)
	(gr_arc
		(start 119.474234 -32.544258)
		(mid 119.560573 -32.527132)
		(end 119.633746 -32.478218)
		(stroke
			(width 0.072898)
			(type default)
		)
		(layer "B.Cu")
	)
	(gr_arc
		(start 119.633746 -32.478218)
		(mid 119.682817 -32.404804)
		(end 119.70004 -32.318198)
		(stroke
			(width 0.072898)
			(type default)
		)
		(layer "B.Cu")
	)
	(gr_arc
		(start 119.650002 -32.9057)
		(mid 119.594298 -32.86848)
		(end 119.52859 -32.855408)
		(stroke
			(width 0.072898)
			(type default)
		)
		(layer "B.Cu")
	)
	(gr_line
		(start 119.70004 -43.881802)
		(end 119.70004 -44.200064)
		(stroke
			(width 0.072898)
			(type default)
		)
		(layer "B.Cu")
	)
	(gr_arc
		(start 119.70004 -43.173396)
		(mid 119.713059 -43.238816)
		(end 119.750078 -43.2943)
		(stroke
			(width 0.072898)
			(type default)
		)
		(layer "B.Cu")
	)
	(gr_line
		(start 119.70004 -42.800016)
		(end 119.70004 -43.173396)
		(stroke
			(width 0.072898)
			(type default)
		)
		(layer "B.Cu")
	)
	(gr_arc
		(start 119.70004 -33.026604)
		(mid 119.687043 -32.961173)
		(end 119.650002 -32.9057)
		(stroke
			(width 0.072898)
			(type default)
		)
		(layer "B.Cu")
	)
	(gr_line
		(start 119.70004 -33.026604)
		(end 119.70004 -33.399984)
		(stroke
			(width 0.072898)
			(type default)
		)
		(layer "B.Cu")
	)
	(gr_line
		(start 119.70004 -32.00019)
		(end 119.70004 -32.318198)
		(stroke
			(width 0.072898)
			(type default)
		)
		(layer "B.Cu")
	)
	(gr_arc
		(start 119.750078 -43.2943)
		(mid 119.805781 -43.331526)
		(end 119.87149 -43.344592)
		(stroke
			(width 0.072898)
			(type default)
		)
		(layer "B.Cu")
	)
	(gr_arc
		(start 119.766334 -43.721782)
		(mid 119.717267 -43.795197)
		(end 119.70004 -43.881802)
		(stroke
			(width 0.072898)
			(type default)
		)
		(layer "B.Cu")
	)
	(gr_arc
		(start 119.925846 -43.655742)
		(mid 119.839511 -43.672875)
		(end 119.766334 -43.721782)
		(stroke
			(width 0.072898)
			(type default)
		)
		(layer "B.Cu")
	)
	(gr_arc
		(start 128.474216 -37.34435)
		(mid 128.560531 -37.327181)
		(end 128.633728 -37.27831)
		(stroke
			(width 0.072898)
			(type default)
		)
		(layer "B.Cu")
	)
	(gr_arc
		(start 128.633728 -37.27831)
		(mid 128.682784 -37.204892)
		(end 128.700022 -37.11829)
		(stroke
			(width 0.072898)
			(type default)
		)
		(layer "B.Cu")
	)
	(gr_arc
		(start 128.649984 -37.705792)
		(mid 128.594278 -37.66858)
		(end 128.528572 -37.6555)
		(stroke
			(width 0.072898)
			(type default)
		)
		(layer "B.Cu")
	)
	(gr_arc
		(start 128.700022 -37.826696)
		(mid 128.687004 -37.761274)
		(end 128.649984 -37.705792)
		(stroke
			(width 0.072898)
			(type default)
		)
		(layer "B.Cu")
	)
	(gr_line
		(start 128.700022 -37.826696)
		(end 128.700022 -38.200076)
		(stroke
			(width 0.072898)
			(type default)
		)
		(layer "B.Cu")
	)
	(gr_line
		(start 128.700022 -36.800028)
		(end 128.700022 -37.11829)
		(stroke
			(width 0.072898)
			(type default)
		)
		(layer "B.Cu")
	)
	(gr_arc
		(start 130.27406 -36.144454)
		(mid 130.360375 -36.127285)
		(end 130.433572 -36.078414)
		(stroke
			(width 0.072898)
			(type default)
		)
		(layer "B.Cu")
	)
	(gr_arc
		(start 130.433572 -36.078414)
		(mid 130.482628 -36.004996)
		(end 130.499866 -35.918394)
		(stroke
			(width 0.072898)
			(type default)
		)
		(layer "B.Cu")
	)
	(gr_arc
		(start 130.449828 -36.505896)
		(mid 130.394125 -36.468669)
		(end 130.328416 -36.455604)
		(stroke
			(width 0.072898)
			(type default)
		)
		(layer "B.Cu")
	)
	(gr_arc
		(start 130.499866 -36.6268)
		(mid 130.486846 -36.561381)
		(end 130.449828 -36.505896)
		(stroke
			(width 0.072898)
			(type default)
		)
		(layer "B.Cu")
	)
	(gr_line
		(start 130.499866 -36.6268)
		(end 130.499866 -37.00018)
		(stroke
			(width 0.072898)
			(type default)
		)
		(layer "B.Cu")
	)
	(gr_line
		(start 130.499866 -35.600132)
		(end 130.499866 -35.918394)
		(stroke
			(width 0.072898)
			(type default)
		)
		(layer "B.Cu")
	)
	(gr_arc
		(start 132.074158 -37.34435)
		(mid 132.160473 -37.327181)
		(end 132.23367 -37.27831)
		(stroke
			(width 0.072898)
			(type default)
		)
		(layer "B.Cu")
	)
	(gr_arc
		(start 132.23367 -37.27831)
		(mid 132.282726 -37.204892)
		(end 132.299964 -37.11829)
		(stroke
			(width 0.072898)
			(type default)
		)
		(layer "B.Cu")
	)
	(gr_arc
		(start 132.249926 -37.705792)
		(mid 132.194223 -37.668566)
		(end 132.128514 -37.6555)
		(stroke
			(width 0.072898)
			(type default)
		)
		(layer "B.Cu")
	)
	(gr_arc
		(start 132.299964 -37.826696)
		(mid 132.286943 -37.761278)
		(end 132.249926 -37.705792)
		(stroke
			(width 0.072898)
			(type default)
		)
		(layer "B.Cu")
	)
	(gr_line
		(start 132.299964 -37.826696)
		(end 132.299964 -38.200076)
		(stroke
			(width 0.072898)
			(type default)
		)
		(layer "B.Cu")
	)
	(gr_line
		(start 132.299964 -36.800028)
		(end 132.299964 -37.11829)
		(stroke
			(width 0.072898)
			(type default)
		)
		(layer "B.Cu")
	)
	(gr_arc
		(start 133.874256 -36.144454)
		(mid 133.960571 -36.127285)
		(end 134.033768 -36.078414)
		(stroke
			(width 0.072898)
			(type default)
		)
		(layer "B.Cu")
	)
	(gr_arc
		(start 134.033768 -36.078414)
		(mid 134.082824 -36.004996)
		(end 134.100062 -35.918394)
		(stroke
			(width 0.072898)
			(type default)
		)
		(layer "B.Cu")
	)
	(gr_arc
		(start 134.050024 -36.505896)
		(mid 133.994321 -36.46867)
		(end 133.928612 -36.455604)
		(stroke
			(width 0.072898)
			(type default)
		)
		(layer "B.Cu")
	)
	(gr_arc
		(start 134.100062 -36.6268)
		(mid 134.087042 -36.561381)
		(end 134.050024 -36.505896)
		(stroke
			(width 0.072898)
			(type default)
		)
		(layer "B.Cu")
	)
	(gr_line
		(start 134.100062 -36.6268)
		(end 134.100062 -37.00018)
		(stroke
			(width 0.072898)
			(type default)
		)
		(layer "B.Cu")
	)
	(gr_line
		(start 134.100062 -35.600132)
		(end 134.100062 -35.918394)
		(stroke
			(width 0.072898)
			(type default)
		)
		(layer "B.Cu")
	)
	(gr_line
		(start 135.46709 -28.754832)
		(end 135.548624 -28.673298)
		(stroke
			(width 0.072898)
			(type default)
		)
		(layer "B.Cu")
	)
	(gr_line
		(start 135.468868 -29.196792)
		(end 135.680704 -29.196792)
		(stroke
			(width 0.072898)
			(type default)
		)
		(layer "B.Cu")
	)
	(gr_arc
		(start 135.6741 -37.34435)
		(mid 135.760425 -37.327202)
		(end 135.833612 -37.27831)
		(stroke
			(width 0.072898)
			(type default)
		)
		(layer "B.Cu")
	)
	(gr_line
		(start 135.680704 -29.196792)
		(end 135.990584 -28.886912)
		(stroke
			(width 0.072898)
			(type default)
		)
		(layer "B.Cu")
	)
	(gr_arc
		(start 135.833612 -37.27831)
		(mid 135.882688 -37.204898)
		(end 135.899906 -37.11829)
		(stroke
			(width 0.072898)
			(type default)
		)
		(layer "B.Cu")
	)
	(gr_arc
		(start 135.849868 -37.705792)
		(mid 135.794164 -37.668572)
		(end 135.728456 -37.6555)
		(stroke
			(width 0.072898)
			(type default)
		)
		(layer "B.Cu")
	)
	(gr_arc
		(start 135.899906 -37.826696)
		(mid 135.886909 -37.761265)
		(end 135.849868 -37.705792)
		(stroke
			(width 0.072898)
			(type default)
		)
		(layer "B.Cu")
	)
	(gr_line
		(start 135.899906 -37.826696)
		(end 135.899906 -38.200076)
		(stroke
			(width 0.072898)
			(type default)
		)
		(layer "B.Cu")
	)
	(gr_line
		(start 135.899906 -36.800028)
		(end 135.899906 -37.11829)
		(stroke
			(width 0.072898)
			(type default)
		)
		(layer "B.Cu")
	)
	(gr_line
		(start 135.990584 -28.675076)
		(end 135.990584 -28.886912)
		(stroke
			(width 0.072898)
			(type default)
		)
		(layer "B.Cu")
	)
	(gr_arc
		(start 137.474198 -36.144454)
		(mid 137.560523 -36.127306)
		(end 137.63371 -36.078414)
		(stroke
			(width 0.072898)
			(type default)
		)
		(layer "B.Cu")
	)
	(gr_arc
		(start 137.63371 -36.078414)
		(mid 137.682788 -36.005002)
		(end 137.700004 -35.918394)
		(stroke
			(width 0.072898)
			(type default)
		)
		(layer "B.Cu")
	)
	(gr_arc
		(start 137.649966 -36.505896)
		(mid 137.594259 -36.468689)
		(end 137.528554 -36.455604)
		(stroke
			(width 0.072898)
			(type default)
		)
		(layer "B.Cu")
	)
	(gr_arc
		(start 137.700004 -36.6268)
		(mid 137.686987 -36.561379)
		(end 137.649966 -36.505896)
		(stroke
			(width 0.072898)
			(type default)
		)
		(layer "B.Cu")
	)
	(gr_line
		(start 137.700004 -36.6268)
		(end 137.700004 -37.00018)
		(stroke
			(width 0.072898)
			(type default)
		)
		(layer "B.Cu")
	)
	(gr_line
		(start 137.700004 -35.600132)
		(end 137.700004 -35.918394)
		(stroke
			(width 0.072898)
			(type default)
		)
		(layer "B.Cu")
	)
	(gr_arc
		(start 139.274042 -37.34435)
		(mid 139.360379 -37.327221)
		(end 139.433554 -37.27831)
		(stroke
			(width 0.072898)
			(type default)
		)
		(layer "B.Cu")
	)
	(gr_arc
		(start 139.433554 -37.27831)
		(mid 139.482621 -37.204895)
		(end 139.499848 -37.11829)
		(stroke
			(width 0.072898)
			(type default)
		)
		(layer "B.Cu")
	)
	(gr_arc
		(start 139.44981 -37.705792)
		(mid 139.394106 -37.668571)
		(end 139.328398 -37.6555)
		(stroke
			(width 0.072898)
			(type default)
		)
		(layer "B.Cu")
	)
	(gr_arc
		(start 139.499848 -37.826696)
		(mid 139.486826 -37.761279)
		(end 139.44981 -37.705792)
		(stroke
			(width 0.072898)
			(type default)
		)
		(layer "B.Cu")
	)
	(gr_line
		(start 139.499848 -37.826696)
		(end 139.499848 -38.200076)
		(stroke
			(width 0.072898)
			(type default)
		)
		(layer "B.Cu")
	)
	(gr_line
		(start 139.499848 -36.800028)
		(end 139.499848 -37.11829)
		(stroke
			(width 0.072898)
			(type default)
		)
		(layer "B.Cu")
	)
	(gr_arc
		(start 141.07414 -36.144454)
		(mid 141.160478 -36.127325)
		(end 141.233652 -36.078414)
		(stroke
			(width 0.072898)
			(type default)
		)
		(layer "B.Cu")
	)
	(gr_arc
		(start 141.233652 -36.078414)
		(mid 141.282721 -36.005)
		(end 141.299946 -35.918394)
		(stroke
			(width 0.072898)
			(type default)
		)
		(layer "B.Cu")
	)
	(gr_arc
		(start 141.249908 -36.505896)
		(mid 141.194204 -36.468676)
		(end 141.128496 -36.455604)
		(stroke
			(width 0.072898)
			(type default)
		)
		(layer "B.Cu")
	)
	(gr_arc
		(start 141.299946 -36.6268)
		(mid 141.286949 -36.561369)
		(end 141.249908 -36.505896)
		(stroke
			(width 0.072898)
			(type default)
		)
		(layer "B.Cu")
	)
	(gr_line
		(start 141.299946 -36.6268)
		(end 141.299946 -37.00018)
		(stroke
			(width 0.072898)
			(type default)
		)
		(layer "B.Cu")
	)
	(gr_line
		(start 141.299946 -35.600132)
		(end 141.299946 -35.918394)
		(stroke
			(width 0.072898)
			(type default)
		)
		(layer "B.Cu")
	)
	(gr_line
		(start 142.50289 -29.980636)
		(end 142.54861 -30.011624)
		(stroke
			(width 0.072898)
			(type default)
		)
		(layer "B.Cu")
	)
	(gr_line
		(start 142.990062 -28.837636)
		(end 143.035528 -28.868116)
		(stroke
			(width 0.072898)
			(type default)
		)
		(layer "B.Cu")
	)
	(gr_line
		(start 143.481044 -30.640782)
		(end 143.499078 -30.652974)
		(stroke
			(width 0.072898)
			(type default)
		)
		(layer "B.Cu")
	)
	(gr_line
		(start 143.499078 -30.652974)
		(end 143.51127 -30.671262)
		(stroke
			(width 0.072898)
			(type default)
		)
		(layer "B.Cu")
	)
	(gr_line
		(start 143.564356 -27.694636)
		(end 143.609822 -27.725116)
		(stroke
			(width 0.072898)
			(type default)
		)
		(layer "B.Cu")
	)
	(gr_line
		(start 144.40662 -29.782516)
		(end 144.425416 -29.795216)
		(stroke
			(width 0.072898)
			(type default)
		)
		(layer "B.Cu")
	)
	(gr_line
		(start 144.425416 -29.795216)
		(end 144.438116 -29.814266)
		(stroke
			(width 0.072898)
			(type default)
		)
		(layer "B.Cu")
	)
	(gr_line
		(start 144.513554 -26.551636)
		(end 144.558258 -26.581608)
		(stroke
			(width 0.072898)
			(type default)
		)
		(layer "B.Cu")
	)
	(gr_line
		(start 144.96923 -34.081974)
		(end 145.055082 -34.511742)
		(stroke
			(width 0.072898)
			(type default)
		)
		(layer "B.Cu")
	)
	(gr_line
		(start 144.96923 -34.081974)
		(end 145.086832 -33.905698)
		(stroke
			(width 0.072898)
			(type default)
		)
		(layer "B.Cu")
	)
	(gr_line
		(start 144.983708 -25.408636)
		(end 145.028412 -25.438608)
		(stroke
			(width 0.072898)
			(type default)
		)
		(layer "B.Cu")
	)
	(gr_line
		(start 145.055082 -34.511742)
		(end 145.231358 -34.629344)
		(stroke
			(width 0.072898)
			(type default)
		)
		(layer "B.Cu")
	)
	(gr_line
		(start 145.200624 -35.240214)
		(end 145.286222 -35.669982)
		(stroke
			(width 0.072898)
			(type default)
		)
		(layer "B.Cu")
	)
	(gr_line
		(start 145.200624 -35.240214)
		(end 145.318226 -35.064192)
		(stroke
			(width 0.072898)
			(type default)
		)
		(layer "B.Cu")
	)
	(gr_line
		(start 145.283682 -33.332928)
		(end 145.296128 -33.351724)
		(stroke
			(width 0.072898)
			(type default)
		)
		(layer "B.Cu")
	)
	(gr_line
		(start 145.286222 -35.669982)
		(end 145.462752 -35.787838)
		(stroke
			(width 0.072898)
			(type default)
		)
		(layer "B.Cu")
	)
	(gr_line
		(start 145.296128 -33.351724)
		(end 145.300446 -33.373314)
		(stroke
			(width 0.072898)
			(type default)
		)
		(layer "B.Cu")
	)
	(gr_line
		(start 145.384266 -24.235156)
		(end 145.42897 -24.265128)
		(stroke
			(width 0.072898)
			(type default)
		)
		(layer "B.Cu")
	)
	(gr_line
		(start 145.401792 -33.880806)
		(end 145.531586 -34.530792)
		(stroke
			(width 0.072898)
			(type default)
		)
		(layer "B.Cu")
	)
	(gr_line
		(start 145.431764 -36.398454)
		(end 145.517616 -36.828222)
		(stroke
			(width 0.072898)
			(type default)
		)
		(layer "B.Cu")
	)
	(gr_line
		(start 145.431764 -36.398454)
		(end 145.54962 -36.222178)
		(stroke
			(width 0.072898)
			(type default)
		)
		(layer "B.Cu")
	)
	(gr_line
		(start 145.517616 -36.828222)
		(end 145.694146 -36.946078)
		(stroke
			(width 0.072898)
			(type default)
		)
		(layer "B.Cu")
	)
	(gr_line
		(start 145.534634 -59.179968)
		(end 145.537682 -59.16168)
		(stroke
			(width 0.072898)
			(type default)
		)
		(layer "B.Cu")
	)
	(gr_line
		(start 145.534634 -59.179968)
		(end 145.53819 -59.198256)
		(stroke
			(width 0.072898)
			(type default)
		)
		(layer "B.Cu")
	)
	(gr_line
		(start 145.633186 -35.040062)
		(end 145.763234 -35.69081)
		(stroke
			(width 0.072898)
			(type default)
		)
		(layer "B.Cu")
	)
	(gr_line
		(start 145.663158 -37.556694)
		(end 145.74901 -37.986462)
		(stroke
			(width 0.072898)
			(type default)
		)
		(layer "B.Cu")
	)
	(gr_line
		(start 145.663158 -37.556694)
		(end 145.781014 -37.380164)
		(stroke
			(width 0.072898)
			(type default)
		)
		(layer "B.Cu")
	)
	(gr_line
		(start 145.74901 -37.986462)
		(end 145.92554 -38.104318)
		(stroke
			(width 0.072898)
			(type default)
		)
		(layer "B.Cu")
	)
	(gr_line
		(start 145.841974 -23.05304)
		(end 145.887694 -23.084028)
		(stroke
			(width 0.072898)
			(type default)
		)
		(layer "B.Cu")
	)
	(gr_line
		(start 145.847054 -30.033722)
		(end 145.888456 -29.825696)
		(stroke
			(width 0.072898)
			(type default)
		)
		(layer "B.Cu")
	)
	(gr_line
		(start 145.847054 -30.033722)
		(end 146.090132 -30.398212)
		(stroke
			(width 0.072898)
			(type default)
		)
		(layer "B.Cu")
	)
	(gr_line
		(start 145.850864 -29.220414)
		(end 145.870676 -29.233368)
		(stroke
			(width 0.072898)
			(type default)
		)
		(layer "B.Cu")
	)
	(gr_line
		(start 145.864072 -36.194746)
		(end 145.995136 -36.85032)
		(stroke
			(width 0.072898)
			(type default)
		)
		(layer "B.Cu")
	)
	(gr_line
		(start 145.870676 -29.233368)
		(end 145.884138 -29.253434)
		(stroke
			(width 0.072898)
			(type default)
		)
		(layer "B.Cu")
	)
	(gr_line
		(start 146.090132 -30.398212)
		(end 146.298158 -30.439868)
		(stroke
			(width 0.072898)
			(type default)
		)
		(layer "B.Cu")
	)
	(gr_line
		(start 146.09572 -37.354256)
		(end 146.226276 -38.007798)
		(stroke
			(width 0.072898)
			(type default)
		)
		(layer "B.Cu")
	)
	(gr_line
		(start 146.169888 -29.682186)
		(end 146.53895 -30.235906)
		(stroke
			(width 0.072898)
			(type default)
		)
		(layer "B.Cu")
	)
	(gr_line
		(start 146.23542 -33.733486)
		(end 146.321272 -34.163)
		(stroke
			(width 0.072898)
			(type default)
		)
		(layer "B.Cu")
	)
	(gr_line
		(start 146.23542 -33.733486)
		(end 146.353022 -33.556956)
		(stroke
			(width 0.072898)
			(type default)
		)
		(layer "B.Cu")
	)
	(gr_line
		(start 146.282918 -21.844)
		(end 146.327622 -21.873972)
		(stroke
			(width 0.072898)
			(type default)
		)
		(layer "B.Cu")
	)
	(gr_line
		(start 146.321272 -34.163)
		(end 146.497548 -34.280602)
		(stroke
			(width 0.072898)
			(type default)
		)
		(layer "B.Cu")
	)
	(gr_line
		(start 146.364198 -27.78506)
		(end 146.384264 -27.798522)
		(stroke
			(width 0.072898)
			(type default)
		)
		(layer "B.Cu")
	)
	(gr_line
		(start 146.384264 -27.798522)
		(end 146.397726 -27.818588)
		(stroke
			(width 0.072898)
			(type default)
		)
		(layer "B.Cu")
	)
	(gr_line
		(start 146.466814 -34.891472)
		(end 146.55292 -35.32124)
		(stroke
			(width 0.072898)
			(type default)
		)
		(layer "B.Cu")
	)
	(gr_line
		(start 146.466814 -34.891472)
		(end 146.584416 -34.714942)
		(stroke
			(width 0.072898)
			(type default)
		)
		(layer "B.Cu")
	)
	(gr_line
		(start 146.502374 -31.016448)
		(end 146.543776 -30.808422)
		(stroke
			(width 0.072898)
			(type default)
		)
		(layer "B.Cu")
	)
	(gr_line
		(start 146.502374 -31.016448)
		(end 146.745452 -31.380938)
		(stroke
			(width 0.072898)
			(type default)
		)
		(layer "B.Cu")
	)
	(gr_line
		(start 146.549618 -32.984186)
		(end 146.562064 -33.002982)
		(stroke
			(width 0.072898)
			(type default)
		)
		(layer "B.Cu")
	)
	(gr_line
		(start 146.55292 -35.32124)
		(end 146.729196 -35.438588)
		(stroke
			(width 0.072898)
			(type default)
		)
		(layer "B.Cu")
	)
	(gr_line
		(start 146.562064 -33.002982)
		(end 146.566382 -33.024572)
		(stroke
			(width 0.072898)
			(type default)
		)
		(layer "B.Cu")
	)
	(gr_line
		(start 146.591782 -42.206672)
		(end 146.677634 -42.63644)
		(stroke
			(width 0.072898)
			(type default)
		)
		(layer "B.Cu")
	)
	(gr_line
		(start 146.591782 -42.206672)
		(end 146.709638 -42.029888)
		(stroke
			(width 0.072898)
			(type default)
		)
		(layer "B.Cu")
	)
	(gr_line
		(start 146.667728 -33.530794)
		(end 146.79803 -34.182812)
		(stroke
			(width 0.072898)
			(type default)
		)
		(layer "B.Cu")
	)
	(gr_line
		(start 146.677634 -42.63644)
		(end 146.854418 -42.754296)
		(stroke
			(width 0.072898)
			(type default)
		)
		(layer "B.Cu")
	)
	(gr_line
		(start 146.698462 -36.049712)
		(end 146.784314 -36.479226)
		(stroke
			(width 0.072898)
			(type default)
		)
		(layer "B.Cu")
	)
	(gr_line
		(start 146.698462 -36.049712)
		(end 146.816064 -35.873436)
		(stroke
			(width 0.072898)
			(type default)
		)
		(layer "B.Cu")
	)
	(gr_line
		(start 146.710146 -59.13374)
		(end 146.714718 -59.110372)
		(stroke
			(width 0.072898)
			(type default)
		)
		(layer "B.Cu")
	)
	(gr_line
		(start 146.710146 -59.13374)
		(end 146.714972 -59.15787)
		(stroke
			(width 0.072898)
			(type default)
		)
		(layer "B.Cu")
	)
	(gr_line
		(start 146.732244 -35.44062)
		(end 146.763232 -35.596068)
		(stroke
			(width 0.072898)
			(type default)
		)
		(layer "B.Cu")
	)
	(gr_line
		(start 146.745452 -31.380938)
		(end 146.953478 -31.422594)
		(stroke
			(width 0.072898)
			(type default)
		)
		(layer "B.Cu")
	)
	(gr_line
		(start 146.784314 -36.479226)
		(end 146.960844 -36.597082)
		(stroke
			(width 0.072898)
			(type default)
		)
		(layer "B.Cu")
	)
	(gr_line
		(start 146.823176 -43.364912)
		(end 146.909028 -43.79468)
		(stroke
			(width 0.072898)
			(type default)
		)
		(layer "B.Cu")
	)
	(gr_line
		(start 146.823176 -43.364912)
		(end 146.941032 -43.188128)
		(stroke
			(width 0.072898)
			(type default)
		)
		(layer "B.Cu")
	)
	(gr_line
		(start 146.824954 -30.664404)
		(end 147.193762 -31.217616)
		(stroke
			(width 0.072898)
			(type default)
		)
		(layer "B.Cu")
	)
	(gr_line
		(start 146.899376 -34.68878)
		(end 147.029678 -35.340798)
		(stroke
			(width 0.072898)
			(type default)
		)
		(layer "B.Cu")
	)
	(gr_line
		(start 146.909028 -43.79468)
		(end 147.085812 -43.912282)
		(stroke
			(width 0.072898)
			(type default)
		)
		(layer "B.Cu")
	)
	(gr_line
		(start 146.93011 -37.207952)
		(end 147.015962 -37.637466)
		(stroke
			(width 0.072898)
			(type default)
		)
		(layer "B.Cu")
	)
	(gr_line
		(start 146.93011 -37.207952)
		(end 147.047712 -37.031676)
		(stroke
			(width 0.072898)
			(type default)
		)
		(layer "B.Cu")
	)
	(gr_line
		(start 147.015962 -37.637466)
		(end 147.192492 -37.755322)
		(stroke
			(width 0.072898)
			(type default)
		)
		(layer "B.Cu")
	)
	(gr_line
		(start 147.02409 -42.001694)
		(end 147.155662 -42.66057)
		(stroke
			(width 0.072898)
			(type default)
		)
		(layer "B.Cu")
	)
	(gr_line
		(start 147.036536 -35.375342)
		(end 147.068286 -35.535108)
		(stroke
			(width 0.072898)
			(type default)
		)
		(layer "B.Cu")
	)
	(gr_line
		(start 147.05457 -44.523152)
		(end 147.140422 -44.95292)
		(stroke
			(width 0.072898)
			(type default)
		)
		(layer "B.Cu")
	)
	(gr_line
		(start 147.05457 -44.523152)
		(end 147.172426 -44.346368)
		(stroke
			(width 0.072898)
			(type default)
		)
		(layer "B.Cu")
	)
	(gr_line
		(start 147.131024 -35.847274)
		(end 147.26158 -36.500562)
		(stroke
			(width 0.072898)
			(type default)
		)
		(layer "B.Cu")
	)
	(gr_line
		(start 147.140422 -44.95292)
		(end 147.317206 -45.070776)
		(stroke
			(width 0.072898)
			(type default)
		)
		(layer "B.Cu")
	)
	(gr_line
		(start 147.244054 -26.915618)
		(end 147.26412 -26.92908)
		(stroke
			(width 0.072898)
			(type default)
		)
		(layer "B.Cu")
	)
	(gr_line
		(start 147.255484 -43.15968)
		(end 147.386802 -43.817286)
		(stroke
			(width 0.072898)
			(type default)
		)
		(layer "B.Cu")
	)
	(gr_line
		(start 147.26412 -26.92908)
		(end 147.277582 -26.949146)
		(stroke
			(width 0.072898)
			(type default)
		)
		(layer "B.Cu")
	)
	(gr_line
		(start 147.28571 -45.681392)
		(end 147.371562 -46.11116)
		(stroke
			(width 0.072898)
			(type default)
		)
		(layer "B.Cu")
	)
	(gr_line
		(start 147.28571 -45.681392)
		(end 147.40382 -45.504354)
		(stroke
			(width 0.072898)
			(type default)
		)
		(layer "B.Cu")
	)
	(gr_line
		(start 147.347178 -32.666686)
		(end 147.4343 -33.0962)
		(stroke
			(width 0.072898)
			(type default)
		)
		(layer "B.Cu")
	)
	(gr_line
		(start 147.347178 -32.666686)
		(end 147.464526 -32.489648)
		(stroke
			(width 0.072898)
			(type default)
		)
		(layer "B.Cu")
	)
	(gr_line
		(start 147.362672 -37.006276)
		(end 147.492974 -37.65804)
		(stroke
			(width 0.072898)
			(type default)
		)
		(layer "B.Cu")
	)
	(gr_line
		(start 147.371562 -46.11116)
		(end 147.5486 -46.229016)
		(stroke
			(width 0.072898)
			(type default)
		)
		(layer "B.Cu")
	)
	(gr_line
		(start 147.4343 -33.0962)
		(end 147.611084 -33.213548)
		(stroke
			(width 0.072898)
			(type default)
		)
		(layer "B.Cu")
	)
	(gr_line
		(start 147.486878 -44.319952)
		(end 147.618196 -44.976542)
		(stroke
			(width 0.072898)
			(type default)
		)
		(layer "B.Cu")
	)
	(gr_line
		(start 147.58162 -33.824418)
		(end 147.668488 -34.253932)
		(stroke
			(width 0.072898)
			(type default)
		)
		(layer "B.Cu")
	)
	(gr_line
		(start 147.58162 -33.824418)
		(end 147.698968 -33.64738)
		(stroke
			(width 0.072898)
			(type default)
		)
		(layer "B.Cu")
	)
	(gr_line
		(start 147.659344 -31.916116)
		(end 147.672552 -31.935674)
		(stroke
			(width 0.072898)
			(type default)
		)
		(layer "B.Cu")
	)
	(gr_line
		(start 147.668488 -34.253932)
		(end 147.845526 -34.37128)
		(stroke
			(width 0.072898)
			(type default)
		)
		(layer "B.Cu")
	)
	(gr_line
		(start 147.672552 -31.935674)
		(end 147.677378 -31.959296)
		(stroke
			(width 0.072898)
			(type default)
		)
		(layer "B.Cu")
	)
	(gr_line
		(start 147.718018 -45.475652)
		(end 147.84959 -46.134782)
		(stroke
			(width 0.072898)
			(type default)
		)
		(layer "B.Cu")
	)
	(gr_line
		(start 147.778978 -32.460692)
		(end 147.91182 -33.117028)
		(stroke
			(width 0.072898)
			(type default)
		)
		(layer "B.Cu")
	)
	(gr_line
		(start 147.816062 -34.98215)
		(end 147.90293 -35.411664)
		(stroke
			(width 0.072898)
			(type default)
		)
		(layer "B.Cu")
	)
	(gr_line
		(start 147.816062 -34.98215)
		(end 147.93341 -34.805366)
		(stroke
			(width 0.072898)
			(type default)
		)
		(layer "B.Cu")
	)
	(gr_line
		(start 147.879308 -59.129676)
		(end 147.88388 -59.15279)
		(stroke
			(width 0.072898)
			(type default)
		)
		(layer "B.Cu")
	)
	(gr_line
		(start 147.879308 -59.129676)
		(end 147.88388 -59.106308)
		(stroke
			(width 0.072898)
			(type default)
		)
		(layer "B.Cu")
	)
	(gr_line
		(start 147.88388 -59.153044)
		(end 147.884134 -59.153806)
		(stroke
			(width 0.072898)
			(type default)
		)
		(layer "B.Cu")
	)
	(gr_line
		(start 147.90293 -35.411664)
		(end 148.079968 -35.529012)
		(stroke
			(width 0.072898)
			(type default)
		)
		(layer "B.Cu")
	)
	(gr_line
		(start 147.949412 -46.634146)
		(end 147.953476 -46.654974)
		(stroke
			(width 0.072898)
			(type default)
		)
		(layer "B.Cu")
	)
	(gr_line
		(start 147.949412 -46.633892)
		(end 147.949412 -46.6344)
		(stroke
			(width 0.072898)
			(type default)
		)
		(layer "B.Cu")
	)
	(gr_line
		(start 147.950174 -46.675294)
		(end 147.953476 -46.654974)
		(stroke
			(width 0.072898)
			(type default)
		)
		(layer "B.Cu")
	)
	(gr_line
		(start 148.013166 -33.617916)
		(end 148.146516 -34.275268)
		(stroke
			(width 0.072898)
			(type default)
		)
		(layer "B.Cu")
	)
	(gr_line
		(start 148.042884 -42.773092)
		(end 148.128736 -43.20286)
		(stroke
			(width 0.072898)
			(type default)
		)
		(layer "B.Cu")
	)
	(gr_line
		(start 148.042884 -42.773092)
		(end 148.16074 -42.596562)
		(stroke
			(width 0.072898)
			(type default)
		)
		(layer "B.Cu")
	)
	(gr_line
		(start 148.050504 -36.139882)
		(end 148.137372 -36.569396)
		(stroke
			(width 0.072898)
			(type default)
		)
		(layer "B.Cu")
	)
	(gr_line
		(start 148.050504 -36.139882)
		(end 148.167852 -35.963098)
		(stroke
			(width 0.072898)
			(type default)
		)
		(layer "B.Cu")
	)
	(gr_line
		(start 148.128736 -43.20286)
		(end 148.305266 -43.320462)
		(stroke
			(width 0.072898)
			(type default)
		)
		(layer "B.Cu")
	)
	(gr_line
		(start 148.137372 -36.569396)
		(end 148.314156 -36.68649)
		(stroke
			(width 0.072898)
			(type default)
		)
		(layer "B.Cu")
	)
	(gr_line
		(start 148.247862 -34.776664)
		(end 148.38045 -35.43173)
		(stroke
			(width 0.072898)
			(type default)
		)
		(layer "B.Cu")
	)
	(gr_line
		(start 148.274532 -43.931332)
		(end 148.360384 -44.360846)
		(stroke
			(width 0.072898)
			(type default)
		)
		(layer "B.Cu")
	)
	(gr_line
		(start 148.274532 -43.931332)
		(end 148.392134 -43.754802)
		(stroke
			(width 0.072898)
			(type default)
		)
		(layer "B.Cu")
	)
	(gr_line
		(start 148.360384 -44.360846)
		(end 148.536914 -44.478702)
		(stroke
			(width 0.072898)
			(type default)
		)
		(layer "B.Cu")
	)
	(gr_line
		(start 148.39442 -27.057858)
		(end 148.435822 -26.849832)
		(stroke
			(width 0.072898)
			(type default)
		)
		(layer "B.Cu")
	)
	(gr_line
		(start 148.39442 -27.057858)
		(end 148.637244 -27.422602)
		(stroke
			(width 0.072898)
			(type default)
		)
		(layer "B.Cu")
	)
	(gr_line
		(start 148.397976 -26.244042)
		(end 148.418042 -26.257504)
		(stroke
			(width 0.072898)
			(type default)
		)
		(layer "B.Cu")
	)
	(gr_line
		(start 148.418042 -26.257504)
		(end 148.431504 -26.27757)
		(stroke
			(width 0.072898)
			(type default)
		)
		(layer "B.Cu")
	)
	(gr_line
		(start 148.475446 -42.57167)
		(end 148.605748 -43.223434)
		(stroke
			(width 0.072898)
			(type default)
		)
		(layer "B.Cu")
	)
	(gr_line
		(start 148.482304 -35.935158)
		(end 148.614638 -36.5887)
		(stroke
			(width 0.072898)
			(type default)
		)
		(layer "B.Cu")
	)
	(gr_line
		(start 148.50618 -45.089572)
		(end 148.592032 -45.519086)
		(stroke
			(width 0.072898)
			(type default)
		)
		(layer "B.Cu")
	)
	(gr_line
		(start 148.50618 -45.089572)
		(end 148.623782 -44.912788)
		(stroke
			(width 0.072898)
			(type default)
		)
		(layer "B.Cu")
	)
	(gr_line
		(start 148.592032 -45.519086)
		(end 148.768562 -45.636942)
		(stroke
			(width 0.072898)
			(type default)
		)
		(layer "B.Cu")
	)
	(gr_line
		(start 148.637244 -27.422602)
		(end 148.845524 -27.464004)
		(stroke
			(width 0.072898)
			(type default)
		)
		(layer "B.Cu")
	)
	(gr_line
		(start 148.707094 -43.72991)
		(end 148.837142 -44.380404)
		(stroke
			(width 0.072898)
			(type default)
		)
		(layer "B.Cu")
	)
	(gr_line
		(start 148.717254 -26.706322)
		(end 149.086062 -27.259534)
		(stroke
			(width 0.072898)
			(type default)
		)
		(layer "B.Cu")
	)
	(gr_line
		(start 148.737828 -46.247558)
		(end 148.82368 -46.677326)
		(stroke
			(width 0.072898)
			(type default)
		)
		(layer "B.Cu")
	)
	(gr_line
		(start 148.737828 -46.247558)
		(end 148.85543 -46.071028)
		(stroke
			(width 0.072898)
			(type default)
		)
		(layer "B.Cu")
	)
	(gr_line
		(start 148.764498 -31.370524)
		(end 148.77669 -31.388558)
		(stroke
			(width 0.072898)
			(type default)
		)
		(layer "B.Cu")
	)
	(gr_line
		(start 148.77669 -31.388558)
		(end 148.781008 -31.410148)
		(stroke
			(width 0.072898)
			(type default)
		)
		(layer "B.Cu")
	)
	(gr_line
		(start 148.82368 -46.677326)
		(end 149.00021 -46.794674)
		(stroke
			(width 0.072898)
			(type default)
		)
		(layer "B.Cu")
	)
	(gr_line
		(start 148.938488 -44.88815)
		(end 149.068536 -45.538644)
		(stroke
			(width 0.072898)
			(type default)
		)
		(layer "B.Cu")
	)
	(gr_line
		(start 149.049486 -28.040584)
		(end 149.091142 -27.832558)
		(stroke
			(width 0.072898)
			(type default)
		)
		(layer "B.Cu")
	)
	(gr_line
		(start 149.049486 -28.040584)
		(end 149.292564 -28.405074)
		(stroke
			(width 0.072898)
			(type default)
		)
		(layer "B.Cu")
	)
	(gr_line
		(start 149.072092 -59.130946)
		(end 149.076664 -59.154314)
		(stroke
			(width 0.072898)
			(type default)
		)
		(layer "B.Cu")
	)
	(gr_line
		(start 149.072092 -59.130946)
		(end 149.076664 -59.107832)
		(stroke
			(width 0.072898)
			(type default)
		)
		(layer "B.Cu")
	)
	(gr_line
		(start 149.076664 -59.107578)
		(end 149.076918 -59.106816)
		(stroke
			(width 0.072898)
			(type default)
		)
		(layer "B.Cu")
	)
	(gr_line
		(start 149.082252 -76.894944)
		(end 149.087078 -76.92009)
		(stroke
			(width 0.072898)
			(type default)
		)
		(layer "B.Cu")
	)
	(gr_line
		(start 149.087078 -76.92009)
		(end 149.102318 -76.94168)
		(stroke
			(width 0.072898)
			(type default)
		)
		(layer "B.Cu")
	)
	(gr_line
		(start 149.167088 -25.29586)
		(end 149.185376 -25.308052)
		(stroke
			(width 0.072898)
			(type default)
		)
		(layer "B.Cu")
	)
	(gr_line
		(start 149.170136 -46.04512)
		(end 149.300438 -46.697138)
		(stroke
			(width 0.072898)
			(type default)
		)
		(layer "B.Cu")
	)
	(gr_line
		(start 149.185376 -25.308052)
		(end 149.197568 -25.32634)
		(stroke
			(width 0.072898)
			(type default)
		)
		(layer "B.Cu")
	)
	(gr_line
		(start 149.292564 -28.405074)
		(end 149.50059 -28.44673)
		(stroke
			(width 0.072898)
			(type default)
		)
		(layer "B.Cu")
	)
	(gr_line
		(start 149.298406 -42.304716)
		(end 149.385528 -42.73423)
		(stroke
			(width 0.072898)
			(type default)
		)
		(layer "B.Cu")
	)
	(gr_line
		(start 149.298406 -42.304716)
		(end 149.415754 -42.127932)
		(stroke
			(width 0.072898)
			(type default)
		)
		(layer "B.Cu")
	)
	(gr_line
		(start 149.371812 -27.688286)
		(end 149.741382 -28.242514)
		(stroke
			(width 0.072898)
			(type default)
		)
		(layer "B.Cu")
	)
	(gr_line
		(start 149.385528 -42.73423)
		(end 149.562312 -42.851324)
		(stroke
			(width 0.072898)
			(type default)
		)
		(layer "B.Cu")
	)
	(gr_line
		(start 149.40153 -47.202344)
		(end 149.401784 -47.203106)
		(stroke
			(width 0.072898)
			(type default)
		)
		(layer "B.Cu")
	)
	(gr_line
		(start 149.401784 -47.249842)
		(end 149.406356 -47.226474)
		(stroke
			(width 0.072898)
			(type default)
		)
		(layer "B.Cu")
	)
	(gr_line
		(start 149.401784 -47.20336)
		(end 149.406356 -47.226474)
		(stroke
			(width 0.072898)
			(type default)
		)
		(layer "B.Cu")
	)
	(gr_line
		(start 149.532848 -43.462448)
		(end 149.619716 -43.891708)
		(stroke
			(width 0.072898)
			(type default)
		)
		(layer "B.Cu")
	)
	(gr_line
		(start 149.532848 -43.462448)
		(end 149.650196 -43.28541)
		(stroke
			(width 0.072898)
			(type default)
		)
		(layer "B.Cu")
	)
	(gr_line
		(start 149.619716 -43.891708)
		(end 149.7965 -44.009056)
		(stroke
			(width 0.072898)
			(type default)
		)
		(layer "B.Cu")
	)
	(gr_line
		(start 149.704806 -29.02331)
		(end 149.746208 -28.815284)
		(stroke
			(width 0.072898)
			(type default)
		)
		(layer "B.Cu")
	)
	(gr_line
		(start 149.704806 -29.02331)
		(end 149.947884 -29.3878)
		(stroke
			(width 0.072898)
			(type default)
		)
		(layer "B.Cu")
	)
	(gr_line
		(start 149.730206 -42.099738)
		(end 149.86254 -42.753534)
		(stroke
			(width 0.072898)
			(type default)
		)
		(layer "B.Cu")
	)
	(gr_line
		(start 149.76729 -44.619926)
		(end 149.854158 -45.04944)
		(stroke
			(width 0.072898)
			(type default)
		)
		(layer "B.Cu")
	)
	(gr_line
		(start 149.76729 -44.619926)
		(end 149.884384 -44.443396)
		(stroke
			(width 0.072898)
			(type default)
		)
		(layer "B.Cu")
	)
	(gr_line
		(start 149.837648 -30.790642)
		(end 149.84984 -30.808676)
		(stroke
			(width 0.072898)
			(type default)
		)
		(layer "B.Cu")
	)
	(gr_line
		(start 149.84984 -30.808676)
		(end 149.854158 -30.830266)
		(stroke
			(width 0.072898)
			(type default)
		)
		(layer "B.Cu")
	)
	(gr_line
		(start 149.854158 -45.04944)
		(end 150.030942 -45.166788)
		(stroke
			(width 0.072898)
			(type default)
		)
		(layer "B.Cu")
	)
	(gr_line
		(start 149.895814 -24.252174)
		(end 149.91588 -24.265636)
		(stroke
			(width 0.072898)
			(type default)
		)
		(layer "B.Cu")
	)
	(gr_line
		(start 149.91588 -24.265636)
		(end 149.929342 -24.285702)
		(stroke
			(width 0.072898)
			(type default)
		)
		(layer "B.Cu")
	)
	(gr_line
		(start 149.947884 -29.3878)
		(end 150.155656 -29.429456)
		(stroke
			(width 0.072898)
			(type default)
		)
		(layer "B.Cu")
	)
	(gr_line
		(start 149.964902 -43.26001)
		(end 150.096982 -43.912028)
		(stroke
			(width 0.072898)
			(type default)
		)
		(layer "B.Cu")
	)
	(gr_line
		(start 150.001478 -45.777658)
		(end 150.0886 -46.206918)
		(stroke
			(width 0.072898)
			(type default)
		)
		(layer "B.Cu")
	)
	(gr_line
		(start 150.001478 -45.777658)
		(end 150.118826 -45.60062)
		(stroke
			(width 0.072898)
			(type default)
		)
		(layer "B.Cu")
	)
	(gr_line
		(start 150.02764 -28.671774)
		(end 150.244048 -28.99664)
		(stroke
			(width 0.072898)
			(type default)
		)
		(layer "B.Cu")
	)
	(gr_line
		(start 150.0886 -46.206918)
		(end 150.26513 -46.324012)
		(stroke
			(width 0.072898)
			(type default)
		)
		(layer "B.Cu")
	)
	(gr_line
		(start 150.14448 -76.298044)
		(end 150.149052 -76.32192)
		(stroke
			(width 0.072898)
			(type default)
		)
		(layer "B.Cu")
	)
	(gr_line
		(start 150.149052 -76.32192)
		(end 150.163276 -76.34224)
		(stroke
			(width 0.072898)
			(type default)
		)
		(layer "B.Cu")
	)
	(gr_line
		(start 150.19909 -44.41571)
		(end 150.331678 -45.070268)
		(stroke
			(width 0.072898)
			(type default)
		)
		(layer "B.Cu")
	)
	(gr_line
		(start 150.244048 -59.128914)
		(end 150.24862 -59.152028)
		(stroke
			(width 0.072898)
			(type default)
		)
		(layer "B.Cu")
	)
	(gr_line
		(start 150.244048 -59.128914)
		(end 150.24862 -59.105546)
		(stroke
			(width 0.072898)
			(type default)
		)
		(layer "B.Cu")
	)
	(gr_line
		(start 150.24862 -59.152282)
		(end 150.248874 -59.153044)
		(stroke
			(width 0.072898)
			(type default)
		)
		(layer "B.Cu")
	)
	(gr_line
		(start 150.433278 -45.572426)
		(end 150.565612 -46.226222)
		(stroke
			(width 0.072898)
			(type default)
		)
		(layer "B.Cu")
	)
	(gr_line
		(start 150.66772 -46.731428)
		(end 150.667974 -46.73219)
		(stroke
			(width 0.072898)
			(type default)
		)
		(layer "B.Cu")
	)
	(gr_line
		(start 150.667974 -46.778672)
		(end 150.672546 -46.755304)
		(stroke
			(width 0.072898)
			(type default)
		)
		(layer "B.Cu")
	)
	(gr_line
		(start 150.667974 -46.732444)
		(end 150.672546 -46.755304)
		(stroke
			(width 0.072898)
			(type default)
		)
		(layer "B.Cu")
	)
	(gr_line
		(start 150.740618 -30.962092)
		(end 150.82647 -31.391606)
		(stroke
			(width 0.072898)
			(type default)
		)
		(layer "B.Cu")
	)
	(gr_line
		(start 150.740618 -30.962092)
		(end 150.858474 -30.785562)
		(stroke
			(width 0.072898)
			(type default)
		)
		(layer "B.Cu")
	)
	(gr_line
		(start 150.82647 -31.391606)
		(end 151.003 -31.509462)
		(stroke
			(width 0.072898)
			(type default)
		)
		(layer "B.Cu")
	)
	(gr_line
		(start 150.972266 -32.120078)
		(end 151.058118 -32.549846)
		(stroke
			(width 0.072898)
			(type default)
		)
		(layer "B.Cu")
	)
	(gr_line
		(start 150.972266 -32.120078)
		(end 151.089868 -31.943548)
		(stroke
			(width 0.072898)
			(type default)
		)
		(layer "B.Cu")
	)
	(gr_line
		(start 151.055324 -30.213554)
		(end 151.067516 -30.231588)
		(stroke
			(width 0.072898)
			(type default)
		)
		(layer "B.Cu")
	)
	(gr_line
		(start 151.058118 -32.549846)
		(end 151.234648 -32.667702)
		(stroke
			(width 0.072898)
			(type default)
		)
		(layer "B.Cu")
	)
	(gr_line
		(start 151.067516 -30.231588)
		(end 151.071834 -30.253178)
		(stroke
			(width 0.072898)
			(type default)
		)
		(layer "B.Cu")
	)
	(gr_line
		(start 151.078692 -79.729584)
		(end 151.09063 -79.746348)
		(stroke
			(width 0.072898)
			(type default)
		)
		(layer "B.Cu")
	)
	(gr_line
		(start 151.09063 -79.746348)
		(end 151.107394 -79.75727)
		(stroke
			(width 0.072898)
			(type default)
		)
		(layer "B.Cu")
	)
	(gr_line
		(start 151.17318 -30.759146)
		(end 151.304244 -31.414466)
		(stroke
			(width 0.072898)
			(type default)
		)
		(layer "B.Cu")
	)
	(gr_line
		(start 151.199088 -75.732894)
		(end 151.203406 -75.754484)
		(stroke
			(width 0.072898)
			(type default)
		)
		(layer "B.Cu")
	)
	(gr_line
		(start 151.203406 -75.754484)
		(end 151.215598 -75.772518)
		(stroke
			(width 0.072898)
			(type default)
		)
		(layer "B.Cu")
	)
	(gr_line
		(start 151.20366 -33.278318)
		(end 151.289512 -33.708086)
		(stroke
			(width 0.072898)
			(type default)
		)
		(layer "B.Cu")
	)
	(gr_line
		(start 151.20366 -33.278318)
		(end 151.321516 -33.101788)
		(stroke
			(width 0.072898)
			(type default)
		)
		(layer "B.Cu")
	)
	(gr_line
		(start 151.289512 -33.708086)
		(end 151.466042 -33.825688)
		(stroke
			(width 0.072898)
			(type default)
		)
		(layer "B.Cu")
	)
	(gr_line
		(start 151.40432 -31.9151)
		(end 151.535638 -32.571944)
		(stroke
			(width 0.072898)
			(type default)
		)
		(layer "B.Cu")
	)
	(gr_line
		(start 151.435054 -34.436558)
		(end 151.52116 -34.866072)
		(stroke
			(width 0.072898)
			(type default)
		)
		(layer "B.Cu")
	)
	(gr_line
		(start 151.435054 -34.436558)
		(end 151.55291 -34.259774)
		(stroke
			(width 0.072898)
			(type default)
		)
		(layer "B.Cu")
	)
	(gr_line
		(start 151.45639 -59.34202)
		(end 151.460962 -59.365134)
		(stroke
			(width 0.072898)
			(type default)
		)
		(layer "B.Cu")
	)
	(gr_line
		(start 151.45639 -59.34202)
		(end 151.460962 -59.318652)
		(stroke
			(width 0.072898)
			(type default)
		)
		(layer "B.Cu")
	)
	(gr_line
		(start 151.460962 -59.365388)
		(end 151.461216 -59.36615)
		(stroke
			(width 0.072898)
			(type default)
		)
		(layer "B.Cu")
	)
	(gr_line
		(start 151.52116 -34.866072)
		(end 151.69769 -34.983928)
		(stroke
			(width 0.072898)
			(type default)
		)
		(layer "B.Cu")
	)
	(gr_line
		(start 151.635968 -33.074864)
		(end 151.766778 -33.729168)
		(stroke
			(width 0.072898)
			(type default)
		)
		(layer "B.Cu")
	)
	(gr_line
		(start 151.641302 -78.486254)
		(end 151.654256 -78.504796)
		(stroke
			(width 0.072898)
			(type default)
		)
		(layer "B.Cu")
	)
	(gr_line
		(start 151.654256 -78.504796)
		(end 151.673306 -78.517496)
		(stroke
			(width 0.072898)
			(type default)
		)
		(layer "B.Cu")
	)
	(gr_line
		(start 151.850598 -46.772576)
		(end 151.850852 -46.773338)
		(stroke
			(width 0.072898)
			(type default)
		)
		(layer "B.Cu")
	)
	(gr_line
		(start 151.850852 -46.820074)
		(end 151.855424 -46.796706)
		(stroke
			(width 0.072898)
			(type default)
		)
		(layer "B.Cu")
	)
	(gr_line
		(start 151.850852 -46.773592)
		(end 151.855424 -46.796706)
		(stroke
			(width 0.072898)
			(type default)
		)
		(layer "B.Cu")
	)
	(gr_line
		(start 151.867616 -34.23412)
		(end 151.997918 -34.885884)
		(stroke
			(width 0.072898)
			(type default)
		)
		(layer "B.Cu")
	)
	(gr_line
		(start 152.023064 -30.731206)
		(end 152.108916 -31.16072)
		(stroke
			(width 0.072898)
			(type default)
		)
		(layer "B.Cu")
	)
	(gr_line
		(start 152.023064 -30.731206)
		(end 152.140666 -30.554422)
		(stroke
			(width 0.072898)
			(type default)
		)
		(layer "B.Cu")
	)
	(gr_line
		(start 152.108916 -31.16072)
		(end 152.2857 -31.278576)
		(stroke
			(width 0.072898)
			(type default)
		)
		(layer "B.Cu")
	)
	(gr_line
		(start 152.254712 -31.889192)
		(end 152.340564 -32.31896)
		(stroke
			(width 0.072898)
			(type default)
		)
		(layer "B.Cu")
	)
	(gr_line
		(start 152.254712 -31.889192)
		(end 152.372314 -31.712408)
		(stroke
			(width 0.072898)
			(type default)
		)
		(layer "B.Cu")
	)
	(gr_line
		(start 152.305766 -75.291188)
		(end 152.30983 -75.312524)
		(stroke
			(width 0.072898)
			(type default)
		)
		(layer "B.Cu")
	)
	(gr_line
		(start 152.30983 -75.312524)
		(end 152.322022 -75.330558)
		(stroke
			(width 0.072898)
			(type default)
		)
		(layer "B.Cu")
	)
	(gr_line
		(start 152.335738 -29.978858)
		(end 152.349708 -29.999686)
		(stroke
			(width 0.072898)
			(type default)
		)
		(layer "B.Cu")
	)
	(gr_line
		(start 152.340564 -32.31896)
		(end 152.517094 -32.436562)
		(stroke
			(width 0.072898)
			(type default)
		)
		(layer "B.Cu")
	)
	(gr_line
		(start 152.349708 -29.999686)
		(end 152.35428 -30.023562)
		(stroke
			(width 0.072898)
			(type default)
		)
		(layer "B.Cu")
	)
	(gr_line
		(start 152.455118 -30.528006)
		(end 152.585674 -31.180532)
		(stroke
			(width 0.072898)
			(type default)
		)
		(layer "B.Cu")
	)
	(gr_line
		(start 152.469596 -77.653388)
		(end 152.483058 -77.673454)
		(stroke
			(width 0.072898)
			(type default)
		)
		(layer "B.Cu")
	)
	(gr_line
		(start 152.483058 -77.673454)
		(end 152.503124 -77.686916)
		(stroke
			(width 0.072898)
			(type default)
		)
		(layer "B.Cu")
	)
	(gr_line
		(start 152.48636 -33.047432)
		(end 152.572212 -33.476946)
		(stroke
			(width 0.072898)
			(type default)
		)
		(layer "B.Cu")
	)
	(gr_line
		(start 152.48636 -33.047432)
		(end 152.603962 -32.870648)
		(stroke
			(width 0.072898)
			(type default)
		)
		(layer "B.Cu")
	)
	(gr_line
		(start 152.572212 -33.476946)
		(end 152.748742 -33.594802)
		(stroke
			(width 0.072898)
			(type default)
		)
		(layer "B.Cu")
	)
	(gr_line
		(start 152.68702 -31.686754)
		(end 152.817576 -32.33928)
		(stroke
			(width 0.072898)
			(type default)
		)
		(layer "B.Cu")
	)
	(gr_line
		(start 152.717754 -34.205672)
		(end 152.80386 -34.635186)
		(stroke
			(width 0.072898)
			(type default)
		)
		(layer "B.Cu")
	)
	(gr_line
		(start 152.717754 -34.205672)
		(end 152.83561 -34.028888)
		(stroke
			(width 0.072898)
			(type default)
		)
		(layer "B.Cu")
	)
	(gr_line
		(start 152.73528 -40.941244)
		(end 152.821132 -41.371012)
		(stroke
			(width 0.072898)
			(type default)
		)
		(layer "B.Cu")
	)
	(gr_line
		(start 152.73528 -40.941244)
		(end 152.853136 -40.76446)
		(stroke
			(width 0.072898)
			(type default)
		)
		(layer "B.Cu")
	)
	(gr_line
		(start 152.744424 -59.057794)
		(end 152.83053 -58.62828)
		(stroke
			(width 0.072898)
			(type default)
		)
		(layer "B.Cu")
	)
	(gr_line
		(start 152.744424 -59.057794)
		(end 152.86228 -59.234324)
		(stroke
			(width 0.072898)
			(type default)
		)
		(layer "B.Cu")
	)
	(gr_line
		(start 152.778206 -59.666886)
		(end 152.782524 -59.688984)
		(stroke
			(width 0.072898)
			(type default)
		)
		(layer "B.Cu")
	)
	(gr_line
		(start 152.778206 -59.666886)
		(end 152.782524 -59.645042)
		(stroke
			(width 0.072898)
			(type default)
		)
		(layer "B.Cu")
	)
	(gr_line
		(start 152.80386 -34.635186)
		(end 152.98039 -34.753042)
		(stroke
			(width 0.072898)
			(type default)
		)
		(layer "B.Cu")
	)
	(gr_line
		(start 152.821132 -41.371012)
		(end 152.99817 -41.488868)
		(stroke
			(width 0.072898)
			(type default)
		)
		(layer "B.Cu")
	)
	(gr_line
		(start 152.83053 -58.62828)
		(end 153.006806 -58.510678)
		(stroke
			(width 0.072898)
			(type default)
		)
		(layer "B.Cu")
	)
	(gr_line
		(start 152.918414 -32.843978)
		(end 153.048716 -33.496504)
		(stroke
			(width 0.072898)
			(type default)
		)
		(layer "B.Cu")
	)
	(gr_line
		(start 152.966928 -42.099484)
		(end 153.05278 -42.528998)
		(stroke
			(width 0.072898)
			(type default)
		)
		(layer "B.Cu")
	)
	(gr_line
		(start 152.966928 -42.099484)
		(end 153.084784 -41.922446)
		(stroke
			(width 0.072898)
			(type default)
		)
		(layer "B.Cu")
	)
	(gr_line
		(start 152.976072 -57.899808)
		(end 153.061924 -57.47004)
		(stroke
			(width 0.072898)
			(type default)
		)
		(layer "B.Cu")
	)
	(gr_line
		(start 152.976072 -57.899808)
		(end 153.093674 -58.076084)
		(stroke
			(width 0.072898)
			(type default)
		)
		(layer "B.Cu")
	)
	(gr_line
		(start 153.03246 -46.773592)
		(end 153.032714 -46.77283)
		(stroke
			(width 0.072898)
			(type default)
		)
		(layer "B.Cu")
	)
	(gr_line
		(start 153.032714 -46.772576)
		(end 153.037286 -46.749462)
		(stroke
			(width 0.072898)
			(type default)
		)
		(layer "B.Cu")
	)
	(gr_line
		(start 153.032714 -46.726094)
		(end 153.037286 -46.749462)
		(stroke
			(width 0.072898)
			(type default)
		)
		(layer "B.Cu")
	)
	(gr_line
		(start 153.05278 -42.528998)
		(end 153.229564 -42.646854)
		(stroke
			(width 0.072898)
			(type default)
		)
		(layer "B.Cu")
	)
	(gr_line
		(start 153.061924 -57.47004)
		(end 153.238454 -57.352184)
		(stroke
			(width 0.072898)
			(type default)
		)
		(layer "B.Cu")
	)
	(gr_line
		(start 153.150316 -34.003234)
		(end 153.280872 -34.65576)
		(stroke
			(width 0.072898)
			(type default)
		)
		(layer "B.Cu")
	)
	(gr_line
		(start 153.167588 -40.736266)
		(end 153.298906 -41.394126)
		(stroke
			(width 0.072898)
			(type default)
		)
		(layer "B.Cu")
	)
	(gr_line
		(start 153.176986 -59.260486)
		(end 153.307288 -58.608468)
		(stroke
			(width 0.072898)
			(type default)
		)
		(layer "B.Cu")
	)
	(gr_line
		(start 153.198322 -43.257724)
		(end 153.284174 -43.687238)
		(stroke
			(width 0.072898)
			(type default)
		)
		(layer "B.Cu")
	)
	(gr_line
		(start 153.198322 -43.257724)
		(end 153.316432 -43.08094)
		(stroke
			(width 0.072898)
			(type default)
		)
		(layer "B.Cu")
	)
	(gr_line
		(start 153.207466 -56.741314)
		(end 153.293572 -56.3118)
		(stroke
			(width 0.072898)
			(type default)
		)
		(layer "B.Cu")
	)
	(gr_line
		(start 153.207466 -56.741314)
		(end 153.325322 -56.918098)
		(stroke
			(width 0.072898)
			(type default)
		)
		(layer "B.Cu")
	)
	(gr_line
		(start 153.284174 -43.687238)
		(end 153.461212 -43.805348)
		(stroke
			(width 0.072898)
			(type default)
		)
		(layer "B.Cu")
	)
	(gr_line
		(start 153.28773 -76.77912)
		(end 153.301192 -76.799186)
		(stroke
			(width 0.072898)
			(type default)
		)
		(layer "B.Cu")
	)
	(gr_line
		(start 153.293572 -56.3118)
		(end 153.470102 -56.193944)
		(stroke
			(width 0.072898)
			(type default)
		)
		(layer "B.Cu")
	)
	(gr_line
		(start 153.301192 -76.799186)
		(end 153.321258 -76.812648)
		(stroke
			(width 0.072898)
			(type default)
		)
		(layer "B.Cu")
	)
	(gr_line
		(start 153.373074 -74.777092)
		(end 153.377392 -74.798428)
		(stroke
			(width 0.072898)
			(type default)
		)
		(layer "B.Cu")
	)
	(gr_line
		(start 153.377392 -74.798428)
		(end 153.38933 -74.816208)
		(stroke
			(width 0.072898)
			(type default)
		)
		(layer "B.Cu")
	)
	(gr_line
		(start 153.398728 -41.891966)
		(end 153.530808 -42.552874)
		(stroke
			(width 0.072898)
			(type default)
		)
		(layer "B.Cu")
	)
	(gr_line
		(start 153.408634 -58.1025)
		(end 153.539444 -57.447942)
		(stroke
			(width 0.072898)
			(type default)
		)
		(layer "B.Cu")
	)
	(gr_line
		(start 153.429462 -29.536644)
		(end 153.441654 -29.554678)
		(stroke
			(width 0.072898)
			(type default)
		)
		(layer "B.Cu")
	)
	(gr_line
		(start 153.429716 -44.41571)
		(end 153.515822 -44.845478)
		(stroke
			(width 0.072898)
			(type default)
		)
		(layer "B.Cu")
	)
	(gr_line
		(start 153.429716 -44.41571)
		(end 153.547826 -44.238672)
		(stroke
			(width 0.072898)
			(type default)
		)
		(layer "B.Cu")
	)
	(gr_line
		(start 153.441654 -29.554678)
		(end 153.445972 -29.576268)
		(stroke
			(width 0.072898)
			(type default)
		)
		(layer "B.Cu")
	)
	(gr_line
		(start 153.515822 -44.845478)
		(end 153.692606 -44.963588)
		(stroke
			(width 0.072898)
			(type default)
		)
		(layer "B.Cu")
	)
	(gr_line
		(start 153.630376 -43.051222)
		(end 153.762456 -43.711622)
		(stroke
			(width 0.072898)
			(type default)
		)
		(layer "B.Cu")
	)
	(gr_line
		(start 153.639774 -56.946038)
		(end 153.770838 -56.290718)
		(stroke
			(width 0.072898)
			(type default)
		)
		(layer "B.Cu")
	)
	(gr_line
		(start 153.661364 -45.57395)
		(end 153.747216 -46.003718)
		(stroke
			(width 0.072898)
			(type default)
		)
		(layer "B.Cu")
	)
	(gr_line
		(start 153.661364 -45.57395)
		(end 153.779474 -45.397166)
		(stroke
			(width 0.072898)
			(type default)
		)
		(layer "B.Cu")
	)
	(gr_line
		(start 153.747216 -46.003718)
		(end 153.924254 -46.121574)
		(stroke
			(width 0.072898)
			(type default)
		)
		(layer "B.Cu")
	)
	(gr_line
		(start 153.862024 -44.209716)
		(end 153.99385 -44.869354)
		(stroke
			(width 0.072898)
			(type default)
		)
		(layer "B.Cu")
	)
	(gr_line
		(start 154.011884 -59.397138)
		(end 154.097482 -58.96737)
		(stroke
			(width 0.072898)
			(type default)
		)
		(layer "B.Cu")
	)
	(gr_line
		(start 154.011884 -59.397138)
		(end 154.12974 -59.573414)
		(stroke
			(width 0.072898)
			(type default)
		)
		(layer "B.Cu")
	)
	(gr_line
		(start 154.04592 -60.005976)
		(end 154.050238 -60.028074)
		(stroke
			(width 0.072898)
			(type default)
		)
		(layer "B.Cu")
	)
	(gr_line
		(start 154.04592 -60.005976)
		(end 154.050238 -59.983878)
		(stroke
			(width 0.072898)
			(type default)
		)
		(layer "B.Cu")
	)
	(gr_line
		(start 154.093672 -45.368718)
		(end 154.225498 -46.027848)
		(stroke
			(width 0.072898)
			(type default)
		)
		(layer "B.Cu")
	)
	(gr_line
		(start 154.097482 -58.96737)
		(end 154.274012 -58.849514)
		(stroke
			(width 0.072898)
			(type default)
		)
		(layer "B.Cu")
	)
	(gr_line
		(start 154.171142 -75.994006)
		(end 154.184096 -76.013564)
		(stroke
			(width 0.072898)
			(type default)
		)
		(layer "B.Cu")
	)
	(gr_line
		(start 154.184096 -76.013564)
		(end 154.203146 -76.026264)
		(stroke
			(width 0.072898)
			(type default)
		)
		(layer "B.Cu")
	)
	(gr_line
		(start 154.24277 -58.238644)
		(end 154.328368 -57.80913)
		(stroke
			(width 0.072898)
			(type default)
		)
		(layer "B.Cu")
	)
	(gr_line
		(start 154.24277 -58.238644)
		(end 154.360626 -58.415174)
		(stroke
			(width 0.072898)
			(type default)
		)
		(layer "B.Cu")
	)
	(gr_line
		(start 154.325066 -46.52645)
		(end 154.330146 -46.55185)
		(stroke
			(width 0.072898)
			(type default)
		)
		(layer "B.Cu")
	)
	(gr_line
		(start 154.32532 -46.576488)
		(end 154.330146 -46.552358)
		(stroke
			(width 0.072898)
			(type default)
		)
		(layer "B.Cu")
	)
	(gr_line
		(start 154.325828 -51.149504)
		(end 154.41168 -50.71999)
		(stroke
			(width 0.072898)
			(type default)
		)
		(layer "B.Cu")
	)
	(gr_line
		(start 154.325828 -51.149504)
		(end 154.44343 -51.326034)
		(stroke
			(width 0.072898)
			(type default)
		)
		(layer "B.Cu")
	)
	(gr_line
		(start 154.328368 -57.80913)
		(end 154.504898 -57.69102)
		(stroke
			(width 0.072898)
			(type default)
		)
		(layer "B.Cu")
	)
	(gr_line
		(start 154.330146 -46.55185)
		(end 154.330146 -46.552358)
		(stroke
			(width 0.072898)
			(type default)
		)
		(layer "B.Cu")
	)
	(gr_line
		(start 154.41168 -50.71999)
		(end 154.58821 -50.602388)
		(stroke
			(width 0.072898)
			(type default)
		)
		(layer "B.Cu")
	)
	(gr_line
		(start 154.431238 -74.229722)
		(end 154.435556 -74.251312)
		(stroke
			(width 0.072898)
			(type default)
		)
		(layer "B.Cu")
	)
	(gr_line
		(start 154.435556 -74.251312)
		(end 154.447748 -74.269346)
		(stroke
			(width 0.072898)
			(type default)
		)
		(layer "B.Cu")
	)
	(gr_line
		(start 154.444446 -59.598814)
		(end 154.573986 -58.947812)
		(stroke
			(width 0.072898)
			(type default)
		)
		(layer "B.Cu")
	)
	(gr_line
		(start 154.473656 -57.080404)
		(end 154.559254 -56.650636)
		(stroke
			(width 0.072898)
			(type default)
		)
		(layer "B.Cu")
	)
	(gr_line
		(start 154.473656 -57.080404)
		(end 154.591512 -57.25668)
		(stroke
			(width 0.072898)
			(type default)
		)
		(layer "B.Cu")
	)
	(gr_line
		(start 154.557222 -49.991264)
		(end 154.643328 -49.56175)
		(stroke
			(width 0.072898)
			(type default)
		)
		(layer "B.Cu")
	)
	(gr_line
		(start 154.557222 -49.991264)
		(end 154.675078 -50.167794)
		(stroke
			(width 0.072898)
			(type default)
		)
		(layer "B.Cu")
	)
	(gr_line
		(start 154.559254 -56.650636)
		(end 154.735784 -56.53278)
		(stroke
			(width 0.072898)
			(type default)
		)
		(layer "B.Cu")
	)
	(gr_line
		(start 154.643328 -49.56175)
		(end 154.819604 -49.444148)
		(stroke
			(width 0.072898)
			(type default)
		)
		(layer "B.Cu")
	)
	(gr_line
		(start 154.675332 -58.440828)
		(end 154.80538 -57.788048)
		(stroke
			(width 0.072898)
			(type default)
		)
		(layer "B.Cu")
	)
	(gr_line
		(start 154.757882 -51.352704)
		(end 154.888692 -50.699416)
		(stroke
			(width 0.072898)
			(type default)
		)
		(layer "B.Cu")
	)
	(gr_line
		(start 154.78887 -48.833278)
		(end 154.874722 -48.40351)
		(stroke
			(width 0.072898)
			(type default)
		)
		(layer "B.Cu")
	)
	(gr_line
		(start 154.78887 -48.833278)
		(end 154.906472 -49.009808)
		(stroke
			(width 0.072898)
			(type default)
		)
		(layer "B.Cu")
	)
	(gr_line
		(start 154.874722 -48.40351)
		(end 155.051252 -48.285654)
		(stroke
			(width 0.072898)
			(type default)
		)
		(layer "B.Cu")
	)
	(gr_line
		(start 154.905964 -57.28335)
		(end 155.03652 -56.6293)
		(stroke
			(width 0.072898)
			(type default)
		)
		(layer "B.Cu")
	)
	(gr_line
		(start 154.989784 -50.193956)
		(end 155.12034 -49.540922)
		(stroke
			(width 0.072898)
			(type default)
		)
		(layer "B.Cu")
	)
	(gr_line
		(start 155.020518 -47.675038)
		(end 155.10637 -47.24527)
		(stroke
			(width 0.072898)
			(type default)
		)
		(layer "B.Cu")
	)
	(gr_line
		(start 155.020518 -47.675038)
		(end 155.13812 -47.851568)
		(stroke
			(width 0.072898)
			(type default)
		)
		(layer "B.Cu")
	)
	(gr_line
		(start 155.090114 -75.23226)
		(end 155.103068 -75.252072)
		(stroke
			(width 0.072898)
			(type default)
		)
		(layer "B.Cu")
	)
	(gr_line
		(start 155.103068 -75.252072)
		(end 155.123134 -75.265534)
		(stroke
			(width 0.072898)
			(type default)
		)
		(layer "B.Cu")
	)
	(gr_line
		(start 155.10637 -47.24527)
		(end 155.2829 -47.127668)
		(stroke
			(width 0.072898)
			(type default)
		)
		(layer "B.Cu")
	)
	(gr_line
		(start 155.221178 -49.03724)
		(end 155.352496 -48.380904)
		(stroke
			(width 0.072898)
			(type default)
		)
		(layer "B.Cu")
	)
	(gr_line
		(start 155.452572 -47.880016)
		(end 155.583636 -47.224442)
		(stroke
			(width 0.072898)
			(type default)
		)
		(layer "B.Cu")
	)
	(gr_line
		(start 155.502864 -73.683368)
		(end 155.507436 -73.708006)
		(stroke
			(width 0.072898)
			(type default)
		)
		(layer "B.Cu")
	)
	(gr_line
		(start 155.507436 -73.708006)
		(end 155.521914 -73.729596)
		(stroke
			(width 0.072898)
			(type default)
		)
		(layer "B.Cu")
	)
	(gr_line
		(start 155.582874 -51.515518)
		(end 155.668472 -51.086004)
		(stroke
			(width 0.072898)
			(type default)
		)
		(layer "B.Cu")
	)
	(gr_line
		(start 155.582874 -51.515518)
		(end 155.70073 -51.692048)
		(stroke
			(width 0.072898)
			(type default)
		)
		(layer "B.Cu")
	)
	(gr_line
		(start 155.668472 -51.086004)
		(end 155.845002 -50.968148)
		(stroke
			(width 0.072898)
			(type default)
		)
		(layer "B.Cu")
	)
	(gr_line
		(start 155.68422 -46.720252)
		(end 155.684474 -46.71949)
		(stroke
			(width 0.072898)
			(type default)
		)
		(layer "B.Cu")
	)
	(gr_line
		(start 155.684474 -46.719236)
		(end 155.689046 -46.696122)
		(stroke
			(width 0.072898)
			(type default)
		)
		(layer "B.Cu")
	)
	(gr_line
		(start 155.684474 -46.672754)
		(end 155.689046 -46.696122)
		(stroke
			(width 0.072898)
			(type default)
		)
		(layer "B.Cu")
	)
	(gr_line
		(start 155.81376 -50.357278)
		(end 155.899358 -49.92751)
		(stroke
			(width 0.072898)
			(type default)
		)
		(layer "B.Cu")
	)
	(gr_line
		(start 155.81376 -50.357278)
		(end 155.931616 -50.533808)
		(stroke
			(width 0.072898)
			(type default)
		)
		(layer "B.Cu")
	)
	(gr_line
		(start 155.899358 -49.92751)
		(end 156.075888 -49.809654)
		(stroke
			(width 0.072898)
			(type default)
		)
		(layer "B.Cu")
	)
	(gr_line
		(start 156.015182 -51.721258)
		(end 156.146246 -51.063398)
		(stroke
			(width 0.072898)
			(type default)
		)
		(layer "B.Cu")
	)
	(gr_line
		(start 156.033216 -74.487024)
		(end 156.045916 -74.506074)
		(stroke
			(width 0.072898)
			(type default)
		)
		(layer "B.Cu")
	)
	(gr_line
		(start 156.044646 -49.199038)
		(end 156.130244 -48.76927)
		(stroke
			(width 0.072898)
			(type default)
		)
		(layer "B.Cu")
	)
	(gr_line
		(start 156.044646 -49.199038)
		(end 156.162502 -49.375568)
		(stroke
			(width 0.072898)
			(type default)
		)
		(layer "B.Cu")
	)
	(gr_line
		(start 156.045916 -74.506074)
		(end 156.06522 -74.519028)
		(stroke
			(width 0.072898)
			(type default)
		)
		(layer "B.Cu")
	)
	(gr_line
		(start 156.130244 -48.76927)
		(end 156.306774 -48.651414)
		(stroke
			(width 0.072898)
			(type default)
		)
		(layer "B.Cu")
	)
	(gr_line
		(start 156.246068 -50.563018)
		(end 156.377386 -49.903888)
		(stroke
			(width 0.072898)
			(type default)
		)
		(layer "B.Cu")
	)
	(gr_line
		(start 156.275532 -48.040798)
		(end 156.36113 -47.61103)
		(stroke
			(width 0.072898)
			(type default)
		)
		(layer "B.Cu")
	)
	(gr_line
		(start 156.275532 -48.040798)
		(end 156.393388 -48.217074)
		(stroke
			(width 0.072898)
			(type default)
		)
		(layer "B.Cu")
	)
	(gr_line
		(start 156.36113 -47.61103)
		(end 156.53766 -47.493174)
		(stroke
			(width 0.072898)
			(type default)
		)
		(layer "B.Cu")
	)
	(gr_line
		(start 156.476954 -49.404524)
		(end 156.608272 -48.745394)
		(stroke
			(width 0.072898)
			(type default)
		)
		(layer "B.Cu")
	)
	(gr_line
		(start 156.584396 -73.064116)
		(end 156.588968 -73.088754)
		(stroke
			(width 0.072898)
			(type default)
		)
		(layer "B.Cu")
	)
	(gr_line
		(start 156.588968 -73.088754)
		(end 156.603446 -73.110344)
		(stroke
			(width 0.072898)
			(type default)
		)
		(layer "B.Cu")
	)
	(gr_line
		(start 156.70784 -48.245522)
		(end 156.83865 -47.589186)
		(stroke
			(width 0.072898)
			(type default)
		)
		(layer "B.Cu")
	)
	(gr_line
		(start 156.938726 -47.086266)
		(end 156.93898 -47.08525)
		(stroke
			(width 0.072898)
			(type default)
		)
		(layer "B.Cu")
	)
	(gr_line
		(start 156.938726 -47.08525)
		(end 156.943552 -47.061628)
		(stroke
			(width 0.072898)
			(type default)
		)
		(layer "B.Cu")
	)
	(gr_line
		(start 156.93898 -47.03826)
		(end 156.943552 -47.061628)
		(stroke
			(width 0.072898)
			(type default)
		)
		(layer "B.Cu")
	)
	(gr_line
		(start 157.073854 -73.807066)
		(end 157.085538 -73.824592)
		(stroke
			(width 0.072898)
			(type default)
		)
		(layer "B.Cu")
	)
	(gr_line
		(start 157.085538 -73.824592)
		(end 157.103572 -73.836784)
		(stroke
			(width 0.072898)
			(type default)
		)
		(layer "B.Cu")
	)
	(gr_line
		(start 159.250126 -22.899878)
		(end 159.470344 -22.488906)
		(stroke
			(width 0.06223)
			(type default)
		)
		(layer "B.Cu")
	)
	(gr_line
		(start 159.250126 -19.100038)
		(end 159.470344 -18.688812)
		(stroke
			(width 0.06223)
			(type default)
		)
		(layer "B.Cu")
	)
	(gr_arc
		(start 159.639 -22.438106)
		(mid 159.544151 -22.428576)
		(end 159.470344 -22.488906)
		(stroke
			(width 0.06223)
			(type default)
		)
		(layer "B.Cu")
	)
	(gr_arc
		(start 159.639 -18.638012)
		(mid 159.544151 -18.628482)
		(end 159.470344 -18.688812)
		(stroke
			(width 0.06223)
			(type default)
		)
		(layer "B.Cu")
	)
	(gr_line
		(start 159.779716 -21.910802)
		(end 159.828738 -22.075902)
		(stroke
			(width 0.06223)
			(type default)
		)
		(layer "B.Cu")
	)
	(gr_line
		(start 159.779716 -21.910802)
		(end 159.999934 -21.500084)
		(stroke
			(width 0.06223)
			(type default)
		)
		(layer "B.Cu")
	)
	(gr_arc
		(start 159.779716 -18.110708)
		(mid 159.770186 -18.205557)
		(end 159.830516 -18.279364)
		(stroke
			(width 0.06223)
			(type default)
		)
		(layer "B.Cu")
	)
	(gr_line
		(start 159.779716 -18.110708)
		(end 159.999934 -17.69999)
		(stroke
			(width 0.06223)
			(type default)
		)
		(layer "B.Cu")
	)
	(gr_line
		(start 159.861758 -22.094952)
		(end 159.8803 -22.10435)
		(stroke
			(width 0.06223)
			(type default)
		)
		(layer "B.Cu")
	)
	(gr_line
		(start 159.969708 -18.352516)
		(end 160.020254 -18.377916)
		(stroke
			(width 0.06223)
			(type default)
		)
		(layer "B.Cu")
	)
	(gr_line
		(start 160.020254 -18.377916)
		(end 160.052766 -18.422874)
		(stroke
			(width 0.06223)
			(type default)
		)
		(layer "B.Cu")
	)
	(gr_line
		(start 160.35401 -18.839688)
		(end 160.405064 -18.910046)
		(stroke
			(width 0.06223)
			(type default)
		)
		(layer "B.Cu")
	)
	(gr_line
		(start 161.500058 -22.899878)
		(end 161.720276 -22.488652)
		(stroke
			(width 0.06223)
			(type default)
		)
		(layer "B.Cu")
	)
	(gr_line
		(start 161.500058 -19.100038)
		(end 161.720276 -18.688812)
		(stroke
			(width 0.06223)
			(type default)
		)
		(layer "B.Cu")
	)
	(gr_arc
		(start 161.888932 -22.437852)
		(mid 161.794083 -22.428322)
		(end 161.720276 -22.488652)
		(stroke
			(width 0.06223)
			(type default)
		)
		(layer "B.Cu")
	)
	(gr_arc
		(start 161.888932 -18.638012)
		(mid 161.794083 -18.628482)
		(end 161.720276 -18.688812)
		(stroke
			(width 0.06223)
			(type default)
		)
		(layer "B.Cu")
	)
	(gr_line
		(start 161.888932 -18.638012)
		(end 161.911284 -18.662142)
		(stroke
			(width 0.06223)
			(type default)
		)
		(layer "B.Cu")
	)
	(gr_arc
		(start 162.029902 -21.910802)
		(mid 162.020389 -22.005635)
		(end 162.080702 -22.079458)
		(stroke
			(width 0.06223)
			(type default)
		)
		(layer "B.Cu")
	)
	(gr_line
		(start 162.029902 -21.910802)
		(end 162.25012 -21.500084)
		(stroke
			(width 0.06223)
			(type default)
		)
		(layer "B.Cu")
	)
	(gr_arc
		(start 162.029902 -18.111216)
		(mid 162.020436 -18.20593)
		(end 162.080702 -18.279618)
		(stroke
			(width 0.06223)
			(type default)
		)
		(layer "B.Cu")
	)
	(gr_line
		(start 162.029902 -18.111216)
		(end 162.25012 -17.69999)
		(stroke
			(width 0.06223)
			(type default)
		)
		(layer "B.Cu")
	)
	(gr_line
		(start 162.080956 -18.279872)
		(end 162.185858 -18.36039)
		(stroke
			(width 0.06223)
			(type default)
		)
		(layer "B.Cu")
	)
	(gr_line
		(start 162.29457 -22.19325)
		(end 162.353752 -22.225)
		(stroke
			(width 0.06223)
			(type default)
		)
		(layer "B.Cu")
	)
	(gr_line
		(start 162.305492 -22.91969)
		(end 162.306254 -22.921214)
		(stroke
			(width 0.06223)
			(type default)
		)
		(layer "B.Cu")
	)
	(gr_line
		(start 162.353752 -22.225)
		(end 162.388804 -22.281642)
		(stroke
			(width 0.06223)
			(type default)
		)
		(layer "B.Cu")
	)
	(gr_line
		(start 164.018722 -22.902164)
		(end 164.105844 -22.989286)
		(stroke
			(width 0.06223)
			(type default)
		)
		(layer "B.Cu")
	)
	(gr_line
		(start 164.955474 -24.794718)
		(end 165.21938 -25.058624)
		(stroke
			(width 0.06223)
			(type default)
		)
		(layer "B.Cu")
	)
	(gr_line
		(start 164.955474 -24.417528)
		(end 164.955474 -24.794718)
		(stroke
			(width 0.06223)
			(type default)
		)
		(layer "B.Cu")
	)
	(gr_line
		(start 165.156896 -33.726374)
		(end 165.423596 -33.993074)
		(stroke
			(width 0.06223)
			(type default)
		)
		(layer "B.Cu")
	)
	(gr_line
		(start 165.156896 -33.352994)
		(end 165.156896 -33.726374)
		(stroke
			(width 0.06223)
			(type default)
		)
		(layer "B.Cu")
	)
	(gr_line
		(start 165.156896 -33.352994)
		(end 165.423596 -33.086294)
		(stroke
			(width 0.06223)
			(type default)
		)
		(layer "B.Cu")
	)
	(gr_line
		(start 165.156896 -32.441134)
		(end 165.423596 -32.707834)
		(stroke
			(width 0.06223)
			(type default)
		)
		(layer "B.Cu")
	)
	(gr_line
		(start 165.156896 -32.067754)
		(end 165.156896 -32.441134)
		(stroke
			(width 0.06223)
			(type default)
		)
		(layer "B.Cu")
	)
	(gr_line
		(start 165.156896 -32.067754)
		(end 165.423596 -31.801054)
		(stroke
			(width 0.06223)
			(type default)
		)
		(layer "B.Cu")
	)
	(gr_line
		(start 165.21938 -25.058624)
		(end 165.59657 -25.058624)
		(stroke
			(width 0.06223)
			(type default)
		)
		(layer "B.Cu")
	)
	(gr_line
		(start 165.275768 -24.159718)
		(end 165.85438 -24.73833)
		(stroke
			(width 0.06223)
			(type default)
		)
		(layer "B.Cu")
	)
	(gr_line
		(start 165.324536 -38.696138)
		(end 165.352984 -38.724586)
		(stroke
			(width 0.06223)
			(type default)
		)
		(layer "B.Cu")
	)
	(gr_line
		(start 165.324536 -38.137338)
		(end 165.352984 -38.10889)
		(stroke
			(width 0.06223)
			(type default)
		)
		(layer "B.Cu")
	)
	(gr_line
		(start 165.832536 -33.492694)
		(end 165.832536 -33.586674)
		(stroke
			(width 0.06223)
			(type default)
		)
		(layer "B.Cu")
	)
	(gr_line
		(start 165.832536 -32.207454)
		(end 165.832536 -32.301434)
		(stroke
			(width 0.06223)
			(type default)
		)
		(layer "B.Cu")
	)
	(gr_line
		(start 165.864032 -25.70353)
		(end 166.128192 -25.967436)
		(stroke
			(width 0.06223)
			(type default)
		)
		(layer "B.Cu")
	)
	(gr_line
		(start 165.864032 -25.326086)
		(end 165.864032 -25.70353)
		(stroke
			(width 0.06223)
			(type default)
		)
		(layer "B.Cu")
	)
	(gr_line
		(start 165.931088 -38.724586)
		(end 165.959536 -38.696138)
		(stroke
			(width 0.06223)
			(type default)
		)
		(layer "B.Cu")
	)
	(gr_line
		(start 165.931088 -38.10889)
		(end 165.959536 -38.137338)
		(stroke
			(width 0.06223)
			(type default)
		)
		(layer "B.Cu")
	)
	(gr_line
		(start 166.128192 -25.967436)
		(end 166.505128 -25.967436)
		(stroke
			(width 0.06223)
			(type default)
		)
		(layer "B.Cu")
	)
	(gr_line
		(start 166.18331 -25.06726)
		(end 166.763192 -25.647142)
		(stroke
			(width 0.06223)
			(type default)
		)
		(layer "B.Cu")
	)
	(gr_line
		(start 166.238428 -23.76424)
		(end 166.502334 -24.028146)
		(stroke
			(width 0.06223)
			(type default)
		)
		(layer "B.Cu")
	)
	(gr_line
		(start 166.238428 -23.38705)
		(end 166.238428 -23.76424)
		(stroke
			(width 0.06223)
			(type default)
		)
		(layer "B.Cu")
	)
	(gr_line
		(start 166.502334 -24.028146)
		(end 166.879524 -24.028146)
		(stroke
			(width 0.06223)
			(type default)
		)
		(layer "B.Cu")
	)
	(gr_line
		(start 166.508938 -25.967436)
		(end 166.66718 -26.125678)
		(stroke
			(width 0.06223)
			(type default)
		)
		(layer "B.Cu")
	)
	(gr_line
		(start 166.64559 -38.696138)
		(end 166.674038 -38.724586)
		(stroke
			(width 0.06223)
			(type default)
		)
		(layer "B.Cu")
	)
	(gr_line
		(start 166.64559 -38.137338)
		(end 166.770304 -38.011608)
		(stroke
			(width 0.06223)
			(type default)
		)
		(layer "B.Cu")
	)
	(gr_line
		(start 166.788846 -25.672796)
		(end 166.992046 -25.875996)
		(stroke
			(width 0.06223)
			(type default)
		)
		(layer "B.Cu")
	)
	(gr_line
		(start 166.815008 -23.385272)
		(end 166.881302 -23.451566)
		(stroke
			(width 0.06223)
			(type default)
		)
		(layer "B.Cu")
	)
	(gr_line
		(start 167.092122 -25.976072)
		(end 167.179244 -26.063194)
		(stroke
			(width 0.06223)
			(type default)
		)
		(layer "B.Cu")
	)
	(gr_line
		(start 167.14724 -24.673052)
		(end 167.411146 -24.936958)
		(stroke
			(width 0.06223)
			(type default)
		)
		(layer "B.Cu")
	)
	(gr_line
		(start 167.14724 -24.295862)
		(end 167.14724 -24.673052)
		(stroke
			(width 0.06223)
			(type default)
		)
		(layer "B.Cu")
	)
	(gr_line
		(start 167.180768 -38.037516)
		(end 167.28059 -38.137338)
		(stroke
			(width 0.06223)
			(type default)
		)
		(layer "B.Cu")
	)
	(gr_line
		(start 167.252142 -38.724586)
		(end 167.28059 -38.696138)
		(stroke
			(width 0.06223)
			(type default)
		)
		(layer "B.Cu")
	)
	(gr_line
		(start 167.301164 -22.699218)
		(end 167.565324 -22.963378)
		(stroke
			(width 0.06223)
			(type default)
		)
		(layer "B.Cu")
	)
	(gr_line
		(start 167.301164 -22.322028)
		(end 167.301164 -22.699218)
		(stroke
			(width 0.06223)
			(type default)
		)
		(layer "B.Cu")
	)
	(gr_line
		(start 167.411146 -24.936958)
		(end 167.788336 -24.936958)
		(stroke
			(width 0.06223)
			(type default)
		)
		(layer "B.Cu")
	)
	(gr_line
		(start 167.565324 -22.963378)
		(end 167.942514 -22.963378)
		(stroke
			(width 0.06223)
			(type default)
		)
		(layer "B.Cu")
	)
	(gr_line
		(start 167.72382 -24.294084)
		(end 167.790114 -24.360378)
		(stroke
			(width 0.06223)
			(type default)
		)
		(layer "B.Cu")
	)
	(gr_line
		(start 167.877744 -22.32025)
		(end 167.944292 -22.386798)
		(stroke
			(width 0.06223)
			(type default)
		)
		(layer "B.Cu")
	)
	(gr_line
		(start 167.966136 -38.721538)
		(end 167.994584 -38.749986)
		(stroke
			(width 0.06223)
			(type default)
		)
		(layer "B.Cu")
	)
	(gr_line
		(start 167.966136 -38.162738)
		(end 167.994584 -38.13429)
		(stroke
			(width 0.06223)
			(type default)
		)
		(layer "B.Cu")
	)
	(gr_line
		(start 168.209976 -23.60803)
		(end 168.474136 -23.87219)
		(stroke
			(width 0.06223)
			(type default)
		)
		(layer "B.Cu")
	)
	(gr_line
		(start 168.209976 -23.23084)
		(end 168.209976 -23.60803)
		(stroke
			(width 0.06223)
			(type default)
		)
		(layer "B.Cu")
	)
	(gr_line
		(start 168.474136 -23.87219)
		(end 168.851326 -23.87219)
		(stroke
			(width 0.06223)
			(type default)
		)
		(layer "B.Cu")
	)
	(gr_line
		(start 168.572688 -38.749986)
		(end 168.601136 -38.721538)
		(stroke
			(width 0.06223)
			(type default)
		)
		(layer "B.Cu")
	)
	(gr_line
		(start 168.572688 -38.13429)
		(end 168.601136 -38.162738)
		(stroke
			(width 0.06223)
			(type default)
		)
		(layer "B.Cu")
	)
	(gr_line
		(start 168.786556 -23.229062)
		(end 168.853104 -23.29561)
		(stroke
			(width 0.06223)
			(type default)
		)
		(layer "B.Cu")
	)
	(gr_line
		(start 169.33799 -38.721538)
		(end 169.366438 -38.749986)
		(stroke
			(width 0.06223)
			(type default)
		)
		(layer "B.Cu")
	)
	(gr_line
		(start 169.33799 -38.162738)
		(end 169.366438 -38.13429)
		(stroke
			(width 0.06223)
			(type default)
		)
		(layer "B.Cu")
	)
	(gr_line
		(start 169.558208 -39.383208)
		(end 169.558208 -39.383462)
		(stroke
			(width 0.06223)
			(type default)
		)
		(layer "B.Cu")
	)
	(gr_line
		(start 169.845736 -38.976808)
		(end 169.845736 -39.095934)
		(stroke
			(width 0.06223)
			(type default)
		)
		(layer "B.Cu")
	)
	(gr_line
		(start 169.887138 -39.712392)
		(end 169.966386 -39.727886)
		(stroke
			(width 0.06223)
			(type default)
		)
		(layer "B.Cu")
	)
	(gr_line
		(start 169.944542 -38.749986)
		(end 169.97299 -38.721538)
		(stroke
			(width 0.06223)
			(type default)
		)
		(layer "B.Cu")
	)
	(gr_line
		(start 169.944542 -38.13429)
		(end 169.97299 -38.162738)
		(stroke
			(width 0.06223)
			(type default)
		)
		(layer "B.Cu")
	)
	(gr_line
		(start 170.67276 -87.005922)
		(end 170.690794 -87.018114)
		(stroke
			(width 0.072898)
			(type default)
		)
		(layer "B.Cu")
	)
	(gr_line
		(start 170.690794 -87.018114)
		(end 170.71213 -87.022178)
		(stroke
			(width 0.072898)
			(type default)
		)
		(layer "B.Cu")
	)
	(gr_line
		(start 170.745658 -88.42883)
		(end 170.763692 -88.441022)
		(stroke
			(width 0.072898)
			(type default)
		)
		(layer "B.Cu")
	)
	(gr_line
		(start 170.763692 -88.441022)
		(end 170.785028 -88.445086)
		(stroke
			(width 0.072898)
			(type default)
		)
		(layer "B.Cu")
	)
	(gr_line
		(start 171.004738 -39.929816)
		(end 171.037758 -39.936166)
		(stroke
			(width 0.06223)
			(type default)
		)
		(layer "B.Cu")
	)
	(gr_line
		(start 171.037758 -39.936166)
		(end 171.070778 -39.929816)
		(stroke
			(width 0.06223)
			(type default)
		)
		(layer "B.Cu")
	)
	(gr_line
		(start 171.103798 -85.919056)
		(end 171.121832 -85.931248)
		(stroke
			(width 0.072898)
			(type default)
		)
		(layer "B.Cu")
	)
	(gr_line
		(start 171.121832 -85.931248)
		(end 171.143422 -85.935566)
		(stroke
			(width 0.072898)
			(type default)
		)
		(layer "B.Cu")
	)
	(gr_line
		(start 171.545504 -84.839302)
		(end 171.563538 -84.851494)
		(stroke
			(width 0.072898)
			(type default)
		)
		(layer "B.Cu")
	)
	(gr_line
		(start 171.563538 -84.851494)
		(end 171.584874 -84.855558)
		(stroke
			(width 0.072898)
			(type default)
		)
		(layer "B.Cu")
	)
	(gr_line
		(start 171.692062 -88.629236)
		(end 171.809664 -88.805512)
		(stroke
			(width 0.072898)
			(type default)
		)
		(layer "B.Cu")
	)
	(gr_line
		(start 171.790106 -88.329008)
		(end 172.44187 -88.459056)
		(stroke
			(width 0.072898)
			(type default)
		)
		(layer "B.Cu")
	)
	(gr_line
		(start 171.809664 -88.805512)
		(end 172.239432 -88.891618)
		(stroke
			(width 0.072898)
			(type default)
		)
		(layer "B.Cu")
	)
	(gr_line
		(start 171.979844 -83.754722)
		(end 171.997878 -83.766914)
		(stroke
			(width 0.072898)
			(type default)
		)
		(layer "B.Cu")
	)
	(gr_line
		(start 171.997878 -83.766914)
		(end 172.019214 -83.770978)
		(stroke
			(width 0.072898)
			(type default)
		)
		(layer "B.Cu")
	)
	(gr_line
		(start 172.239432 -88.891618)
		(end 172.415962 -88.774016)
		(stroke
			(width 0.072898)
			(type default)
		)
		(layer "B.Cu")
	)
	(gr_line
		(start 172.451522 -93.701616)
		(end 172.468286 -93.712538)
		(stroke
			(width 0.072898)
			(type default)
		)
		(layer "B.Cu")
	)
	(gr_line
		(start 172.468286 -93.712538)
		(end 172.468794 -93.712792)
		(stroke
			(width 0.072898)
			(type default)
		)
		(layer "B.Cu")
	)
	(gr_line
		(start 172.468794 -93.712792)
		(end 172.489114 -93.716856)
		(stroke
			(width 0.072898)
			(type default)
		)
		(layer "B.Cu")
	)
	(gr_line
		(start 172.744384 -92.51188)
		(end 172.762418 -92.523818)
		(stroke
			(width 0.072898)
			(type default)
		)
		(layer "B.Cu")
	)
	(gr_line
		(start 172.762418 -92.523818)
		(end 172.783754 -92.528136)
		(stroke
			(width 0.072898)
			(type default)
		)
		(layer "B.Cu")
	)
	(gr_line
		(start 172.850556 -88.860884)
		(end 172.967904 -89.03716)
		(stroke
			(width 0.072898)
			(type default)
		)
		(layer "B.Cu")
	)
	(gr_line
		(start 172.948346 -88.560402)
		(end 173.601126 -88.690958)
		(stroke
			(width 0.072898)
			(type default)
		)
		(layer "B.Cu")
	)
	(gr_line
		(start 172.967904 -89.03716)
		(end 173.397672 -89.123266)
		(stroke
			(width 0.072898)
			(type default)
		)
		(layer "B.Cu")
	)
	(gr_line
		(start 173.151546 -39.111682)
		(end 173.958758 -38.95471)
		(stroke
			(width 0.06223)
			(type default)
		)
		(layer "B.Cu")
	)
	(gr_line
		(start 173.177454 -91.422474)
		(end 173.195488 -91.434412)
		(stroke
			(width 0.072898)
			(type default)
		)
		(layer "B.Cu")
	)
	(gr_line
		(start 173.188376 -39.520876)
		(end 173.501304 -39.73195)
		(stroke
			(width 0.06223)
			(type default)
		)
		(layer "B.Cu")
	)
	(gr_line
		(start 173.195488 -91.434412)
		(end 173.216824 -91.43873)
		(stroke
			(width 0.072898)
			(type default)
		)
		(layer "B.Cu")
	)
	(gr_line
		(start 173.397672 -89.123266)
		(end 173.574202 -89.00541)
		(stroke
			(width 0.072898)
			(type default)
		)
		(layer "B.Cu")
	)
	(gr_line
		(start 173.501304 -39.73195)
		(end 173.867826 -39.66083)
		(stroke
			(width 0.06223)
			(type default)
		)
		(layer "B.Cu")
	)
	(gr_line
		(start 173.867826 -39.66083)
		(end 174.078646 -39.347902)
		(stroke
			(width 0.06223)
			(type default)
		)
		(layer "B.Cu")
	)
	(gr_line
		(start 174.008796 -89.092532)
		(end 174.126144 -89.268808)
		(stroke
			(width 0.072898)
			(type default)
		)
		(layer "B.Cu")
	)
	(gr_line
		(start 174.105824 -88.791796)
		(end 174.758858 -88.922352)
		(stroke
			(width 0.072898)
			(type default)
		)
		(layer "B.Cu")
	)
	(gr_line
		(start 174.126144 -89.268808)
		(end 174.555912 -89.354914)
		(stroke
			(width 0.072898)
			(type default)
		)
		(layer "B.Cu")
	)
	(gr_line
		(start 174.159164 -40.605964)
		(end 174.967392 -40.444166)
		(stroke
			(width 0.06223)
			(type default)
		)
		(layer "B.Cu")
	)
	(gr_line
		(start 174.197772 -41.015412)
		(end 174.51197 -41.224454)
		(stroke
			(width 0.06223)
			(type default)
		)
		(layer "B.Cu")
	)
	(gr_line
		(start 174.413164 -38.866572)
		(end 175.220376 -38.7096)
		(stroke
			(width 0.06223)
			(type default)
		)
		(layer "B.Cu")
	)
	(gr_line
		(start 174.449994 -39.275766)
		(end 174.762922 -39.48684)
		(stroke
			(width 0.06223)
			(type default)
		)
		(layer "B.Cu")
	)
	(gr_line
		(start 174.51197 -41.224454)
		(end 174.877984 -41.151302)
		(stroke
			(width 0.06223)
			(type default)
		)
		(layer "B.Cu")
	)
	(gr_line
		(start 174.555912 -89.354914)
		(end 174.732442 -89.237058)
		(stroke
			(width 0.072898)
			(type default)
		)
		(layer "B.Cu")
	)
	(gr_line
		(start 174.762922 -39.48684)
		(end 175.129444 -39.41572)
		(stroke
			(width 0.06223)
			(type default)
		)
		(layer "B.Cu")
	)
	(gr_line
		(start 174.877984 -41.151302)
		(end 175.087534 -40.837358)
		(stroke
			(width 0.06223)
			(type default)
		)
		(layer "B.Cu")
	)
	(gr_line
		(start 175.129444 -39.41572)
		(end 175.340264 -39.102792)
		(stroke
			(width 0.06223)
			(type default)
		)
		(layer "B.Cu")
	)
	(gr_line
		(start 175.325532 -40.78732)
		(end 175.455326 -40.761158)
		(stroke
			(width 0.06223)
			(type default)
		)
		(layer "B.Cu")
	)
	(gr_line
		(start 175.371506 -87.957152)
		(end 175.489362 -88.133682)
		(stroke
			(width 0.072898)
			(type default)
		)
		(layer "B.Cu")
	)
	(gr_line
		(start 175.371506 -40.363394)
		(end 175.379634 -40.36187)
		(stroke
			(width 0.06223)
			(type default)
		)
		(layer "B.Cu")
	)
	(gr_line
		(start 175.420782 -40.353742)
		(end 176.226724 -40.192452)
		(stroke
			(width 0.06223)
			(type default)
		)
		(layer "B.Cu")
	)
	(gr_line
		(start 175.458374 -40.76319)
		(end 175.772064 -40.972486)
		(stroke
			(width 0.06223)
			(type default)
		)
		(layer "B.Cu")
	)
	(gr_line
		(start 175.468026 -87.656416)
		(end 176.12233 -87.78748)
		(stroke
			(width 0.072898)
			(type default)
		)
		(layer "B.Cu")
	)
	(gr_line
		(start 175.489362 -88.133682)
		(end 175.918876 -88.219534)
		(stroke
			(width 0.072898)
			(type default)
		)
		(layer "B.Cu")
	)
	(gr_line
		(start 175.674782 -38.621462)
		(end 176.481994 -38.46449)
		(stroke
			(width 0.06223)
			(type default)
		)
		(layer "B.Cu")
	)
	(gr_line
		(start 175.711612 -39.030656)
		(end 176.02454 -39.24173)
		(stroke
			(width 0.06223)
			(type default)
		)
		(layer "B.Cu")
	)
	(gr_line
		(start 175.772064 -40.972486)
		(end 176.138332 -40.899334)
		(stroke
			(width 0.06223)
			(type default)
		)
		(layer "B.Cu")
	)
	(gr_line
		(start 175.918876 -88.219534)
		(end 176.09566 -88.101932)
		(stroke
			(width 0.072898)
			(type default)
		)
		(layer "B.Cu")
	)
	(gr_line
		(start 176.02454 -39.24173)
		(end 176.391062 -39.17061)
		(stroke
			(width 0.06223)
			(type default)
		)
		(layer "B.Cu")
	)
	(gr_line
		(start 176.138332 -40.899334)
		(end 176.347628 -40.58539)
		(stroke
			(width 0.06223)
			(type default)
		)
		(layer "B.Cu")
	)
	(gr_line
		(start 176.391062 -39.17061)
		(end 176.601882 -38.857936)
		(stroke
			(width 0.06223)
			(type default)
		)
		(layer "B.Cu")
	)
	(gr_line
		(start 176.529746 -88.1888)
		(end 176.647602 -88.36533)
		(stroke
			(width 0.072898)
			(type default)
		)
		(layer "B.Cu")
	)
	(gr_line
		(start 176.627282 -87.888318)
		(end 177.279808 -88.018874)
		(stroke
			(width 0.072898)
			(type default)
		)
		(layer "B.Cu")
	)
	(gr_line
		(start 176.635664 -40.110664)
		(end 176.643538 -40.10914)
		(stroke
			(width 0.06223)
			(type default)
		)
		(layer "B.Cu")
	)
	(gr_line
		(start 176.647602 -88.36533)
		(end 177.07737 -88.451182)
		(stroke
			(width 0.072898)
			(type default)
		)
		(layer "B.Cu")
	)
	(gr_line
		(start 176.680876 -40.101774)
		(end 177.484532 -39.940992)
		(stroke
			(width 0.06223)
			(type default)
		)
		(layer "B.Cu")
	)
	(gr_line
		(start 176.69891 -40.512492)
		(end 176.715674 -40.50919)
		(stroke
			(width 0.06223)
			(type default)
		)
		(layer "B.Cu")
	)
	(gr_line
		(start 176.718722 -40.511222)
		(end 177.032412 -40.720518)
		(stroke
			(width 0.06223)
			(type default)
		)
		(layer "B.Cu")
	)
	(gr_line
		(start 176.937416 -38.376098)
		(end 177.745136 -38.219126)
		(stroke
			(width 0.06223)
			(type default)
		)
		(layer "B.Cu")
	)
	(gr_line
		(start 176.97323 -38.7858)
		(end 177.286158 -38.996874)
		(stroke
			(width 0.06223)
			(type default)
		)
		(layer "B.Cu")
	)
	(gr_line
		(start 177.032412 -40.720518)
		(end 177.39868 -40.647366)
		(stroke
			(width 0.06223)
			(type default)
		)
		(layer "B.Cu")
	)
	(gr_line
		(start 177.07737 -88.451182)
		(end 177.2539 -88.33358)
		(stroke
			(width 0.072898)
			(type default)
		)
		(layer "B.Cu")
	)
	(gr_line
		(start 177.286158 -38.996874)
		(end 177.65268 -38.9255)
		(stroke
			(width 0.06223)
			(type default)
		)
		(layer "B.Cu")
	)
	(gr_line
		(start 177.39868 -40.647366)
		(end 177.607722 -40.333422)
		(stroke
			(width 0.06223)
			(type default)
		)
		(layer "B.Cu")
	)
	(gr_line
		(start 177.525172 -39.932864)
		(end 177.535078 -39.930832)
		(stroke
			(width 0.06223)
			(type default)
		)
		(layer "B.Cu")
	)
	(gr_line
		(start 177.65268 -38.9255)
		(end 177.863754 -38.612826)
		(stroke
			(width 0.06223)
			(type default)
		)
		(layer "B.Cu")
	)
	(gr_line
		(start 177.68824 -88.420448)
		(end 177.805842 -88.596978)
		(stroke
			(width 0.072898)
			(type default)
		)
		(layer "B.Cu")
	)
	(gr_line
		(start 177.785776 -88.12022)
		(end 178.43754 -88.250522)
		(stroke
			(width 0.072898)
			(type default)
		)
		(layer "B.Cu")
	)
	(gr_line
		(start 177.805842 -88.596978)
		(end 178.235356 -88.683084)
		(stroke
			(width 0.072898)
			(type default)
		)
		(layer "B.Cu")
	)
	(gr_line
		(start 178.235356 -88.683084)
		(end 178.411886 -88.565228)
		(stroke
			(width 0.072898)
			(type default)
		)
		(layer "B.Cu")
	)
	(gr_line
		(start 178.84648 -88.65235)
		(end 178.963828 -88.82888)
		(stroke
			(width 0.072898)
			(type default)
		)
		(layer "B.Cu")
	)
	(gr_line
		(start 178.946048 -88.35263)
		(end 179.59324 -88.48217)
		(stroke
			(width 0.072898)
			(type default)
		)
		(layer "B.Cu")
	)
	(gr_line
		(start 178.963828 -88.82888)
		(end 179.393596 -88.914732)
		(stroke
			(width 0.072898)
			(type default)
		)
		(layer "B.Cu")
	)
	(gr_line
		(start 179.250086 -22.899878)
		(end 179.470304 -22.488906)
		(stroke
			(width 0.06223)
			(type default)
		)
		(layer "B.Cu")
	)
	(gr_line
		(start 179.250086 -19.100038)
		(end 179.470304 -18.688812)
		(stroke
			(width 0.06223)
			(type default)
		)
		(layer "B.Cu")
	)
	(gr_line
		(start 179.393596 -88.914732)
		(end 179.570126 -88.79713)
		(stroke
			(width 0.072898)
			(type default)
		)
		(layer "B.Cu")
	)
	(gr_arc
		(start 179.63896 -22.438106)
		(mid 179.544111 -22.428576)
		(end 179.470304 -22.488906)
		(stroke
			(width 0.06223)
			(type default)
		)
		(layer "B.Cu")
	)
	(gr_arc
		(start 179.63896 -18.638012)
		(mid 179.544111 -18.628482)
		(end 179.470304 -18.688812)
		(stroke
			(width 0.06223)
			(type default)
		)
		(layer "B.Cu")
	)
	(gr_line
		(start 179.660296 -41.155112)
		(end 180.46573 -40.994076)
		(stroke
			(width 0.06223)
			(type default)
		)
		(layer "B.Cu")
	)
	(gr_line
		(start 179.698904 -41.564306)
		(end 180.012848 -41.773856)
		(stroke
			(width 0.06223)
			(type default)
		)
		(layer "B.Cu")
	)
	(gr_line
		(start 179.779676 -21.910802)
		(end 179.828698 -22.075902)
		(stroke
			(width 0.06223)
			(type default)
		)
		(layer "B.Cu")
	)
	(gr_line
		(start 179.779676 -21.910802)
		(end 179.999894 -21.500084)
		(stroke
			(width 0.06223)
			(type default)
		)
		(layer "B.Cu")
	)
	(gr_arc
		(start 179.779676 -18.110708)
		(mid 179.770169 -18.205539)
		(end 179.830476 -18.279364)
		(stroke
			(width 0.06223)
			(type default)
		)
		(layer "B.Cu")
	)
	(gr_line
		(start 179.779676 -18.110708)
		(end 179.999894 -17.69999)
		(stroke
			(width 0.06223)
			(type default)
		)
		(layer "B.Cu")
	)
	(gr_line
		(start 179.861718 -22.094952)
		(end 179.88026 -22.10435)
		(stroke
			(width 0.06223)
			(type default)
		)
		(layer "B.Cu")
	)
	(gr_line
		(start 179.969668 -18.352516)
		(end 180.020214 -18.377916)
		(stroke
			(width 0.06223)
			(type default)
		)
		(layer "B.Cu")
	)
	(gr_line
		(start 180.004212 -88.883998)
		(end 180.122068 -89.060528)
		(stroke
			(width 0.072898)
			(type default)
		)
		(layer "B.Cu")
	)
	(gr_line
		(start 180.012848 -41.773856)
		(end 180.378862 -41.70045)
		(stroke
			(width 0.06223)
			(type default)
		)
		(layer "B.Cu")
	)
	(gr_line
		(start 180.020214 -18.377916)
		(end 180.053742 -18.42389)
		(stroke
			(width 0.06223)
			(type default)
		)
		(layer "B.Cu")
	)
	(gr_line
		(start 180.102256 -88.58377)
		(end 180.754782 -88.714072)
		(stroke
			(width 0.072898)
			(type default)
		)
		(layer "B.Cu")
	)
	(gr_line
		(start 180.122068 -89.060528)
		(end 180.551582 -89.14638)
		(stroke
			(width 0.072898)
			(type default)
		)
		(layer "B.Cu")
	)
	(gr_line
		(start 180.135276 -90.317574)
		(end 180.252878 -90.49385)
		(stroke
			(width 0.072898)
			(type default)
		)
		(layer "B.Cu")
	)
	(gr_line
		(start 180.233066 -90.017092)
		(end 180.884576 -90.147394)
		(stroke
			(width 0.072898)
			(type default)
		)
		(layer "B.Cu")
	)
	(gr_line
		(start 180.252878 -90.49385)
		(end 180.682392 -90.579702)
		(stroke
			(width 0.072898)
			(type default)
		)
		(layer "B.Cu")
	)
	(gr_line
		(start 180.354732 -18.840704)
		(end 180.405024 -18.9103)
		(stroke
			(width 0.06223)
			(type default)
		)
		(layer "B.Cu")
	)
	(gr_line
		(start 180.378862 -41.70045)
		(end 180.588158 -41.38676)
		(stroke
			(width 0.06223)
			(type default)
		)
		(layer "B.Cu")
	)
	(gr_line
		(start 180.503068 -40.98671)
		(end 180.645308 -40.958262)
		(stroke
			(width 0.06223)
			(type default)
		)
		(layer "B.Cu")
	)
	(gr_line
		(start 180.525674 -85.473032)
		(end 180.549042 -85.477604)
		(stroke
			(width 0.072898)
			(type default)
		)
		(layer "B.Cu")
	)
	(gr_line
		(start 180.530754 -86.645496)
		(end 180.554122 -86.650068)
		(stroke
			(width 0.072898)
			(type default)
		)
		(layer "B.Cu")
	)
	(gr_line
		(start 180.549042 -85.477604)
		(end 180.57241 -85.473032)
		(stroke
			(width 0.072898)
			(type default)
		)
		(layer "B.Cu")
	)
	(gr_line
		(start 180.551582 -89.14638)
		(end 180.728366 -89.028778)
		(stroke
			(width 0.072898)
			(type default)
		)
		(layer "B.Cu")
	)
	(gr_line
		(start 180.554122 -86.650068)
		(end 180.57749 -86.645496)
		(stroke
			(width 0.072898)
			(type default)
		)
		(layer "B.Cu")
	)
	(gr_line
		(start 180.59019 -41.383712)
		(end 180.725064 -41.356788)
		(stroke
			(width 0.06223)
			(type default)
		)
		(layer "B.Cu")
	)
	(gr_line
		(start 180.682392 -90.579702)
		(end 180.858922 -90.4621)
		(stroke
			(width 0.072898)
			(type default)
		)
		(layer "B.Cu")
	)
	(gr_line
		(start 180.92166 -40.903144)
		(end 181.727094 -40.742108)
		(stroke
			(width 0.06223)
			(type default)
		)
		(layer "B.Cu")
	)
	(gr_line
		(start 180.93182 -87.893398)
		(end 180.953664 -87.897716)
		(stroke
			(width 0.072898)
			(type default)
		)
		(layer "B.Cu")
	)
	(gr_line
		(start 180.953664 -87.897716)
		(end 180.975254 -87.893398)
		(stroke
			(width 0.072898)
			(type default)
		)
		(layer "B.Cu")
	)
	(gr_line
		(start 180.959506 -41.312592)
		(end 181.273196 -41.521888)
		(stroke
			(width 0.06223)
			(type default)
		)
		(layer "B.Cu")
	)
	(gr_line
		(start 181.137306 -89.10828)
		(end 181.160674 -89.112852)
		(stroke
			(width 0.072898)
			(type default)
		)
		(layer "B.Cu")
	)
	(gr_line
		(start 181.160674 -89.112852)
		(end 181.184042 -89.10828)
		(stroke
			(width 0.072898)
			(type default)
		)
		(layer "B.Cu")
	)
	(gr_line
		(start 181.273196 -41.521888)
		(end 181.63921 -41.448736)
		(stroke
			(width 0.06223)
			(type default)
		)
		(layer "B.Cu")
	)
	(gr_line
		(start 181.293516 -90.548968)
		(end 181.411118 -90.725498)
		(stroke
			(width 0.072898)
			(type default)
		)
		(layer "B.Cu")
	)
	(gr_line
		(start 181.39156 -90.24874)
		(end 182.043832 -90.379296)
		(stroke
			(width 0.072898)
			(type default)
		)
		(layer "B.Cu")
	)
	(gr_line
		(start 181.411118 -90.725498)
		(end 181.840632 -90.81135)
		(stroke
			(width 0.072898)
			(type default)
		)
		(layer "B.Cu")
	)
	(gr_line
		(start 181.500018 -22.899878)
		(end 181.720236 -22.488652)
		(stroke
			(width 0.06223)
			(type default)
		)
		(layer "B.Cu")
	)
	(gr_line
		(start 181.500018 -19.100038)
		(end 181.720236 -18.688812)
		(stroke
			(width 0.06223)
			(type default)
		)
		(layer "B.Cu")
	)
	(gr_line
		(start 181.63921 -41.448736)
		(end 181.84876 -41.134792)
		(stroke
			(width 0.06223)
			(type default)
		)
		(layer "B.Cu")
	)
	(gr_line
		(start 181.749446 -42.26814)
		(end 182.555388 -42.111676)
		(stroke
			(width 0.06223)
			(type default)
		)
		(layer "B.Cu")
	)
	(gr_line
		(start 181.785768 -42.677842)
		(end 182.098696 -42.888662)
		(stroke
			(width 0.06223)
			(type default)
		)
		(layer "B.Cu")
	)
	(gr_line
		(start 181.840632 -90.81135)
		(end 182.017162 -90.693748)
		(stroke
			(width 0.072898)
			(type default)
		)
		(layer "B.Cu")
	)
	(gr_arc
		(start 181.888892 -22.437852)
		(mid 181.794059 -22.428347)
		(end 181.720236 -22.488652)
		(stroke
			(width 0.06223)
			(type default)
		)
		(layer "B.Cu")
	)
	(gr_line
		(start 181.888892 -22.437852)
		(end 181.890416 -22.438868)
		(stroke
			(width 0.06223)
			(type default)
		)
		(layer "B.Cu")
	)
	(gr_arc
		(start 181.888892 -18.638012)
		(mid 181.794043 -18.628482)
		(end 181.720236 -18.688812)
		(stroke
			(width 0.06223)
			(type default)
		)
		(layer "B.Cu")
	)
	(gr_line
		(start 181.888892 -18.638012)
		(end 181.911244 -18.662142)
		(stroke
			(width 0.06223)
			(type default)
		)
		(layer "B.Cu")
	)
	(gr_arc
		(start 182.029862 -21.910802)
		(mid 182.020332 -22.005651)
		(end 182.080662 -22.079458)
		(stroke
			(width 0.06223)
			(type default)
		)
		(layer "B.Cu")
	)
	(gr_line
		(start 182.029862 -21.910802)
		(end 182.25008 -21.500084)
		(stroke
			(width 0.06223)
			(type default)
		)
		(layer "B.Cu")
	)
	(gr_arc
		(start 182.029862 -18.111216)
		(mid 182.02039 -18.205926)
		(end 182.080662 -18.279618)
		(stroke
			(width 0.06223)
			(type default)
		)
		(layer "B.Cu")
	)
	(gr_line
		(start 182.029862 -18.111216)
		(end 182.25008 -17.69999)
		(stroke
			(width 0.06223)
			(type default)
		)
		(layer "B.Cu")
	)
	(gr_line
		(start 182.080916 -18.279872)
		(end 182.185818 -18.36039)
		(stroke
			(width 0.06223)
			(type default)
		)
		(layer "B.Cu")
	)
	(gr_line
		(start 182.093616 -22.086062)
		(end 182.094378 -22.08657)
		(stroke
			(width 0.06223)
			(type default)
		)
		(layer "B.Cu")
	)
	(gr_line
		(start 182.098696 -42.888662)
		(end 182.465218 -42.817542)
		(stroke
			(width 0.06223)
			(type default)
		)
		(layer "B.Cu")
	)
	(gr_line
		(start 182.180484 -40.65143)
		(end 182.98541 -40.490648)
		(stroke
			(width 0.06223)
			(type default)
		)
		(layer "B.Cu")
	)
	(gr_line
		(start 182.219346 -41.060624)
		(end 182.533544 -41.26992)
		(stroke
			(width 0.06223)
			(type default)
		)
		(layer "B.Cu")
	)
	(gr_line
		(start 182.297578 -22.195282)
		(end 182.353712 -22.225)
		(stroke
			(width 0.06223)
			(type default)
		)
		(layer "B.Cu")
	)
	(gr_line
		(start 182.353712 -22.225)
		(end 182.387494 -22.279864)
		(stroke
			(width 0.06223)
			(type default)
		)
		(layer "B.Cu")
	)
	(gr_line
		(start 182.4355 -23.13051)
		(end 182.531004 -23.284688)
		(stroke
			(width 0.06223)
			(type default)
		)
		(layer "B.Cu")
	)
	(gr_line
		(start 182.451756 -90.780616)
		(end 182.569358 -90.957146)
		(stroke
			(width 0.072898)
			(type default)
		)
		(layer "B.Cu")
	)
	(gr_line
		(start 182.465218 -42.817542)
		(end 182.676038 -42.504614)
		(stroke
			(width 0.06223)
			(type default)
		)
		(layer "B.Cu")
	)
	(gr_line
		(start 182.533544 -41.26992)
		(end 182.899558 -41.196768)
		(stroke
			(width 0.06223)
			(type default)
		)
		(layer "B.Cu")
	)
	(gr_line
		(start 182.548784 -90.480134)
		(end 183.201564 -90.61069)
		(stroke
			(width 0.072898)
			(type default)
		)
		(layer "B.Cu")
	)
	(gr_line
		(start 182.569358 -90.957146)
		(end 182.998872 -91.042998)
		(stroke
			(width 0.072898)
			(type default)
		)
		(layer "B.Cu")
	)
	(gr_line
		(start 182.82539 -37.232336)
		(end 183.633618 -37.075364)
		(stroke
			(width 0.06223)
			(type default)
		)
		(layer "B.Cu")
	)
	(gr_line
		(start 182.861712 -37.641784)
		(end 183.17464 -37.853112)
		(stroke
			(width 0.06223)
			(type default)
		)
		(layer "B.Cu")
	)
	(gr_line
		(start 182.899558 -41.196768)
		(end 183.108854 -40.883078)
		(stroke
			(width 0.06223)
			(type default)
		)
		(layer "B.Cu")
	)
	(gr_line
		(start 182.998872 -91.042998)
		(end 183.175402 -90.925396)
		(stroke
			(width 0.072898)
			(type default)
		)
		(layer "B.Cu")
	)
	(gr_line
		(start 183.011064 -42.02303)
		(end 183.817006 -41.866566)
		(stroke
			(width 0.06223)
			(type default)
		)
		(layer "B.Cu")
	)
	(gr_line
		(start 183.047386 -42.432478)
		(end 183.360314 -42.643552)
		(stroke
			(width 0.06223)
			(type default)
		)
		(layer "B.Cu")
	)
	(gr_line
		(start 183.17464 -37.853112)
		(end 183.541162 -37.781738)
		(stroke
			(width 0.06223)
			(type default)
		)
		(layer "B.Cu")
	)
	(gr_line
		(start 183.35879 -93.467428)
		(end 183.382158 -93.472)
		(stroke
			(width 0.072898)
			(type default)
		)
		(layer "B.Cu")
	)
	(gr_line
		(start 183.360314 -42.643552)
		(end 183.726836 -42.572432)
		(stroke
			(width 0.06223)
			(type default)
		)
		(layer "B.Cu")
	)
	(gr_line
		(start 183.382158 -93.472)
		(end 183.405526 -93.467428)
		(stroke
			(width 0.072898)
			(type default)
		)
		(layer "B.Cu")
	)
	(gr_line
		(start 183.44134 -40.399462)
		(end 184.248552 -40.238172)
		(stroke
			(width 0.06223)
			(type default)
		)
		(layer "B.Cu")
	)
	(gr_line
		(start 183.462676 -94.664022)
		(end 183.486044 -94.668594)
		(stroke
			(width 0.072898)
			(type default)
		)
		(layer "B.Cu")
	)
	(gr_line
		(start 183.479948 -40.80891)
		(end 183.793638 -41.018206)
		(stroke
			(width 0.06223)
			(type default)
		)
		(layer "B.Cu")
	)
	(gr_line
		(start 183.486044 -94.668594)
		(end 183.509158 -94.664022)
		(stroke
			(width 0.072898)
			(type default)
		)
		(layer "B.Cu")
	)
	(gr_line
		(start 183.541162 -37.781738)
		(end 183.752236 -37.46881)
		(stroke
			(width 0.06223)
			(type default)
		)
		(layer "B.Cu")
	)
	(gr_line
		(start 183.609742 -91.012264)
		(end 183.727598 -91.188794)
		(stroke
			(width 0.072898)
			(type default)
		)
		(layer "B.Cu")
	)
	(gr_line
		(start 183.707786 -90.712036)
		(end 184.360566 -90.842592)
		(stroke
			(width 0.072898)
			(type default)
		)
		(layer "B.Cu")
	)
	(gr_line
		(start 183.726836 -42.572432)
		(end 183.937656 -42.259504)
		(stroke
			(width 0.06223)
			(type default)
		)
		(layer "B.Cu")
	)
	(gr_line
		(start 183.727598 -91.188794)
		(end 184.157112 -91.274646)
		(stroke
			(width 0.072898)
			(type default)
		)
		(layer "B.Cu")
	)
	(gr_line
		(start 183.778652 -95.97517)
		(end 183.80202 -95.979742)
		(stroke
			(width 0.072898)
			(type default)
		)
		(layer "B.Cu")
	)
	(gr_line
		(start 183.793638 -41.018206)
		(end 184.159906 -40.945054)
		(stroke
			(width 0.06223)
			(type default)
		)
		(layer "B.Cu")
	)
	(gr_line
		(start 183.80202 -95.979742)
		(end 183.825388 -95.97517)
		(stroke
			(width 0.072898)
			(type default)
		)
		(layer "B.Cu")
	)
	(gr_line
		(start 184.087262 -36.987226)
		(end 184.895744 -36.830254)
		(stroke
			(width 0.06223)
			(type default)
		)
		(layer "B.Cu")
	)
	(gr_line
		(start 184.08904 -42.227754)
		(end 184.30621 -42.185336)
		(stroke
			(width 0.06223)
			(type default)
		)
		(layer "B.Cu")
	)
	(gr_line
		(start 184.12333 -37.396674)
		(end 184.436258 -37.608002)
		(stroke
			(width 0.06223)
			(type default)
		)
		(layer "B.Cu")
	)
	(gr_line
		(start 184.157112 -91.274646)
		(end 184.333642 -91.157044)
		(stroke
			(width 0.072898)
			(type default)
		)
		(layer "B.Cu")
	)
	(gr_line
		(start 184.159906 -40.945054)
		(end 184.369456 -40.63111)
		(stroke
			(width 0.06223)
			(type default)
		)
		(layer "B.Cu")
	)
	(gr_line
		(start 184.196482 -41.792652)
		(end 184.237376 -41.784778)
		(stroke
			(width 0.06223)
			(type default)
		)
		(layer "B.Cu")
	)
	(gr_line
		(start 184.27573 -41.777412)
		(end 185.079132 -41.621456)
		(stroke
			(width 0.06223)
			(type default)
		)
		(layer "B.Cu")
	)
	(gr_line
		(start 184.309258 -42.187368)
		(end 184.621932 -42.398442)
		(stroke
			(width 0.06223)
			(type default)
		)
		(layer "B.Cu")
	)
	(gr_line
		(start 184.436258 -37.608002)
		(end 184.80278 -37.536628)
		(stroke
			(width 0.06223)
			(type default)
		)
		(layer "B.Cu")
	)
	(gr_line
		(start 184.467246 -94.154752)
		(end 185.123836 -94.023434)
		(stroke
			(width 0.072898)
			(type default)
		)
		(layer "B.Cu")
	)
	(gr_line
		(start 184.49544 -94.469204)
		(end 184.672224 -94.586806)
		(stroke
			(width 0.072898)
			(type default)
		)
		(layer "B.Cu")
	)
	(gr_line
		(start 184.621932 -42.398442)
		(end 184.988454 -42.327068)
		(stroke
			(width 0.06223)
			(type default)
		)
		(layer "B.Cu")
	)
	(gr_line
		(start 184.672224 -94.586806)
		(end 185.101992 -94.500954)
		(stroke
			(width 0.072898)
			(type default)
		)
		(layer "B.Cu")
	)
	(gr_line
		(start 184.705752 -88.086184)
		(end 185.35904 -87.955374)
		(stroke
			(width 0.072898)
			(type default)
		)
		(layer "B.Cu")
	)
	(gr_line
		(start 184.73166 -88.40089)
		(end 184.90819 -88.518492)
		(stroke
			(width 0.072898)
			(type default)
		)
		(layer "B.Cu")
	)
	(gr_line
		(start 184.742836 -91.236546)
		(end 184.766204 -91.241118)
		(stroke
			(width 0.072898)
			(type default)
		)
		(layer "B.Cu")
	)
	(gr_line
		(start 184.766204 -91.241118)
		(end 184.789572 -91.236546)
		(stroke
			(width 0.072898)
			(type default)
		)
		(layer "B.Cu")
	)
	(gr_line
		(start 184.80278 -37.536628)
		(end 185.013854 -37.2237)
		(stroke
			(width 0.06223)
			(type default)
		)
		(layer "B.Cu")
	)
	(gr_line
		(start 184.90819 -88.518492)
		(end 185.337958 -88.43264)
		(stroke
			(width 0.072898)
			(type default)
		)
		(layer "B.Cu")
	)
	(gr_line
		(start 184.988454 -42.327068)
		(end 185.199274 -42.014394)
		(stroke
			(width 0.06223)
			(type default)
		)
		(layer "B.Cu")
	)
	(gr_line
		(start 185.101992 -94.500954)
		(end 185.219594 -94.324424)
		(stroke
			(width 0.072898)
			(type default)
		)
		(layer "B.Cu")
	)
	(gr_line
		(start 185.337958 -88.43264)
		(end 185.455814 -88.25611)
		(stroke
			(width 0.072898)
			(type default)
		)
		(layer "B.Cu")
	)
	(gr_line
		(start 185.347356 -36.74237)
		(end 186.157616 -36.58489)
		(stroke
			(width 0.06223)
			(type default)
		)
		(layer "B.Cu")
	)
	(gr_line
		(start 185.384948 -37.151564)
		(end 185.697876 -37.362892)
		(stroke
			(width 0.06223)
			(type default)
		)
		(layer "B.Cu")
	)
	(gr_line
		(start 185.494422 -84.488782)
		(end 185.516012 -84.484464)
		(stroke
			(width 0.072898)
			(type default)
		)
		(layer "B.Cu")
	)
	(gr_line
		(start 185.516012 -84.484464)
		(end 185.534046 -84.472272)
		(stroke
			(width 0.072898)
			(type default)
		)
		(layer "B.Cu")
	)
	(gr_line
		(start 185.625486 -93.923104)
		(end 186.282076 -93.791786)
		(stroke
			(width 0.072898)
			(type default)
		)
		(layer "B.Cu")
	)
	(gr_line
		(start 185.653934 -94.237556)
		(end 185.830464 -94.355158)
		(stroke
			(width 0.072898)
			(type default)
		)
		(layer "B.Cu")
	)
	(gr_line
		(start 185.697876 -37.362892)
		(end 186.064398 -37.291518)
		(stroke
			(width 0.06223)
			(type default)
		)
		(layer "B.Cu")
	)
	(gr_line
		(start 185.712354 -90.734388)
		(end 186.365134 -90.603832)
		(stroke
			(width 0.072898)
			(type default)
		)
		(layer "B.Cu")
	)
	(gr_line
		(start 185.738516 -91.049094)
		(end 185.915046 -91.166696)
		(stroke
			(width 0.072898)
			(type default)
		)
		(layer "B.Cu")
	)
	(gr_line
		(start 185.830464 -94.355158)
		(end 186.260232 -94.269306)
		(stroke
			(width 0.072898)
			(type default)
		)
		(layer "B.Cu")
	)
	(gr_line
		(start 185.863738 -87.854536)
		(end 186.51601 -87.724234)
		(stroke
			(width 0.072898)
			(type default)
		)
		(layer "B.Cu")
	)
	(gr_line
		(start 185.8899 -88.169242)
		(end 186.06643 -88.286844)
		(stroke
			(width 0.072898)
			(type default)
		)
		(layer "B.Cu")
	)
	(gr_line
		(start 185.915046 -91.166696)
		(end 186.344814 -91.080844)
		(stroke
			(width 0.072898)
			(type default)
		)
		(layer "B.Cu")
	)
	(gr_line
		(start 186.064398 -37.291518)
		(end 186.275218 -36.978844)
		(stroke
			(width 0.06223)
			(type default)
		)
		(layer "B.Cu")
	)
	(gr_line
		(start 186.06643 -88.286844)
		(end 186.496198 -88.200992)
		(stroke
			(width 0.072898)
			(type default)
		)
		(layer "B.Cu")
	)
	(gr_line
		(start 186.260232 -94.269306)
		(end 186.377834 -94.092776)
		(stroke
			(width 0.072898)
			(type default)
		)
		(layer "B.Cu")
	)
	(gr_line
		(start 186.304428 -85.499956)
		(end 186.322208 -85.488018)
		(stroke
			(width 0.072898)
			(type default)
		)
		(layer "B.Cu")
	)
	(gr_line
		(start 186.344814 -91.080844)
		(end 186.462162 -90.904314)
		(stroke
			(width 0.072898)
			(type default)
		)
		(layer "B.Cu")
	)
	(gr_line
		(start 186.496198 -88.200992)
		(end 186.6138 -88.024462)
		(stroke
			(width 0.072898)
			(type default)
		)
		(layer "B.Cu")
	)
	(gr_line
		(start 186.785504 -93.691456)
		(end 187.438792 -93.560646)
		(stroke
			(width 0.072898)
			(type default)
		)
		(layer "B.Cu")
	)
	(gr_line
		(start 186.812174 -94.005908)
		(end 186.988704 -94.12351)
		(stroke
			(width 0.072898)
			(type default)
		)
		(layer "B.Cu")
	)
	(gr_line
		(start 186.870848 -90.50274)
		(end 187.522358 -90.372438)
		(stroke
			(width 0.072898)
			(type default)
		)
		(layer "B.Cu")
	)
	(gr_line
		(start 186.896756 -90.817446)
		(end 187.073286 -90.935048)
		(stroke
			(width 0.072898)
			(type default)
		)
		(layer "B.Cu")
	)
	(gr_line
		(start 186.988704 -94.12351)
		(end 187.418472 -94.037658)
		(stroke
			(width 0.072898)
			(type default)
		)
		(layer "B.Cu")
	)
	(gr_line
		(start 187.02401 -87.622634)
		(end 187.674504 -87.492332)
		(stroke
			(width 0.072898)
			(type default)
		)
		(layer "B.Cu")
	)
	(gr_line
		(start 187.048394 -87.937594)
		(end 187.22467 -88.055196)
		(stroke
			(width 0.072898)
			(type default)
		)
		(layer "B.Cu")
	)
	(gr_line
		(start 187.073286 -90.935048)
		(end 187.503054 -90.849196)
		(stroke
			(width 0.072898)
			(type default)
		)
		(layer "B.Cu")
	)
	(gr_line
		(start 187.22467 -88.055196)
		(end 187.654184 -87.969344)
		(stroke
			(width 0.072898)
			(type default)
		)
		(layer "B.Cu")
	)
	(gr_line
		(start 187.418472 -94.037658)
		(end 187.53582 -93.861128)
		(stroke
			(width 0.072898)
			(type default)
		)
		(layer "B.Cu")
	)
	(gr_line
		(start 187.437014 -92.661232)
		(end 187.458604 -92.656914)
		(stroke
			(width 0.072898)
			(type default)
		)
		(layer "B.Cu")
	)
	(gr_line
		(start 187.439554 -25.388062)
		(end 187.706254 -25.121362)
		(stroke
			(width 0.06223)
			(type default)
		)
		(layer "B.Cu")
	)
	(gr_line
		(start 187.458604 -92.656914)
		(end 187.476638 -92.644722)
		(stroke
			(width 0.072898)
			(type default)
		)
		(layer "B.Cu")
	)
	(gr_line
		(start 187.503054 -90.849196)
		(end 187.620402 -90.67292)
		(stroke
			(width 0.072898)
			(type default)
		)
		(layer "B.Cu")
	)
	(gr_line
		(start 187.654184 -87.969344)
		(end 187.77204 -87.792814)
		(stroke
			(width 0.072898)
			(type default)
		)
		(layer "B.Cu")
	)
	(gr_line
		(start 187.706254 -25.121362)
		(end 188.079634 -25.121362)
		(stroke
			(width 0.06223)
			(type default)
		)
		(layer "B.Cu")
	)
	(gr_line
		(start 187.845954 -25.797002)
		(end 187.939934 -25.797002)
		(stroke
			(width 0.06223)
			(type default)
		)
		(layer "B.Cu")
	)
	(gr_line
		(start 187.918598 -36.243006)
		(end 187.953142 -36.236402)
		(stroke
			(width 0.06223)
			(type default)
		)
		(layer "B.Cu")
	)
	(gr_line
		(start 187.944506 -93.459554)
		(end 188.596016 -93.329252)
		(stroke
			(width 0.072898)
			(type default)
		)
		(layer "B.Cu")
	)
	(gr_line
		(start 187.953142 -36.236402)
		(end 187.987432 -36.24326)
		(stroke
			(width 0.06223)
			(type default)
		)
		(layer "B.Cu")
	)
	(gr_line
		(start 187.970414 -93.77426)
		(end 188.146944 -93.891862)
		(stroke
			(width 0.072898)
			(type default)
		)
		(layer "B.Cu")
	)
	(gr_line
		(start 187.989718 -81.4324)
		(end 188.047376 -81.490058)
		(stroke
			(width 0.072898)
			(type default)
		)
		(layer "B.Cu")
	)
	(gr_line
		(start 187.989718 -80.8736)
		(end 188.047376 -80.815942)
		(stroke
			(width 0.072898)
			(type default)
		)
		(layer "B.Cu")
	)
	(gr_line
		(start 188.030612 -90.588338)
		(end 188.052202 -90.58402)
		(stroke
			(width 0.072898)
			(type default)
		)
		(layer "B.Cu")
	)
	(gr_line
		(start 188.052202 -90.58402)
		(end 188.070236 -90.571828)
		(stroke
			(width 0.072898)
			(type default)
		)
		(layer "B.Cu")
	)
	(gr_line
		(start 188.079634 -25.121362)
		(end 188.346334 -25.388062)
		(stroke
			(width 0.06223)
			(type default)
		)
		(layer "B.Cu")
	)
	(gr_line
		(start 188.086238 -23.36546)
		(end 188.352938 -23.09876)
		(stroke
			(width 0.06223)
			(type default)
		)
		(layer "B.Cu")
	)
	(gr_line
		(start 188.099954 -91.855036)
		(end 188.654182 -91.485466)
		(stroke
			(width 0.072898)
			(type default)
		)
		(layer "B.Cu")
	)
	(gr_line
		(start 188.146944 -93.891862)
		(end 188.576712 -93.80601)
		(stroke
			(width 0.072898)
			(type default)
		)
		(layer "B.Cu")
	)
	(gr_line
		(start 188.181234 -87.390986)
		(end 188.831982 -87.260684)
		(stroke
			(width 0.072898)
			(type default)
		)
		(layer "B.Cu")
	)
	(gr_line
		(start 188.20638 -87.705946)
		(end 188.382656 -87.823548)
		(stroke
			(width 0.072898)
			(type default)
		)
		(layer "B.Cu")
	)
	(gr_line
		(start 188.243972 -92.136214)
		(end 188.451998 -92.177616)
		(stroke
			(width 0.072898)
			(type default)
		)
		(layer "B.Cu")
	)
	(gr_line
		(start 188.352938 -23.09876)
		(end 188.726318 -23.09876)
		(stroke
			(width 0.06223)
			(type default)
		)
		(layer "B.Cu")
	)
	(gr_line
		(start 188.364622 -82.292952)
		(end 188.428122 -82.229452)
		(stroke
			(width 0.072898)
			(type default)
		)
		(layer "B.Cu")
	)
	(gr_line
		(start 188.382656 -87.823548)
		(end 188.812424 -87.737442)
		(stroke
			(width 0.072898)
			(type default)
		)
		(layer "B.Cu")
	)
	(gr_line
		(start 188.451998 -92.177616)
		(end 188.816742 -91.934538)
		(stroke
			(width 0.072898)
			(type default)
		)
		(layer "B.Cu")
	)
	(gr_line
		(start 188.49086 -81.490058)
		(end 188.548518 -81.4324)
		(stroke
			(width 0.072898)
			(type default)
		)
		(layer "B.Cu")
	)
	(gr_line
		(start 188.49086 -80.815942)
		(end 188.548518 -80.8736)
		(stroke
			(width 0.072898)
			(type default)
		)
		(layer "B.Cu")
	)
	(gr_line
		(start 188.492638 -23.7744)
		(end 188.586618 -23.7744)
		(stroke
			(width 0.06223)
			(type default)
		)
		(layer "B.Cu")
	)
	(gr_line
		(start 188.576712 -93.80601)
		(end 188.69406 -93.629734)
		(stroke
			(width 0.072898)
			(type default)
		)
		(layer "B.Cu")
	)
	(gr_line
		(start 188.632592 -37.711634)
		(end 188.668406 -37.704522)
		(stroke
			(width 0.06223)
			(type default)
		)
		(layer "B.Cu")
	)
	(gr_line
		(start 188.6458 -86.385654)
		(end 188.667644 -86.381336)
		(stroke
			(width 0.072898)
			(type default)
		)
		(layer "B.Cu")
	)
	(gr_line
		(start 188.667644 -86.381336)
		(end 188.685678 -86.369144)
		(stroke
			(width 0.072898)
			(type default)
		)
		(layer "B.Cu")
	)
	(gr_line
		(start 188.668406 -37.704522)
		(end 188.70422 -37.711634)
		(stroke
			(width 0.06223)
			(type default)
		)
		(layer "B.Cu")
	)
	(gr_line
		(start 188.726318 -23.09876)
		(end 188.993018 -23.36546)
		(stroke
			(width 0.06223)
			(type default)
		)
		(layer "B.Cu")
	)
	(gr_line
		(start 188.812424 -87.737442)
		(end 188.930026 -87.561166)
		(stroke
			(width 0.072898)
			(type default)
		)
		(layer "B.Cu")
	)
	(gr_line
		(start 188.816742 -91.934538)
		(end 188.858144 -91.726512)
		(stroke
			(width 0.072898)
			(type default)
		)
		(layer "B.Cu")
	)
	(gr_line
		(start 188.90615 -21.311616)
		(end 189.17285 -21.044916)
		(stroke
			(width 0.06223)
			(type default)
		)
		(layer "B.Cu")
	)
	(gr_line
		(start 189.083442 -91.199462)
		(end 189.637416 -90.829892)
		(stroke
			(width 0.072898)
			(type default)
		)
		(layer "B.Cu")
	)
	(gr_line
		(start 189.093856 -89.515696)
		(end 189.648846 -89.145872)
		(stroke
			(width 0.072898)
			(type default)
		)
		(layer "B.Cu")
	)
	(gr_line
		(start 189.10427 -93.545152)
		(end 189.12586 -93.540834)
		(stroke
			(width 0.072898)
			(type default)
		)
		(layer "B.Cu")
	)
	(gr_line
		(start 189.116208 -94.916244)
		(end 189.137544 -94.91218)
		(stroke
			(width 0.072898)
			(type default)
		)
		(layer "B.Cu")
	)
	(gr_line
		(start 189.12586 -93.540834)
		(end 189.143894 -93.528642)
		(stroke
			(width 0.072898)
			(type default)
		)
		(layer "B.Cu")
	)
	(gr_line
		(start 189.137544 -94.91218)
		(end 189.155578 -94.899988)
		(stroke
			(width 0.072898)
			(type default)
		)
		(layer "B.Cu")
	)
	(gr_line
		(start 189.17285 -21.044916)
		(end 189.54623 -21.044916)
		(stroke
			(width 0.06223)
			(type default)
		)
		(layer "B.Cu")
	)
	(gr_line
		(start 189.226952 -91.480894)
		(end 189.434724 -91.52255)
		(stroke
			(width 0.072898)
			(type default)
		)
		(layer "B.Cu")
	)
	(gr_line
		(start 189.23762 -89.79662)
		(end 189.4459 -89.838276)
		(stroke
			(width 0.072898)
			(type default)
		)
		(layer "B.Cu")
	)
	(gr_line
		(start 189.31255 -21.720556)
		(end 189.40653 -21.720556)
		(stroke
			(width 0.06223)
			(type default)
		)
		(layer "B.Cu")
	)
	(gr_line
		(start 189.331092 -87.478362)
		(end 189.361572 -87.472266)
		(stroke
			(width 0.072898)
			(type default)
		)
		(layer "B.Cu")
	)
	(gr_line
		(start 189.361572 -87.472266)
		(end 189.386718 -87.45347)
		(stroke
			(width 0.072898)
			(type default)
		)
		(layer "B.Cu")
	)
	(gr_line
		(start 189.434724 -91.52255)
		(end 189.799214 -91.279472)
		(stroke
			(width 0.072898)
			(type default)
		)
		(layer "B.Cu")
	)
	(gr_line
		(start 189.4459 -89.838276)
		(end 189.81039 -89.595452)
		(stroke
			(width 0.072898)
			(type default)
		)
		(layer "B.Cu")
	)
	(gr_line
		(start 189.473586 -19.295872)
		(end 189.740286 -19.029172)
		(stroke
			(width 0.06223)
			(type default)
		)
		(layer "B.Cu")
	)
	(gr_line
		(start 189.533276 -39.18204)
		(end 189.56909 -39.174928)
		(stroke
			(width 0.06223)
			(type default)
		)
		(layer "B.Cu")
	)
	(gr_line
		(start 189.54623 -21.044916)
		(end 189.81293 -21.311616)
		(stroke
			(width 0.06223)
			(type default)
		)
		(layer "B.Cu")
	)
	(gr_line
		(start 189.56909 -39.174928)
		(end 189.604904 -39.18204)
		(stroke
			(width 0.06223)
			(type default)
		)
		(layer "B.Cu")
	)
	(gr_line
		(start 189.640718 -81.4324)
		(end 189.698376 -81.490058)
		(stroke
			(width 0.072898)
			(type default)
		)
		(layer "B.Cu")
	)
	(gr_line
		(start 189.640718 -80.8736)
		(end 189.698376 -80.815942)
		(stroke
			(width 0.072898)
			(type default)
		)
		(layer "B.Cu")
	)
	(gr_line
		(start 189.740286 -19.029172)
		(end 190.113666 -19.029172)
		(stroke
			(width 0.06223)
			(type default)
		)
		(layer "B.Cu")
	)
	(gr_line
		(start 189.799214 -91.279472)
		(end 189.84087 -91.071446)
		(stroke
			(width 0.072898)
			(type default)
		)
		(layer "B.Cu")
	)
	(gr_line
		(start 189.81039 -89.595452)
		(end 189.8523 -89.387172)
		(stroke
			(width 0.072898)
			(type default)
		)
		(layer "B.Cu")
	)
	(gr_line
		(start 189.879986 -19.704812)
		(end 189.973966 -19.704812)
		(stroke
			(width 0.06223)
			(type default)
		)
		(layer "B.Cu")
	)
	(gr_line
		(start 189.949328 -93.997018)
		(end 190.504572 -93.626686)
		(stroke
			(width 0.072898)
			(type default)
		)
		(layer "B.Cu")
	)
	(gr_line
		(start 190.009272 -82.485992)
		(end 190.072772 -82.422492)
		(stroke
			(width 0.072898)
			(type default)
		)
		(layer "B.Cu")
	)
	(gr_line
		(start 190.065152 -90.544904)
		(end 190.619888 -90.174826)
		(stroke
			(width 0.072898)
			(type default)
		)
		(layer "B.Cu")
	)
	(gr_line
		(start 190.077344 -88.860376)
		(end 190.631572 -88.490806)
		(stroke
			(width 0.072898)
			(type default)
		)
		(layer "B.Cu")
	)
	(gr_line
		(start 190.093092 -94.278196)
		(end 190.301118 -94.319852)
		(stroke
			(width 0.072898)
			(type default)
		)
		(layer "B.Cu")
	)
	(gr_line
		(start 190.113666 -19.029172)
		(end 190.380366 -19.295872)
		(stroke
			(width 0.06223)
			(type default)
		)
		(layer "B.Cu")
	)
	(gr_line
		(start 190.14186 -81.490058)
		(end 190.199518 -81.4324)
		(stroke
			(width 0.072898)
			(type default)
		)
		(layer "B.Cu")
	)
	(gr_line
		(start 190.14186 -80.815942)
		(end 190.199518 -80.8736)
		(stroke
			(width 0.072898)
			(type default)
		)
		(layer "B.Cu")
	)
	(gr_line
		(start 190.209424 -90.825828)
		(end 190.41745 -90.86723)
		(stroke
			(width 0.072898)
			(type default)
		)
		(layer "B.Cu")
	)
	(gr_line
		(start 190.220346 -89.141554)
		(end 190.428626 -89.18321)
		(stroke
			(width 0.072898)
			(type default)
		)
		(layer "B.Cu")
	)
	(gr_line
		(start 190.255398 -40.615108)
		(end 190.291466 -40.607996)
		(stroke
			(width 0.06223)
			(type default)
		)
		(layer "B.Cu")
	)
	(gr_line
		(start 190.291466 -40.607996)
		(end 190.328042 -40.615362)
		(stroke
			(width 0.06223)
			(type default)
		)
		(layer "B.Cu")
	)
	(gr_line
		(start 190.301118 -94.319852)
		(end 190.665608 -94.076774)
		(stroke
			(width 0.072898)
			(type default)
		)
		(layer "B.Cu")
	)
	(gr_line
		(start 190.41745 -90.86723)
		(end 190.78194 -90.624152)
		(stroke
			(width 0.072898)
			(type default)
		)
		(layer "B.Cu")
	)
	(gr_line
		(start 190.428626 -89.18321)
		(end 190.793116 -88.940386)
		(stroke
			(width 0.072898)
			(type default)
		)
		(layer "B.Cu")
	)
	(gr_line
		(start 190.665608 -94.076774)
		(end 190.707518 -93.868494)
		(stroke
			(width 0.072898)
			(type default)
		)
		(layer "B.Cu")
	)
	(gr_line
		(start 190.78194 -90.624152)
		(end 190.823596 -90.416126)
		(stroke
			(width 0.072898)
			(type default)
		)
		(layer "B.Cu")
	)
	(gr_line
		(start 190.793116 -88.940386)
		(end 190.835026 -88.732106)
		(stroke
			(width 0.072898)
			(type default)
		)
		(layer "B.Cu")
	)
	(gr_line
		(start 190.931038 -93.34246)
		(end 191.486282 -92.972128)
		(stroke
			(width 0.072898)
			(type default)
		)
		(layer "B.Cu")
	)
	(gr_line
		(start 191.057784 -88.206326)
		(end 191.615314 -87.834724)
		(stroke
			(width 0.072898)
			(type default)
		)
		(layer "B.Cu")
	)
	(gr_line
		(start 191.075818 -93.62313)
		(end 191.283844 -93.664532)
		(stroke
			(width 0.072898)
			(type default)
		)
		(layer "B.Cu")
	)
	(gr_line
		(start 191.140588 -74.942192)
		(end 191.36614 -75.167744)
		(stroke
			(width 0.047498)
			(type default)
		)
		(layer "B.Cu")
	)
	(gr_line
		(start 191.140588 -74.416666)
		(end 191.140588 -74.942192)
		(stroke
			(width 0.047498)
			(type default)
		)
		(layer "B.Cu")
	)
	(gr_line
		(start 191.140588 -74.416666)
		(end 191.140588 -74.555858)
		(stroke
			(width 0.047498)
			(type default)
		)
		(layer "B.Cu")
	)
	(gr_line
		(start 191.140588 -74.409808)
		(end 191.140588 -74.555858)
		(stroke
			(width 0.047498)
			(type default)
		)
		(layer "B.Cu")
	)
	(gr_line
		(start 191.140588 -74.409808)
		(end 191.342772 -74.207624)
		(stroke
			(width 0.047498)
			(type default)
		)
		(layer "B.Cu")
	)
	(gr_line
		(start 191.203072 -88.486488)
		(end 191.411352 -88.528144)
		(stroke
			(width 0.072898)
			(type default)
		)
		(layer "B.Cu")
	)
	(gr_line
		(start 191.208152 -23.847552)
		(end 191.2366 -23.876)
		(stroke
			(width 0.06223)
			(type default)
		)
		(layer "B.Cu")
	)
	(gr_line
		(start 191.208152 -23.269448)
		(end 191.2366 -23.241)
		(stroke
			(width 0.06223)
			(type default)
		)
		(layer "B.Cu")
	)
	(gr_line
		(start 191.2366 -23.876)
		(end 191.41059 -23.876)
		(stroke
			(width 0.06223)
			(type default)
		)
		(layer "B.Cu")
	)
	(gr_line
		(start 191.2366 -23.241)
		(end 191.41059 -23.241)
		(stroke
			(width 0.06223)
			(type default)
		)
		(layer "B.Cu")
	)
	(gr_line
		(start 191.283844 -93.664532)
		(end 191.648334 -93.421454)
		(stroke
			(width 0.072898)
			(type default)
		)
		(layer "B.Cu")
	)
	(gr_line
		(start 191.30264 -75.85075)
		(end 191.30264 -76.017628)
		(stroke
			(width 0.072898)
			(type default)
		)
		(layer "B.Cu")
	)
	(gr_line
		(start 191.30264 -75.827128)
		(end 191.30264 -75.85075)
		(stroke
			(width 0.047498)
			(type default)
		)
		(layer "B.Cu")
	)
	(gr_line
		(start 191.30264 -75.827128)
		(end 191.317118 -75.81265)
		(stroke
			(width 0.047498)
			(type default)
		)
		(layer "B.Cu")
	)
	(gr_line
		(start 191.318896 -75.810872)
		(end 191.36614 -75.763628)
		(stroke
			(width 0.047498)
			(type default)
		)
		(layer "B.Cu")
	)
	(gr_line
		(start 191.324738 -74.865738)
		(end 191.55029 -75.09129)
		(stroke
			(width 0.047498)
			(type default)
		)
		(layer "B.Cu")
	)
	(gr_line
		(start 191.324738 -74.486262)
		(end 191.324738 -74.865738)
		(stroke
			(width 0.047498)
			(type default)
		)
		(layer "B.Cu")
	)
	(gr_line
		(start 191.324738 -74.486262)
		(end 191.419226 -74.391774)
		(stroke
			(width 0.047498)
			(type default)
		)
		(layer "B.Cu")
	)
	(gr_line
		(start 191.342772 -74.207624)
		(end 191.843406 -74.207624)
		(stroke
			(width 0.047498)
			(type default)
		)
		(layer "B.Cu")
	)
	(gr_line
		(start 191.36614 -75.167744)
		(end 191.36614 -75.763628)
		(stroke
			(width 0.047498)
			(type default)
		)
		(layer "B.Cu")
	)
	(gr_line
		(start 191.380364 -19.206972)
		(end 191.41059 -19.177)
		(stroke
			(width 0.06223)
			(type default)
		)
		(layer "B.Cu")
	)
	(gr_line
		(start 191.381888 -25.879552)
		(end 191.410336 -25.908)
		(stroke
			(width 0.06223)
			(type default)
		)
		(layer "B.Cu")
	)
	(gr_line
		(start 191.381888 -25.301448)
		(end 191.410336 -25.273)
		(stroke
			(width 0.06223)
			(type default)
		)
		(layer "B.Cu")
	)
	(gr_line
		(start 191.382142 -21.815552)
		(end 191.41059 -21.844)
		(stroke
			(width 0.06223)
			(type default)
		)
		(layer "B.Cu")
	)
	(gr_line
		(start 191.382142 -21.237448)
		(end 191.41059 -21.209)
		(stroke
			(width 0.06223)
			(type default)
		)
		(layer "B.Cu")
	)
	(gr_line
		(start 191.382142 -19.783552)
		(end 191.41059 -19.812)
		(stroke
			(width 0.06223)
			(type default)
		)
		(layer "B.Cu")
	)
	(gr_line
		(start 191.411352 -88.528144)
		(end 191.775842 -88.28532)
		(stroke
			(width 0.072898)
			(type default)
		)
		(layer "B.Cu")
	)
	(gr_line
		(start 191.419226 -74.391774)
		(end 191.824356 -74.391774)
		(stroke
			(width 0.047498)
			(type default)
		)
		(layer "B.Cu")
	)
	(gr_line
		(start 191.55029 -75.763628)
		(end 191.597534 -75.810872)
		(stroke
			(width 0.047498)
			(type default)
		)
		(layer "B.Cu")
	)
	(gr_line
		(start 191.55029 -75.09129)
		(end 191.55029 -75.763628)
		(stroke
			(width 0.047498)
			(type default)
		)
		(layer "B.Cu")
	)
	(gr_line
		(start 191.599312 -75.81265)
		(end 191.61379 -75.827128)
		(stroke
			(width 0.047498)
			(type default)
		)
		(layer "B.Cu")
	)
	(gr_line
		(start 191.61379 -75.85075)
		(end 191.61379 -76.017628)
		(stroke
			(width 0.072898)
			(type default)
		)
		(layer "B.Cu")
	)
	(gr_line
		(start 191.61379 -75.827128)
		(end 191.61379 -75.85075)
		(stroke
			(width 0.047498)
			(type default)
		)
		(layer "B.Cu")
	)
	(gr_line
		(start 191.648334 -93.421454)
		(end 191.68999 -93.213428)
		(stroke
			(width 0.072898)
			(type default)
		)
		(layer "B.Cu")
	)
	(gr_line
		(start 191.672718 -81.4324)
		(end 191.730376 -81.490058)
		(stroke
			(width 0.072898)
			(type default)
		)
		(layer "B.Cu")
	)
	(gr_line
		(start 191.672718 -80.8736)
		(end 191.730376 -80.815942)
		(stroke
			(width 0.072898)
			(type default)
		)
		(layer "B.Cu")
	)
	(gr_line
		(start 191.679576 -77.844904)
		(end 191.797432 -77.727048)
		(stroke
			(width 0.072898)
			(type default)
		)
		(layer "B.Cu")
	)
	(gr_line
		(start 191.706246 -85.047836)
		(end 191.78778 -84.966302)
		(stroke
			(width 0.072898)
			(type default)
		)
		(layer "B.Cu")
	)
	(gr_line
		(start 191.708024 -85.489796)
		(end 191.91986 -85.489796)
		(stroke
			(width 0.072898)
			(type default)
		)
		(layer "B.Cu")
	)
	(gr_line
		(start 191.775842 -88.28532)
		(end 191.817752 -88.07704)
		(stroke
			(width 0.072898)
			(type default)
		)
		(layer "B.Cu")
	)
	(gr_line
		(start 191.797432 -77.727048)
		(end 191.814196 -77.710284)
		(stroke
			(width 0.047498)
			(type default)
		)
		(layer "B.Cu")
	)
	(gr_line
		(start 191.814196 -77.710284)
		(end 191.835024 -77.710284)
		(stroke
			(width 0.047498)
			(type default)
		)
		(layer "B.Cu")
	)
	(gr_line
		(start 191.837564 -77.710284)
		(end 191.904112 -77.710284)
		(stroke
			(width 0.047498)
			(type default)
		)
		(layer "B.Cu")
	)
	(gr_arc
		(start 191.843406 -74.207624)
		(mid 191.903205 -74.195591)
		(end 191.953896 -74.16165)
		(stroke
			(width 0.047498)
			(type default)
		)
		(layer "B.Cu")
	)
	(gr_line
		(start 191.899794 -78.065122)
		(end 192.01765 -77.947266)
		(stroke
			(width 0.072898)
			(type default)
		)
		(layer "B.Cu")
	)
	(gr_line
		(start 191.904112 -77.710284)
		(end 192.061338 -77.553058)
		(stroke
			(width 0.047498)
			(type default)
		)
		(layer "B.Cu")
	)
	(gr_line
		(start 191.913764 -92.687394)
		(end 192.469008 -92.317062)
		(stroke
			(width 0.072898)
			(type default)
		)
		(layer "B.Cu")
	)
	(gr_line
		(start 191.91986 -85.489796)
		(end 192.22974 -85.179916)
		(stroke
			(width 0.072898)
			(type default)
		)
		(layer "B.Cu")
	)
	(gr_arc
		(start 191.948308 -74.443336)
		(mid 191.891453 -74.405254)
		(end 191.824356 -74.391774)
		(stroke
			(width 0.047498)
			(type default)
		)
		(layer "B.Cu")
	)
	(gr_line
		(start 191.948308 -74.443336)
		(end 191.97193 -74.466704)
		(stroke
			(width 0.047498)
			(type default)
		)
		(layer "B.Cu")
	)
	(gr_line
		(start 191.953896 -74.16165)
		(end 191.971676 -74.14387)
		(stroke
			(width 0.047498)
			(type default)
		)
		(layer "B.Cu")
	)
	(gr_line
		(start 191.969136 -25.908)
		(end 191.997584 -25.879552)
		(stroke
			(width 0.06223)
			(type default)
		)
		(layer "B.Cu")
	)
	(gr_line
		(start 191.969136 -25.273)
		(end 191.997584 -25.301448)
		(stroke
			(width 0.06223)
			(type default)
		)
		(layer "B.Cu")
	)
	(gr_line
		(start 191.96939 -23.876)
		(end 191.997838 -23.847552)
		(stroke
			(width 0.06223)
			(type default)
		)
		(layer "B.Cu")
	)
	(gr_line
		(start 191.96939 -23.241)
		(end 191.997838 -23.269448)
		(stroke
			(width 0.06223)
			(type default)
		)
		(layer "B.Cu")
	)
	(gr_line
		(start 191.96939 -21.843746)
		(end 191.96939 -21.844)
		(stroke
			(width 0.06223)
			(type default)
		)
		(layer "B.Cu")
	)
	(gr_line
		(start 191.96939 -21.843746)
		(end 191.997584 -21.815552)
		(stroke
			(width 0.06223)
			(type default)
		)
		(layer "B.Cu")
	)
	(gr_line
		(start 191.96939 -21.209)
		(end 191.997584 -21.237194)
		(stroke
			(width 0.06223)
			(type default)
		)
		(layer "B.Cu")
	)
	(gr_line
		(start 191.96939 -19.812)
		(end 191.997838 -19.783552)
		(stroke
			(width 0.06223)
			(type default)
		)
		(layer "B.Cu")
	)
	(gr_line
		(start 191.96939 -19.177)
		(end 191.997838 -19.205448)
		(stroke
			(width 0.06223)
			(type default)
		)
		(layer "B.Cu")
	)
	(gr_arc
		(start 191.971676 -74.14387)
		(mid 191.992537 -74.112911)
		(end 191.99987 -74.076306)
		(stroke
			(width 0.047498)
			(type default)
		)
		(layer "B.Cu")
	)
	(gr_arc
		(start 191.99987 -74.534268)
		(mid 191.992668 -74.497681)
		(end 191.97193 -74.466704)
		(stroke
			(width 0.047498)
			(type default)
		)
		(layer "B.Cu")
	)
	(gr_line
		(start 191.99987 -74.534268)
		(end 191.99987 -74.699622)
		(stroke
			(width 0.047498)
			(type default)
		)
		(layer "B.Cu")
	)
	(gr_line
		(start 191.99987 -73.899776)
		(end 191.99987 -74.076306)
		(stroke
			(width 0.047498)
			(type default)
		)
		(layer "B.Cu")
	)
	(gr_line
		(start 192.01765 -77.947266)
		(end 192.034414 -77.930502)
		(stroke
			(width 0.047498)
			(type default)
		)
		(layer "B.Cu")
	)
	(gr_line
		(start 192.034414 -77.909674)
		(end 192.034414 -77.930502)
		(stroke
			(width 0.047498)
			(type default)
		)
		(layer "B.Cu")
	)
	(gr_line
		(start 192.034414 -77.840586)
		(end 192.034414 -77.907134)
		(stroke
			(width 0.047498)
			(type default)
		)
		(layer "B.Cu")
	)
	(gr_line
		(start 192.034414 -77.840586)
		(end 192.245488 -77.629512)
		(stroke
			(width 0.047498)
			(type default)
		)
		(layer "B.Cu")
	)
	(gr_line
		(start 192.0367 -83.531964)
		(end 192.1002 -83.468464)
		(stroke
			(width 0.072898)
			(type default)
		)
		(layer "B.Cu")
	)
	(gr_line
		(start 192.05829 -92.96781)
		(end 192.26657 -93.009466)
		(stroke
			(width 0.072898)
			(type default)
		)
		(layer "B.Cu")
	)
	(gr_line
		(start 192.061338 -75.488546)
		(end 192.061338 -77.553058)
		(stroke
			(width 0.047498)
			(type default)
		)
		(layer "B.Cu")
	)
	(gr_line
		(start 192.061338 -75.488546)
		(end 192.402968 -74.975212)
		(stroke
			(width 0.047498)
			(type default)
		)
		(layer "B.Cu")
	)
	(gr_line
		(start 192.17386 -81.490058)
		(end 192.231518 -81.4324)
		(stroke
			(width 0.072898)
			(type default)
		)
		(layer "B.Cu")
	)
	(gr_line
		(start 192.17386 -80.815942)
		(end 192.231518 -80.8736)
		(stroke
			(width 0.072898)
			(type default)
		)
		(layer "B.Cu")
	)
	(gr_line
		(start 192.22974 -84.96808)
		(end 192.22974 -85.179916)
		(stroke
			(width 0.072898)
			(type default)
		)
		(layer "B.Cu")
	)
	(gr_line
		(start 192.245488 -75.544426)
		(end 192.245488 -77.629512)
		(stroke
			(width 0.047498)
			(type default)
		)
		(layer "B.Cu")
	)
	(gr_line
		(start 192.245488 -75.544426)
		(end 192.587118 -75.031092)
		(stroke
			(width 0.047498)
			(type default)
		)
		(layer "B.Cu")
	)
	(gr_line
		(start 192.26657 -93.009466)
		(end 192.63106 -92.766388)
		(stroke
			(width 0.072898)
			(type default)
		)
		(layer "B.Cu")
	)
	(gr_line
		(start 192.402968 -74.715878)
		(end 192.402968 -74.975212)
		(stroke
			(width 0.047498)
			(type default)
		)
		(layer "B.Cu")
	)
	(gr_line
		(start 192.402968 -74.529188)
		(end 192.402968 -74.713338)
		(stroke
			(width 0.047498)
			(type default)
		)
		(layer "B.Cu")
	)
	(gr_line
		(start 192.402968 -74.529188)
		(end 192.799716 -73.899776)
		(stroke
			(width 0.047498)
			(type default)
		)
		(layer "B.Cu")
	)
	(gr_line
		(start 192.541398 -84.212684)
		(end 192.622932 -84.13115)
		(stroke
			(width 0.072898)
			(type default)
		)
		(layer "B.Cu")
	)
	(gr_line
		(start 192.543176 -84.654644)
		(end 192.755012 -84.654644)
		(stroke
			(width 0.072898)
			(type default)
		)
		(layer "B.Cu")
	)
	(gr_line
		(start 192.587118 -74.912728)
		(end 192.587118 -75.031092)
		(stroke
			(width 0.047498)
			(type default)
		)
		(layer "B.Cu")
	)
	(gr_line
		(start 192.587118 -74.912728)
		(end 192.599818 -74.900028)
		(stroke
			(width 0.047498)
			(type default)
		)
		(layer "B.Cu")
	)
	(gr_line
		(start 192.602358 -74.897488)
		(end 192.79997 -74.699876)
		(stroke
			(width 0.047498)
			(type default)
		)
		(layer "B.Cu")
	)
	(gr_line
		(start 192.63106 -92.766388)
		(end 192.672716 -92.558362)
		(stroke
			(width 0.072898)
			(type default)
		)
		(layer "B.Cu")
	)
	(gr_line
		(start 192.755012 -84.654644)
		(end 193.064892 -84.344764)
		(stroke
			(width 0.072898)
			(type default)
		)
		(layer "B.Cu")
	)
	(gr_line
		(start 192.942718 -81.4324)
		(end 193.000376 -81.490058)
		(stroke
			(width 0.072898)
			(type default)
		)
		(layer "B.Cu")
	)
	(gr_line
		(start 192.942718 -80.8736)
		(end 192.942972 -80.8736)
		(stroke
			(width 0.068326)
			(type default)
		)
		(layer "B.Cu")
	)
	(gr_line
		(start 192.942972 -80.8736)
		(end 193.000376 -80.816196)
		(stroke
			(width 0.072898)
			(type default)
		)
		(layer "B.Cu")
	)
	(gr_line
		(start 193.064892 -84.132928)
		(end 193.064892 -84.344764)
		(stroke
			(width 0.072898)
			(type default)
		)
		(layer "B.Cu")
	)
	(gr_line
		(start 193.44386 -81.490058)
		(end 193.501518 -81.4324)
		(stroke
			(width 0.072898)
			(type default)
		)
		(layer "B.Cu")
	)
	(gr_line
		(start 193.444114 -80.816196)
		(end 193.501518 -80.8736)
		(stroke
			(width 0.072898)
			(type default)
		)
		(layer "B.Cu")
	)
	(gr_line
		(start 193.84264 -76.62545)
		(end 193.84264 -76.792328)
		(stroke
			(width 0.072898)
			(type default)
		)
		(layer "B.Cu")
	)
	(gr_line
		(start 193.84264 -76.601828)
		(end 193.84264 -76.62545)
		(stroke
			(width 0.047498)
			(type default)
		)
		(layer "B.Cu")
	)
	(gr_line
		(start 193.84264 -76.601828)
		(end 193.857118 -76.58735)
		(stroke
			(width 0.047498)
			(type default)
		)
		(layer "B.Cu")
	)
	(gr_line
		(start 193.858896 -76.585572)
		(end 193.90614 -76.538328)
		(stroke
			(width 0.047498)
			(type default)
		)
		(layer "B.Cu")
	)
	(gr_line
		(start 193.90614 -76.07046)
		(end 193.90614 -76.538328)
		(stroke
			(width 0.047498)
			(type default)
		)
		(layer "B.Cu")
	)
	(gr_line
		(start 193.90614 -76.07046)
		(end 194.0433 -75.9333)
		(stroke
			(width 0.047498)
			(type default)
		)
		(layer "B.Cu")
	)
	(gr_line
		(start 193.988944 -74.864214)
		(end 194.0433 -74.91857)
		(stroke
			(width 0.047498)
			(type default)
		)
		(layer "B.Cu")
	)
	(gr_line
		(start 193.988944 -74.310494)
		(end 193.988944 -74.864214)
		(stroke
			(width 0.047498)
			(type default)
		)
		(layer "B.Cu")
	)
	(gr_line
		(start 193.988944 -74.310494)
		(end 194.399662 -73.899776)
		(stroke
			(width 0.047498)
			(type default)
		)
		(layer "B.Cu")
	)
	(gr_line
		(start 194.0433 -74.91857)
		(end 194.0433 -75.9333)
		(stroke
			(width 0.047498)
			(type default)
		)
		(layer "B.Cu")
	)
	(gr_line
		(start 194.09029 -76.538328)
		(end 194.137534 -76.585572)
		(stroke
			(width 0.047498)
			(type default)
		)
		(layer "B.Cu")
	)
	(gr_line
		(start 194.09029 -76.146914)
		(end 194.09029 -76.538328)
		(stroke
			(width 0.047498)
			(type default)
		)
		(layer "B.Cu")
	)
	(gr_line
		(start 194.09029 -76.146914)
		(end 194.22745 -76.009754)
		(stroke
			(width 0.047498)
			(type default)
		)
		(layer "B.Cu")
	)
	(gr_line
		(start 194.139312 -76.58735)
		(end 194.15379 -76.601828)
		(stroke
			(width 0.047498)
			(type default)
		)
		(layer "B.Cu")
	)
	(gr_line
		(start 194.15379 -76.62545)
		(end 194.15379 -76.792328)
		(stroke
			(width 0.072898)
			(type default)
		)
		(layer "B.Cu")
	)
	(gr_line
		(start 194.15379 -76.601828)
		(end 194.15379 -76.62545)
		(stroke
			(width 0.047498)
			(type default)
		)
		(layer "B.Cu")
	)
	(gr_line
		(start 194.22745 -75.863704)
		(end 194.22745 -76.009754)
		(stroke
			(width 0.047498)
			(type default)
		)
		(layer "B.Cu")
	)
	(gr_line
		(start 194.22745 -75.863704)
		(end 194.22745 -76.002896)
		(stroke
			(width 0.047498)
			(type default)
		)
		(layer "B.Cu")
	)
	(gr_line
		(start 194.22745 -74.867008)
		(end 194.22745 -76.002896)
		(stroke
			(width 0.047498)
			(type default)
		)
		(layer "B.Cu")
	)
	(gr_line
		(start 194.22745 -74.867008)
		(end 194.248786 -74.845672)
		(stroke
			(width 0.047498)
			(type default)
		)
		(layer "B.Cu")
	)
	(gr_line
		(start 194.250564 -74.843894)
		(end 194.39255 -74.701908)
		(stroke
			(width 0.047498)
			(type default)
		)
		(layer "B.Cu")
	)
	(gr_line
		(start 194.64655 -77.724)
		(end 194.64655 -77.890878)
		(stroke
			(width 0.072898)
			(type default)
		)
		(layer "B.Cu")
	)
	(gr_line
		(start 194.64655 -77.700378)
		(end 194.64655 -77.724)
		(stroke
			(width 0.047498)
			(type default)
		)
		(layer "B.Cu")
	)
	(gr_line
		(start 194.64655 -77.700378)
		(end 194.661028 -77.6859)
		(stroke
			(width 0.047498)
			(type default)
		)
		(layer "B.Cu")
	)
	(gr_line
		(start 194.662806 -77.684122)
		(end 194.71005 -77.636878)
		(stroke
			(width 0.047498)
			(type default)
		)
		(layer "B.Cu")
	)
	(gr_line
		(start 194.71005 -76.580746)
		(end 194.71005 -77.636878)
		(stroke
			(width 0.047498)
			(type default)
		)
		(layer "B.Cu")
	)
	(gr_line
		(start 194.71005 -76.580746)
		(end 194.795902 -76.494894)
		(stroke
			(width 0.047498)
			(type default)
		)
		(layer "B.Cu")
	)
	(gr_line
		(start 194.795902 -74.729086)
		(end 194.795902 -76.494894)
		(stroke
			(width 0.047498)
			(type default)
		)
		(layer "B.Cu")
	)
	(gr_line
		(start 194.795902 -74.573892)
		(end 194.795902 -74.726546)
		(stroke
			(width 0.047498)
			(type default)
		)
		(layer "B.Cu")
	)
	(gr_line
		(start 194.795902 -74.573892)
		(end 195.199762 -73.899776)
		(stroke
			(width 0.047498)
			(type default)
		)
		(layer "B.Cu")
	)
	(gr_line
		(start 194.8942 -77.636878)
		(end 194.941444 -77.684122)
		(stroke
			(width 0.047498)
			(type default)
		)
		(layer "B.Cu")
	)
	(gr_line
		(start 194.8942 -76.6572)
		(end 194.8942 -77.636878)
		(stroke
			(width 0.047498)
			(type default)
		)
		(layer "B.Cu")
	)
	(gr_line
		(start 194.8942 -76.6572)
		(end 194.980052 -76.571348)
		(stroke
			(width 0.047498)
			(type default)
		)
		(layer "B.Cu")
	)
	(gr_line
		(start 194.943222 -77.6859)
		(end 194.9577 -77.700378)
		(stroke
			(width 0.047498)
			(type default)
		)
		(layer "B.Cu")
	)
	(gr_line
		(start 194.9577 -77.724)
		(end 194.9577 -77.890878)
		(stroke
			(width 0.072898)
			(type default)
		)
		(layer "B.Cu")
	)
	(gr_line
		(start 194.9577 -77.700378)
		(end 194.9577 -77.724)
		(stroke
			(width 0.047498)
			(type default)
		)
		(layer "B.Cu")
	)
	(gr_line
		(start 194.980052 -76.425298)
		(end 194.980052 -76.571348)
		(stroke
			(width 0.047498)
			(type default)
		)
		(layer "B.Cu")
	)
	(gr_line
		(start 194.980052 -76.425298)
		(end 194.980052 -76.56449)
		(stroke
			(width 0.047498)
			(type default)
		)
		(layer "B.Cu")
	)
	(gr_line
		(start 194.980052 -74.925936)
		(end 194.980052 -76.56449)
		(stroke
			(width 0.047498)
			(type default)
		)
		(layer "B.Cu")
	)
	(gr_line
		(start 194.980052 -74.925936)
		(end 194.992752 -74.913236)
		(stroke
			(width 0.047498)
			(type default)
		)
		(layer "B.Cu")
	)
	(gr_line
		(start 194.995292 -74.910696)
		(end 195.198492 -74.707496)
		(stroke
			(width 0.047498)
			(type default)
		)
		(layer "B.Cu")
	)
	(gr_line
		(start 196.07784 -25.795986)
		(end 196.115432 -25.803352)
		(stroke
			(width 0.06223)
			(type default)
		)
		(layer "B.Cu")
	)
	(gr_line
		(start 196.115432 -25.803352)
		(end 196.146674 -25.824434)
		(stroke
			(width 0.06223)
			(type default)
		)
		(layer "B.Cu")
	)
	(gr_line
		(start 196.390514 -19.248628)
		(end 196.455792 -19.292062)
		(stroke
			(width 0.06223)
			(type default)
		)
		(layer "B.Cu")
	)
	(gr_line
		(start 196.404738 -74.865484)
		(end 196.6087 -75.069446)
		(stroke
			(width 0.047498)
			(type default)
		)
		(layer "B.Cu")
	)
	(gr_line
		(start 196.404738 -74.294746)
		(end 196.404738 -74.865484)
		(stroke
			(width 0.047498)
			(type default)
		)
		(layer "B.Cu")
	)
	(gr_line
		(start 196.404738 -74.294746)
		(end 196.799708 -73.899776)
		(stroke
			(width 0.047498)
			(type default)
		)
		(layer "B.Cu")
	)
	(gr_line
		(start 196.61124 -75.071986)
		(end 196.62394 -75.084686)
		(stroke
			(width 0.047498)
			(type default)
		)
		(layer "B.Cu")
	)
	(gr_line
		(start 196.62394 -75.587098)
		(end 196.70014 -75.663298)
		(stroke
			(width 0.047498)
			(type default)
		)
		(layer "B.Cu")
	)
	(gr_line
		(start 196.62394 -75.084686)
		(end 196.62394 -75.587098)
		(stroke
			(width 0.047498)
			(type default)
		)
		(layer "B.Cu")
	)
	(gr_line
		(start 196.63664 -76.77785)
		(end 196.63664 -76.944728)
		(stroke
			(width 0.072898)
			(type default)
		)
		(layer "B.Cu")
	)
	(gr_line
		(start 196.63664 -76.754228)
		(end 196.63664 -76.77785)
		(stroke
			(width 0.047498)
			(type default)
		)
		(layer "B.Cu")
	)
	(gr_line
		(start 196.63664 -76.754228)
		(end 196.651118 -76.73975)
		(stroke
			(width 0.047498)
			(type default)
		)
		(layer "B.Cu")
	)
	(gr_line
		(start 196.652896 -76.737972)
		(end 196.70014 -76.690728)
		(stroke
			(width 0.047498)
			(type default)
		)
		(layer "B.Cu")
	)
	(gr_line
		(start 196.70014 -75.663298)
		(end 196.70014 -76.690728)
		(stroke
			(width 0.047498)
			(type default)
		)
		(layer "B.Cu")
	)
	(gr_line
		(start 196.80809 -75.510644)
		(end 196.88429 -75.586844)
		(stroke
			(width 0.047498)
			(type default)
		)
		(layer "B.Cu")
	)
	(gr_line
		(start 196.80809 -74.887836)
		(end 196.80809 -75.510644)
		(stroke
			(width 0.047498)
			(type default)
		)
		(layer "B.Cu")
	)
	(gr_line
		(start 196.80809 -74.698352)
		(end 196.80809 -74.885296)
		(stroke
			(width 0.047498)
			(type default)
		)
		(layer "B.Cu")
	)
	(gr_line
		(start 196.88429 -76.690728)
		(end 196.931534 -76.737972)
		(stroke
			(width 0.047498)
			(type default)
		)
		(layer "B.Cu")
	)
	(gr_line
		(start 196.88429 -75.586844)
		(end 196.88429 -76.690728)
		(stroke
			(width 0.047498)
			(type default)
		)
		(layer "B.Cu")
	)
	(gr_line
		(start 196.933312 -76.73975)
		(end 196.94779 -76.754228)
		(stroke
			(width 0.047498)
			(type default)
		)
		(layer "B.Cu")
	)
	(gr_line
		(start 196.94779 -76.77785)
		(end 196.94779 -76.944728)
		(stroke
			(width 0.072898)
			(type default)
		)
		(layer "B.Cu")
	)
	(gr_line
		(start 196.94779 -76.754228)
		(end 196.94779 -76.77785)
		(stroke
			(width 0.047498)
			(type default)
		)
		(layer "B.Cu")
	)
	(gr_line
		(start 197.212204 -74.866754)
		(end 197.416166 -75.070716)
		(stroke
			(width 0.047498)
			(type default)
		)
		(layer "B.Cu")
	)
	(gr_line
		(start 197.212204 -74.147426)
		(end 197.212204 -74.866754)
		(stroke
			(width 0.047498)
			(type default)
		)
		(layer "B.Cu")
	)
	(gr_line
		(start 197.212204 -74.147426)
		(end 197.459854 -73.899776)
		(stroke
			(width 0.047498)
			(type default)
		)
		(layer "B.Cu")
	)
	(gr_line
		(start 197.24624 -21.671534)
		(end 197.28307 -21.678646)
		(stroke
			(width 0.06223)
			(type default)
		)
		(layer "B.Cu")
	)
	(gr_line
		(start 197.260718 -81.4324)
		(end 197.318376 -81.490058)
		(stroke
			(width 0.072898)
			(type default)
		)
		(layer "B.Cu")
	)
	(gr_line
		(start 197.260718 -80.8736)
		(end 197.318376 -80.815942)
		(stroke
			(width 0.072898)
			(type default)
		)
		(layer "B.Cu")
	)
	(gr_line
		(start 197.28307 -21.678646)
		(end 197.314058 -21.699474)
		(stroke
			(width 0.06223)
			(type default)
		)
		(layer "B.Cu")
	)
	(gr_line
		(start 197.418706 -75.073256)
		(end 197.431406 -75.085956)
		(stroke
			(width 0.047498)
			(type default)
		)
		(layer "B.Cu")
	)
	(gr_line
		(start 197.431406 -75.74661)
		(end 197.82155 -76.136754)
		(stroke
			(width 0.047498)
			(type default)
		)
		(layer "B.Cu")
	)
	(gr_line
		(start 197.431406 -75.085956)
		(end 197.431406 -75.74661)
		(stroke
			(width 0.047498)
			(type default)
		)
		(layer "B.Cu")
	)
	(gr_line
		(start 197.459854 -73.899776)
		(end 197.599808 -73.899776)
		(stroke
			(width 0.047498)
			(type default)
		)
		(layer "B.Cu")
	)
	(gr_line
		(start 197.609206 -74.699622)
		(end 197.615556 -74.705972)
		(stroke
			(width 0.047498)
			(type default)
		)
		(layer "B.Cu")
	)
	(gr_line
		(start 197.615556 -75.670156)
		(end 198.0057 -76.0603)
		(stroke
			(width 0.047498)
			(type default)
		)
		(layer "B.Cu")
	)
	(gr_line
		(start 197.615556 -74.889106)
		(end 197.615556 -75.670156)
		(stroke
			(width 0.047498)
			(type default)
		)
		(layer "B.Cu")
	)
	(gr_line
		(start 197.615556 -74.705972)
		(end 197.615556 -74.886566)
		(stroke
			(width 0.047498)
			(type default)
		)
		(layer "B.Cu")
	)
	(gr_line
		(start 197.639686 -27.324812)
		(end 197.711822 -27.695144)
		(stroke
			(width 0.06223)
			(type default)
		)
		(layer "B.Cu")
	)
	(gr_line
		(start 197.711822 -27.695144)
		(end 198.021448 -27.903932)
		(stroke
			(width 0.06223)
			(type default)
		)
		(layer "B.Cu")
	)
	(gr_line
		(start 197.75805 -76.446126)
		(end 197.75805 -76.613004)
		(stroke
			(width 0.072898)
			(type default)
		)
		(layer "B.Cu")
	)
	(gr_line
		(start 197.75805 -76.422504)
		(end 197.75805 -76.446126)
		(stroke
			(width 0.047498)
			(type default)
		)
		(layer "B.Cu")
	)
	(gr_line
		(start 197.75805 -76.422504)
		(end 197.772528 -76.408026)
		(stroke
			(width 0.047498)
			(type default)
		)
		(layer "B.Cu")
	)
	(gr_line
		(start 197.76186 -81.490058)
		(end 197.819518 -81.4324)
		(stroke
			(width 0.072898)
			(type default)
		)
		(layer "B.Cu")
	)
	(gr_line
		(start 197.76186 -80.815942)
		(end 197.819518 -80.8736)
		(stroke
			(width 0.072898)
			(type default)
		)
		(layer "B.Cu")
	)
	(gr_line
		(start 197.774306 -76.406248)
		(end 197.82155 -76.359004)
		(stroke
			(width 0.047498)
			(type default)
		)
		(layer "B.Cu")
	)
	(gr_line
		(start 197.82155 -76.136754)
		(end 197.82155 -76.359004)
		(stroke
			(width 0.047498)
			(type default)
		)
		(layer "B.Cu")
	)
	(gr_line
		(start 197.83679 -24.131016)
		(end 197.874636 -24.138636)
		(stroke
			(width 0.06223)
			(type default)
		)
		(layer "B.Cu")
	)
	(gr_line
		(start 197.874636 -24.13889)
		(end 197.904862 -24.15921)
		(stroke
			(width 0.06223)
			(type default)
		)
		(layer "B.Cu")
	)
	(gr_line
		(start 197.874636 -24.138636)
		(end 197.874636 -24.13889)
		(stroke
			(width 0.06223)
			(type default)
		)
		(layer "B.Cu")
	)
	(gr_line
		(start 197.903846 -27.009852)
		(end 198.585074 -27.469084)
		(stroke
			(width 0.06223)
			(type default)
		)
		(layer "B.Cu")
	)
	(gr_line
		(start 198.0057 -76.359004)
		(end 198.052944 -76.406248)
		(stroke
			(width 0.047498)
			(type default)
		)
		(layer "B.Cu")
	)
	(gr_line
		(start 198.0057 -76.0603)
		(end 198.0057 -76.359004)
		(stroke
			(width 0.047498)
			(type default)
		)
		(layer "B.Cu")
	)
	(gr_line
		(start 198.021448 -27.903932)
		(end 198.39178 -27.83205)
		(stroke
			(width 0.06223)
			(type default)
		)
		(layer "B.Cu")
	)
	(gr_line
		(start 198.054722 -76.408026)
		(end 198.0692 -76.422504)
		(stroke
			(width 0.047498)
			(type default)
		)
		(layer "B.Cu")
	)
	(gr_line
		(start 198.0692 -76.446126)
		(end 198.0692 -76.613004)
		(stroke
			(width 0.072898)
			(type default)
		)
		(layer "B.Cu")
	)
	(gr_line
		(start 198.0692 -76.422504)
		(end 198.0692 -76.446126)
		(stroke
			(width 0.047498)
			(type default)
		)
		(layer "B.Cu")
	)
	(gr_line
		(start 198.530718 -81.4324)
		(end 198.530972 -81.4324)
		(stroke
			(width 0.072898)
			(type default)
		)
		(layer "B.Cu")
	)
	(gr_line
		(start 198.530718 -80.8736)
		(end 198.588376 -80.815942)
		(stroke
			(width 0.072898)
			(type default)
		)
		(layer "B.Cu")
	)
	(gr_line
		(start 198.530972 -81.4324)
		(end 198.588376 -81.489804)
		(stroke
			(width 0.072898)
			(type default)
		)
		(layer "B.Cu")
	)
	(gr_line
		(start 198.676768 -23.099268)
		(end 198.750936 -23.4696)
		(stroke
			(width 0.06223)
			(type default)
		)
		(layer "B.Cu")
	)
	(gr_line
		(start 198.70547 -28.043378)
		(end 198.777352 -28.413964)
		(stroke
			(width 0.06223)
			(type default)
		)
		(layer "B.Cu")
	)
	(gr_line
		(start 198.750936 -23.4696)
		(end 199.061578 -23.67661)
		(stroke
			(width 0.06223)
			(type default)
		)
		(layer "B.Cu")
	)
	(gr_line
		(start 198.777352 -28.413964)
		(end 199.086978 -28.622752)
		(stroke
			(width 0.06223)
			(type default)
		)
		(layer "B.Cu")
	)
	(gr_line
		(start 198.7931 -74.867008)
		(end 198.90486 -74.978768)
		(stroke
			(width 0.047498)
			(type default)
		)
		(layer "B.Cu")
	)
	(gr_line
		(start 198.7931 -74.30643)
		(end 198.7931 -74.867008)
		(stroke
			(width 0.047498)
			(type default)
		)
		(layer "B.Cu")
	)
	(gr_line
		(start 198.7931 -74.30643)
		(end 199.199754 -73.899776)
		(stroke
			(width 0.047498)
			(type default)
		)
		(layer "B.Cu")
	)
	(gr_line
		(start 198.901304 -82.784696)
		(end 198.964804 -82.721196)
		(stroke
			(width 0.072898)
			(type default)
		)
		(layer "B.Cu")
	)
	(gr_line
		(start 198.9074 -74.981308)
		(end 198.9201 -74.994008)
		(stroke
			(width 0.047498)
			(type default)
		)
		(layer "B.Cu")
	)
	(gr_line
		(start 198.9201 -74.994008)
		(end 198.9201 -76.6191)
		(stroke
			(width 0.047498)
			(type default)
		)
		(layer "B.Cu")
	)
	(gr_line
		(start 198.924926 -76.623926)
		(end 198.974202 -76.673202)
		(stroke
			(width 0.047498)
			(type default)
		)
		(layer "B.Cu")
	)
	(gr_line
		(start 198.935594 -22.77999)
		(end 199.626474 -23.240492)
		(stroke
			(width 0.06223)
			(type default)
		)
		(layer "B.Cu")
	)
	(gr_line
		(start 198.9455 -25.354534)
		(end 199.017382 -25.724866)
		(stroke
			(width 0.06223)
			(type default)
		)
		(layer "B.Cu")
	)
	(gr_line
		(start 198.970392 -27.72918)
		(end 199.651112 -28.188412)
		(stroke
			(width 0.06223)
			(type default)
		)
		(layer "B.Cu")
	)
	(gr_line
		(start 198.974202 -76.673202)
		(end 199.493886 -77.19187)
		(stroke
			(width 0.047498)
			(type default)
		)
		(layer "B.Cu")
	)
	(gr_line
		(start 199.017382 -25.724866)
		(end 199.327008 -25.933654)
		(stroke
			(width 0.06223)
			(type default)
		)
		(layer "B.Cu")
	)
	(gr_line
		(start 199.03186 -80.815942)
		(end 199.089518 -80.8736)
		(stroke
			(width 0.072898)
			(type default)
		)
		(layer "B.Cu")
	)
	(gr_line
		(start 199.032114 -81.489804)
		(end 199.089518 -81.4324)
		(stroke
			(width 0.072898)
			(type default)
		)
		(layer "B.Cu")
	)
	(gr_line
		(start 199.061578 -23.67661)
		(end 199.43191 -23.602442)
		(stroke
			(width 0.06223)
			(type default)
		)
		(layer "B.Cu")
	)
	(gr_line
		(start 199.086978 -28.622752)
		(end 199.457564 -28.550616)
		(stroke
			(width 0.06223)
			(type default)
		)
		(layer "B.Cu")
	)
	(gr_line
		(start 199.10425 -76.542646)
		(end 199.623934 -77.061314)
		(stroke
			(width 0.047498)
			(type default)
		)
		(layer "B.Cu")
	)
	(gr_line
		(start 199.10425 -74.797158)
		(end 199.10425 -76.542646)
		(stroke
			(width 0.047498)
			(type default)
		)
		(layer "B.Cu")
	)
	(gr_line
		(start 199.10425 -74.776838)
		(end 199.10425 -74.794618)
		(stroke
			(width 0.047498)
			(type default)
		)
		(layer "B.Cu")
	)
	(gr_line
		(start 199.10425 -74.776838)
		(end 199.201532 -74.692256)
		(stroke
			(width 0.047498)
			(type default)
		)
		(layer "B.Cu")
	)
	(gr_line
		(start 199.211184 -25.040844)
		(end 199.888602 -25.49779)
		(stroke
			(width 0.06223)
			(type default)
		)
		(layer "B.Cu")
	)
	(gr_line
		(start 199.327008 -25.933654)
		(end 199.69734 -25.861772)
		(stroke
			(width 0.06223)
			(type default)
		)
		(layer "B.Cu")
	)
	(gr_line
		(start 199.392032 -76.010516)
		(end 200.008236 -76.62672)
		(stroke
			(width 0.047498)
			(type default)
		)
		(layer "B.Cu")
	)
	(gr_line
		(start 199.392032 -75.220576)
		(end 199.392032 -76.010516)
		(stroke
			(width 0.047498)
			(type default)
		)
		(layer "B.Cu")
	)
	(gr_line
		(start 199.392032 -75.220576)
		(end 199.392032 -75.359768)
		(stroke
			(width 0.047498)
			(type default)
		)
		(layer "B.Cu")
	)
	(gr_line
		(start 199.392032 -75.213718)
		(end 199.392032 -75.359768)
		(stroke
			(width 0.047498)
			(type default)
		)
		(layer "B.Cu")
	)
	(gr_line
		(start 199.392032 -75.213718)
		(end 199.6059 -74.99985)
		(stroke
			(width 0.047498)
			(type default)
		)
		(layer "B.Cu")
	)
	(gr_line
		(start 199.493886 -77.281786)
		(end 199.51065 -77.29855)
		(stroke
			(width 0.047498)
			(type default)
		)
		(layer "B.Cu")
	)
	(gr_line
		(start 199.493886 -77.260958)
		(end 199.493886 -77.281786)
		(stroke
			(width 0.047498)
			(type default)
		)
		(layer "B.Cu")
	)
	(gr_line
		(start 199.493886 -77.19187)
		(end 199.493886 -77.258418)
		(stroke
			(width 0.047498)
			(type default)
		)
		(layer "B.Cu")
	)
	(gr_line
		(start 199.51065 -77.29855)
		(end 199.628506 -77.416406)
		(stroke
			(width 0.072898)
			(type default)
		)
		(layer "B.Cu")
	)
	(gr_line
		(start 199.576182 -75.934062)
		(end 200.138792 -76.496672)
		(stroke
			(width 0.047498)
			(type default)
		)
		(layer "B.Cu")
	)
	(gr_line
		(start 199.576182 -75.290172)
		(end 199.576182 -75.934062)
		(stroke
			(width 0.047498)
			(type default)
		)
		(layer "B.Cu")
	)
	(gr_line
		(start 199.576182 -75.290172)
		(end 199.855328 -75.011026)
		(stroke
			(width 0.047498)
			(type default)
		)
		(layer "B.Cu")
	)
	(gr_line
		(start 199.6059 -74.98207)
		(end 199.6059 -74.99985)
		(stroke
			(width 0.047498)
			(type default)
		)
		(layer "B.Cu")
	)
	(gr_line
		(start 199.6059 -74.29373)
		(end 199.6059 -74.978514)
		(stroke
			(width 0.047498)
			(type default)
		)
		(layer "B.Cu")
	)
	(gr_line
		(start 199.6059 -74.29373)
		(end 199.999854 -73.899776)
		(stroke
			(width 0.047498)
			(type default)
		)
		(layer "B.Cu")
	)
	(gr_line
		(start 199.623934 -77.061314)
		(end 199.624188 -77.061568)
		(stroke
			(width 0.047498)
			(type default)
		)
		(layer "B.Cu")
	)
	(gr_line
		(start 199.624188 -77.061568)
		(end 199.690736 -77.061568)
		(stroke
			(width 0.047498)
			(type default)
		)
		(layer "B.Cu")
	)
	(gr_line
		(start 199.693276 -77.061568)
		(end 199.71385 -77.061568)
		(stroke
			(width 0.047498)
			(type default)
		)
		(layer "B.Cu")
	)
	(gr_line
		(start 199.71385 -77.061568)
		(end 199.730614 -77.078332)
		(stroke
			(width 0.047498)
			(type default)
		)
		(layer "B.Cu")
	)
	(gr_line
		(start 199.746616 -23.812246)
		(end 199.82053 -24.182324)
		(stroke
			(width 0.06223)
			(type default)
		)
		(layer "B.Cu")
	)
	(gr_line
		(start 199.770746 -28.761944)
		(end 199.842882 -29.13253)
		(stroke
			(width 0.06223)
			(type default)
		)
		(layer "B.Cu")
	)
	(gr_line
		(start 199.796908 -22.009862)
		(end 199.870822 -22.37994)
		(stroke
			(width 0.06223)
			(type default)
		)
		(layer "B.Cu")
	)
	(gr_line
		(start 199.800718 -81.4324)
		(end 199.932798 -81.56448)
		(stroke
			(width 0.068326)
			(type default)
		)
		(layer "B.Cu")
	)
	(gr_line
		(start 199.800718 -80.8736)
		(end 199.858376 -80.815942)
		(stroke
			(width 0.072898)
			(type default)
		)
		(layer "B.Cu")
	)
	(gr_line
		(start 199.82053 -24.182324)
		(end 200.131172 -24.389588)
		(stroke
			(width 0.06223)
			(type default)
		)
		(layer "B.Cu")
	)
	(gr_line
		(start 199.842882 -29.13253)
		(end 200.152508 -29.341318)
		(stroke
			(width 0.06223)
			(type default)
		)
		(layer "B.Cu")
	)
	(gr_line
		(start 199.855328 -75.011026)
		(end 200.001632 -74.694796)
		(stroke
			(width 0.047498)
			(type default)
		)
		(layer "B.Cu")
	)
	(gr_line
		(start 199.870822 -22.37994)
		(end 200.181718 -22.58695)
		(stroke
			(width 0.06223)
			(type default)
		)
		(layer "B.Cu")
	)
	(gr_line
		(start 200.006712 -23.493984)
		(end 200.694544 -23.952454)
		(stroke
			(width 0.06223)
			(type default)
		)
		(layer "B.Cu")
	)
	(gr_line
		(start 200.008236 -76.716636)
		(end 200.025 -76.7334)
		(stroke
			(width 0.047498)
			(type default)
		)
		(layer "B.Cu")
	)
	(gr_line
		(start 200.008236 -76.696062)
		(end 200.008236 -76.716636)
		(stroke
			(width 0.047498)
			(type default)
		)
		(layer "B.Cu")
	)
	(gr_line
		(start 200.008236 -76.62672)
		(end 200.008236 -76.693522)
		(stroke
			(width 0.047498)
			(type default)
		)
		(layer "B.Cu")
	)
	(gr_line
		(start 200.01103 -26.0731)
		(end 200.082912 -26.443686)
		(stroke
			(width 0.06223)
			(type default)
		)
		(layer "B.Cu")
	)
	(gr_line
		(start 200.025 -76.7334)
		(end 200.14311 -76.85151)
		(stroke
			(width 0.072898)
			(type default)
		)
		(layer "B.Cu")
	)
	(gr_line
		(start 200.033128 -28.44546)
		(end 200.717912 -28.907486)
		(stroke
			(width 0.06223)
			(type default)
		)
		(layer "B.Cu")
	)
	(gr_line
		(start 200.058274 -21.692616)
		(end 200.742804 -22.1488)
		(stroke
			(width 0.06223)
			(type default)
		)
		(layer "B.Cu")
	)
	(gr_line
		(start 200.082912 -26.443686)
		(end 200.392538 -26.652474)
		(stroke
			(width 0.06223)
			(type default)
		)
		(layer "B.Cu")
	)
	(gr_line
		(start 200.131172 -24.389588)
		(end 200.50125 -24.31542)
		(stroke
			(width 0.06223)
			(type default)
		)
		(layer "B.Cu")
	)
	(gr_line
		(start 200.138792 -76.496672)
		(end 200.205086 -76.496672)
		(stroke
			(width 0.047498)
			(type default)
		)
		(layer "B.Cu")
	)
	(gr_line
		(start 200.152508 -29.341318)
		(end 200.52284 -29.269182)
		(stroke
			(width 0.06223)
			(type default)
		)
		(layer "B.Cu")
	)
	(gr_line
		(start 200.180448 -84.299806)
		(end 200.243948 -84.236306)
		(stroke
			(width 0.072898)
			(type default)
		)
		(layer "B.Cu")
	)
	(gr_line
		(start 200.181718 -22.58695)
		(end 200.551542 -22.513036)
		(stroke
			(width 0.06223)
			(type default)
		)
		(layer "B.Cu")
	)
	(gr_line
		(start 200.207626 -76.496672)
		(end 200.228454 -76.496672)
		(stroke
			(width 0.047498)
			(type default)
		)
		(layer "B.Cu")
	)
	(gr_line
		(start 200.228454 -76.496672)
		(end 200.245218 -76.513436)
		(stroke
			(width 0.047498)
			(type default)
		)
		(layer "B.Cu")
	)
	(gr_line
		(start 200.245218 -76.513436)
		(end 200.363074 -76.631292)
		(stroke
			(width 0.072898)
			(type default)
		)
		(layer "B.Cu")
	)
	(gr_line
		(start 200.24598 -81.545938)
		(end 200.359518 -81.4324)
		(stroke
			(width 0.072898)
			(type default)
		)
		(layer "B.Cu")
	)
	(gr_line
		(start 200.276206 -25.759156)
		(end 200.955656 -26.217372)
		(stroke
			(width 0.06223)
			(type default)
		)
		(layer "B.Cu")
	)
	(gr_line
		(start 200.30186 -80.815942)
		(end 200.359518 -80.8736)
		(stroke
			(width 0.072898)
			(type default)
		)
		(layer "B.Cu")
	)
	(gr_line
		(start 200.392538 -26.652474)
		(end 200.763124 -26.580338)
		(stroke
			(width 0.06223)
			(type default)
		)
		(layer "B.Cu")
	)
	(gr_line
		(start 200.79843 -73.903586)
		(end 200.963022 -73.903586)
		(stroke
			(width 0.04445)
			(type default)
		)
		(layer "B.Cu")
	)
	(gr_line
		(start 200.815702 -24.52497)
		(end 200.88987 -24.895302)
		(stroke
			(width 0.06223)
			(type default)
		)
		(layer "B.Cu")
	)
	(gr_line
		(start 200.866502 -22.72284)
		(end 200.940416 -23.092664)
		(stroke
			(width 0.06223)
			(type default)
		)
		(layer "B.Cu")
	)
	(gr_line
		(start 200.88987 -24.895302)
		(end 201.200512 -25.102312)
		(stroke
			(width 0.06223)
			(type default)
		)
		(layer "B.Cu")
	)
	(gr_line
		(start 200.940416 -23.092664)
		(end 201.251058 -23.299674)
		(stroke
			(width 0.06223)
			(type default)
		)
		(layer "B.Cu")
	)
	(gr_arc
		(start 201.026268 -73.929748)
		(mid 200.997264 -73.910335)
		(end 200.963022 -73.903586)
		(stroke
			(width 0.04445)
			(type default)
		)
		(layer "B.Cu")
	)
	(gr_line
		(start 201.026268 -73.929748)
		(end 201.036936 -73.94067)
		(stroke
			(width 0.04445)
			(type default)
		)
		(layer "B.Cu")
	)
	(gr_line
		(start 201.070718 -81.4324)
		(end 201.18705 -81.548732)
		(stroke
			(width 0.072898)
			(type default)
		)
		(layer "B.Cu")
	)
	(gr_line
		(start 201.070718 -80.8736)
		(end 201.128376 -80.815942)
		(stroke
			(width 0.072898)
			(type default)
		)
		(layer "B.Cu")
	)
	(gr_arc
		(start 201.07402 -74.029824)
		(mid 201.064328 -73.981568)
		(end 201.036936 -73.94067)
		(stroke
			(width 0.04445)
			(type default)
		)
		(layer "B.Cu")
	)
	(gr_line
		(start 201.074782 -24.205946)
		(end 201.7649 -24.66594)
		(stroke
			(width 0.06223)
			(type default)
		)
		(layer "B.Cu")
	)
	(gr_line
		(start 201.076306 -26.79192)
		(end 201.148442 -27.162252)
		(stroke
			(width 0.06223)
			(type default)
		)
		(layer "B.Cu")
	)
	(gr_line
		(start 201.129138 -22.406356)
		(end 201.81316 -22.862286)
		(stroke
			(width 0.06223)
			(type default)
		)
		(layer "B.Cu")
	)
	(gr_line
		(start 201.148442 -27.162252)
		(end 201.458068 -27.37104)
		(stroke
			(width 0.06223)
			(type default)
		)
		(layer "B.Cu")
	)
	(gr_line
		(start 201.200512 -25.102312)
		(end 201.570844 -25.028144)
		(stroke
			(width 0.06223)
			(type default)
		)
		(layer "B.Cu")
	)
	(gr_line
		(start 201.251058 -23.299674)
		(end 201.621136 -23.22576)
		(stroke
			(width 0.06223)
			(type default)
		)
		(layer "B.Cu")
	)
	(gr_arc
		(start 201.304144 -73.94321)
		(mid 201.274888 -73.986903)
		(end 201.26452 -74.03846)
		(stroke
			(width 0.04445)
			(type default)
		)
		(layer "B.Cu")
	)
	(gr_line
		(start 201.304144 -73.94321)
		(end 201.317352 -73.929748)
		(stroke
			(width 0.04445)
			(type default)
		)
		(layer "B.Cu")
	)
	(gr_line
		(start 201.341736 -26.477976)
		(end 202.020424 -26.935684)
		(stroke
			(width 0.06223)
			(type default)
		)
		(layer "B.Cu")
	)
	(gr_arc
		(start 201.380598 -73.903586)
		(mid 201.346348 -73.910323)
		(end 201.317352 -73.929748)
		(stroke
			(width 0.04445)
			(type default)
		)
		(layer "B.Cu")
	)
	(gr_line
		(start 201.380598 -73.903586)
		(end 201.598276 -73.903586)
		(stroke
			(width 0.04445)
			(type default)
		)
		(layer "B.Cu")
	)
	(gr_line
		(start 201.458068 -27.37104)
		(end 201.8284 -27.299158)
		(stroke
			(width 0.06223)
			(type default)
		)
		(layer "B.Cu")
	)
	(gr_line
		(start 201.503026 -81.558638)
		(end 201.629518 -81.4324)
		(stroke
			(width 0.072898)
			(type default)
		)
		(layer "B.Cu")
	)
	(gr_line
		(start 201.57186 -80.815942)
		(end 201.629518 -80.8736)
		(stroke
			(width 0.072898)
			(type default)
		)
		(layer "B.Cu")
	)
	(gr_line
		(start 201.593196 -67.309492)
		(end 201.593196 -67.502532)
		(stroke
			(width 0.04445)
			(type default)
		)
		(layer "B.Cu")
	)
	(gr_line
		(start 201.59345 -72.10425)
		(end 201.59345 -72.297798)
		(stroke
			(width 0.04445)
			(type default)
		)
		(layer "B.Cu")
	)
	(gr_line
		(start 201.59345 -70.702678)
		(end 201.995532 -71.106538)
		(stroke
			(width 0.04445)
			(type default)
		)
		(layer "B.Cu")
	)
	(gr_arc
		(start 201.594466 -71.695056)
		(mid 201.626738 -71.773032)
		(end 201.704702 -71.805292)
		(stroke
			(width 0.04445)
			(type default)
		)
		(layer "B.Cu")
	)
	(gr_line
		(start 201.594466 -71.503032)
		(end 201.594466 -71.695056)
		(stroke
			(width 0.04445)
			(type default)
		)
		(layer "B.Cu")
	)
	(gr_arc
		(start 201.595228 -69.28104)
		(mid 201.63311 -69.372428)
		(end 201.724514 -69.410326)
		(stroke
			(width 0.04445)
			(type default)
		)
		(layer "B.Cu")
	)
	(gr_line
		(start 201.595228 -69.104256)
		(end 201.595228 -69.28104)
		(stroke
			(width 0.04445)
			(type default)
		)
		(layer "B.Cu")
	)
	(gr_line
		(start 201.595482 -68.397882)
		(end 201.901806 -68.704206)
		(stroke
			(width 0.04445)
			(type default)
		)
		(layer "B.Cu")
	)
	(gr_line
		(start 201.595482 -68.295266)
		(end 201.595482 -68.397882)
		(stroke
			(width 0.04445)
			(type default)
		)
		(layer "B.Cu")
	)
	(gr_arc
		(start 201.599546 -66.889376)
		(mid 201.608795 -66.936302)
		(end 201.635106 -66.976244)
		(stroke
			(width 0.04445)
			(type default)
		)
		(layer "B.Cu")
	)
	(gr_line
		(start 201.599546 -66.709036)
		(end 201.599546 -66.889376)
		(stroke
			(width 0.04445)
			(type default)
		)
		(layer "B.Cu")
	)
	(gr_line
		(start 201.5998 -75.499722)
		(end 201.737976 -75.499722)
		(stroke
			(width 0.04445)
			(type default)
		)
		(layer "B.Cu")
	)
	(gr_line
		(start 201.600562 -73.100438)
		(end 201.99477 -73.494646)
		(stroke
			(width 0.04445)
			(type default)
		)
		(layer "B.Cu")
	)
	(gr_line
		(start 201.609198 -69.706744)
		(end 201.609198 -69.899784)
		(stroke
			(width 0.04445)
			(type default)
		)
		(layer "B.Cu")
	)
	(gr_arc
		(start 201.624692 -67.234054)
		(mid 201.601403 -67.268622)
		(end 201.593196 -67.309492)
		(stroke
			(width 0.04445)
			(type default)
		)
		(layer "B.Cu")
	)
	(gr_line
		(start 201.624692 -67.234054)
		(end 201.624946 -67.2338)
		(stroke
			(width 0.04445)
			(type default)
		)
		(layer "B.Cu")
	)
	(gr_line
		(start 201.635106 -66.976244)
		(end 201.645266 -66.986658)
		(stroke
			(width 0.04445)
			(type default)
		)
		(layer "B.Cu")
	)
	(gr_arc
		(start 201.640694 -69.631306)
		(mid 201.617405 -69.665874)
		(end 201.609198 -69.706744)
		(stroke
			(width 0.04445)
			(type default)
		)
		(layer "B.Cu")
	)
	(gr_line
		(start 201.640694 -69.631306)
		(end 201.640948 -69.631052)
		(stroke
			(width 0.04445)
			(type default)
		)
		(layer "B.Cu")
	)
	(gr_arc
		(start 201.645266 -66.986658)
		(mid 201.674245 -67.006189)
		(end 201.708512 -67.013074)
		(stroke
			(width 0.04445)
			(type default)
		)
		(layer "B.Cu")
	)
	(gr_arc
		(start 201.674222 -71.999348)
		(mid 201.615958 -72.038041)
		(end 201.59345 -72.10425)
		(stroke
			(width 0.04445)
			(type default)
		)
		(layer "B.Cu")
	)
	(gr_arc
		(start 201.698606 -67.203574)
		(mid 201.658794 -67.211422)
		(end 201.624946 -67.2338)
		(stroke
			(width 0.04445)
			(type default)
		)
		(layer "B.Cu")
	)
	(gr_arc
		(start 201.701654 -71.996046)
		(mid 201.687835 -71.996834)
		(end 201.674222 -71.999348)
		(stroke
			(width 0.04445)
			(type default)
		)
		(layer "B.Cu")
	)
	(gr_arc
		(start 201.704702 -71.805292)
		(mid 201.706606 -71.805435)
		(end 201.708512 -71.805546)
		(stroke
			(width 0.04445)
			(type default)
		)
		(layer "B.Cu")
	)
	(gr_arc
		(start 201.714608 -69.600826)
		(mid 201.674796 -69.608674)
		(end 201.640948 -69.631052)
		(stroke
			(width 0.04445)
			(type default)
		)
		(layer "B.Cu")
	)
	(gr_arc
		(start 201.845926 -75.544426)
		(mid 201.796395 -75.511345)
		(end 201.737976 -75.499722)
		(stroke
			(width 0.04445)
			(type default)
		)
		(layer "B.Cu")
	)
	(gr_line
		(start 201.885042 -25.237694)
		(end 201.959464 -25.608026)
		(stroke
			(width 0.06223)
			(type default)
		)
		(layer "B.Cu")
	)
	(gr_arc
		(start 201.89063 -75.652376)
		(mid 201.879033 -75.593943)
		(end 201.845926 -75.544426)
		(stroke
			(width 0.04445)
			(type default)
		)
		(layer "B.Cu")
	)
	(gr_arc
		(start 201.89952 -67.013074)
		(mid 201.899012 -67.013073)
		(end 201.898504 -67.013074)
		(stroke
			(width 0.04445)
			(type default)
		)
		(layer "B.Cu")
	)
	(gr_line
		(start 201.901806 -68.704206)
		(end 202.417426 -68.704206)
		(stroke
			(width 0.04445)
			(type default)
		)
		(layer "B.Cu")
	)
	(gr_line
		(start 201.936096 -23.435564)
		(end 202.01001 -23.805388)
		(stroke
			(width 0.06223)
			(type default)
		)
		(layer "B.Cu")
	)
	(gr_line
		(start 201.954638 -71.996046)
		(end 201.965052 -71.996046)
		(stroke
			(width 0.04445)
			(type default)
		)
		(layer "B.Cu")
	)
	(gr_line
		(start 201.959464 -25.608026)
		(end 202.270106 -25.815036)
		(stroke
			(width 0.06223)
			(type default)
		)
		(layer "B.Cu")
	)
	(gr_line
		(start 201.99477 -73.494646)
		(end 202.228704 -73.494646)
		(stroke
			(width 0.04445)
			(type default)
		)
		(layer "B.Cu")
	)
	(gr_line
		(start 201.995532 -71.106538)
		(end 202.423014 -71.106538)
		(stroke
			(width 0.04445)
			(type default)
		)
		(layer "B.Cu")
	)
	(gr_line
		(start 202.004168 -69.600826)
		(end 202.079606 -69.676264)
		(stroke
			(width 0.04445)
			(type default)
		)
		(layer "B.Cu")
	)
	(gr_line
		(start 202.01001 -23.805388)
		(end 202.320652 -24.012398)
		(stroke
			(width 0.06223)
			(type default)
		)
		(layer "B.Cu")
	)
	(gr_line
		(start 202.079606 -69.40677)
		(end 202.07605 -69.410326)
		(stroke
			(width 0.04445)
			(type default)
		)
		(layer "B.Cu")
	)
	(gr_arc
		(start 202.126342 -75.545188)
		(mid 202.092859 -75.595299)
		(end 202.08113 -75.654408)
		(stroke
			(width 0.04445)
			(type default)
		)
		(layer "B.Cu")
	)
	(gr_line
		(start 202.14209 -27.510486)
		(end 202.213972 -27.881072)
		(stroke
			(width 0.06223)
			(type default)
		)
		(layer "B.Cu")
	)
	(gr_line
		(start 202.144122 -24.91867)
		(end 202.833478 -25.378156)
		(stroke
			(width 0.06223)
			(type default)
		)
		(layer "B.Cu")
	)
	(gr_line
		(start 202.145138 -71.906638)
		(end 202.155552 -71.906638)
		(stroke
			(width 0.04445)
			(type default)
		)
		(layer "B.Cu")
	)
	(gr_line
		(start 202.198478 -23.11908)
		(end 202.881738 -23.574248)
		(stroke
			(width 0.06223)
			(type default)
		)
		(layer "B.Cu")
	)
	(gr_line
		(start 202.213972 -27.881072)
		(end 202.523598 -28.08986)
		(stroke
			(width 0.06223)
			(type default)
		)
		(layer "B.Cu")
	)
	(gr_line
		(start 202.228704 -73.494646)
		(end 202.231244 -73.497186)
		(stroke
			(width 0.04445)
			(type default)
		)
		(layer "B.Cu")
	)
	(gr_line
		(start 202.231244 -73.497186)
		(end 202.413616 -73.497186)
		(stroke
			(width 0.04445)
			(type default)
		)
		(layer "B.Cu")
	)
	(gr_arc
		(start 202.23607 -75.499722)
		(mid 202.17668 -75.511535)
		(end 202.126342 -75.545188)
		(stroke
			(width 0.04445)
			(type default)
		)
		(layer "B.Cu")
	)
	(gr_line
		(start 202.23607 -75.499722)
		(end 202.399646 -75.499722)
		(stroke
			(width 0.04445)
			(type default)
		)
		(layer "B.Cu")
	)
	(gr_line
		(start 202.270106 -25.815036)
		(end 202.640184 -25.741122)
		(stroke
			(width 0.06223)
			(type default)
		)
		(layer "B.Cu")
	)
	(gr_line
		(start 202.320652 -24.012398)
		(end 202.69073 -23.938484)
		(stroke
			(width 0.06223)
			(type default)
		)
		(layer "B.Cu")
	)
	(gr_line
		(start 202.397106 -73.097136)
		(end 202.604116 -73.304146)
		(stroke
			(width 0.04445)
			(type default)
		)
		(layer "B.Cu")
	)
	(gr_line
		(start 202.3999 -68.30314)
		(end 202.607926 -68.511166)
		(stroke
			(width 0.04445)
			(type default)
		)
		(layer "B.Cu")
	)
	(gr_line
		(start 202.404472 -70.704456)
		(end 202.551284 -70.851268)
		(stroke
			(width 0.04445)
			(type default)
		)
		(layer "B.Cu")
	)
	(gr_line
		(start 202.405996 -27.195526)
		(end 203.088494 -27.655774)
		(stroke
			(width 0.06223)
			(type default)
		)
		(layer "B.Cu")
	)
	(gr_line
		(start 202.523598 -28.08986)
		(end 202.89393 -28.017724)
		(stroke
			(width 0.06223)
			(type default)
		)
		(layer "B.Cu")
	)
	(gr_line
		(start 202.553062 -70.853046)
		(end 202.616054 -70.916038)
		(stroke
			(width 0.04445)
			(type default)
		)
		(layer "B.Cu")
	)
	(gr_line
		(start 202.56881 -71.106538)
		(end 202.631802 -71.16953)
		(stroke
			(width 0.04445)
			(type default)
		)
		(layer "B.Cu")
	)
	(gr_line
		(start 203.005436 -24.148034)
		(end 203.079604 -24.518112)
		(stroke
			(width 0.06223)
			(type default)
		)
		(layer "B.Cu")
	)
	(gr_line
		(start 203.079604 -24.518112)
		(end 203.390246 -24.725122)
		(stroke
			(width 0.06223)
			(type default)
		)
		(layer "B.Cu")
	)
	(gr_line
		(start 203.267818 -23.831804)
		(end 203.848716 -24.218646)
		(stroke
			(width 0.06223)
			(type default)
		)
		(layer "B.Cu")
	)
	(gr_line
		(start 203.390246 -24.725122)
		(end 203.760324 -24.651208)
		(stroke
			(width 0.06223)
			(type default)
		)
		(layer "B.Cu")
	)
	(gr_line
		(start 203.65085 -76.357226)
		(end 203.840334 -76.357226)
		(stroke
			(width 0.04445)
			(type default)
		)
		(layer "B.Cu")
	)
	(gr_line
		(start 203.840334 -76.357226)
		(end 203.88072 -76.31684)
		(stroke
			(width 0.04445)
			(type default)
		)
		(layer "B.Cu")
	)
	(gr_line
		(start 203.842366 -76.547726)
		(end 203.88072 -76.58608)
		(stroke
			(width 0.04445)
			(type default)
		)
		(layer "B.Cu")
	)
	(gr_line
		(start 203.848716 -24.218646)
		(end 203.952856 -24.287988)
		(stroke
			(width 0.06223)
			(type default)
		)
		(layer "B.Cu")
	)
	(gr_line
		(start 203.882498 -76.587858)
		(end 203.9493 -76.65466)
		(stroke
			(width 0.04445)
			(type default)
		)
		(layer "B.Cu")
	)
	(gr_line
		(start 203.882498 -76.315062)
		(end 203.9493 -76.24826)
		(stroke
			(width 0.04445)
			(type default)
		)
		(layer "B.Cu")
	)
	(gr_line
		(start 203.9493 -76.65466)
		(end 204.138784 -76.65466)
		(stroke
			(width 0.06223)
			(type default)
		)
		(layer "B.Cu")
	)
	(gr_line
		(start 204.22743 -75.46594)
		(end 204.2668 -75.50531)
		(stroke
			(width 0.04445)
			(type default)
		)
		(layer "B.Cu")
	)
	(gr_line
		(start 204.22743 -75.27544)
		(end 204.2668 -75.23607)
		(stroke
			(width 0.04445)
			(type default)
		)
		(layer "B.Cu")
	)
	(gr_line
		(start 204.268578 -75.507088)
		(end 204.33538 -75.57389)
		(stroke
			(width 0.04445)
			(type default)
		)
		(layer "B.Cu")
	)
	(gr_line
		(start 204.268578 -75.234292)
		(end 204.33538 -75.16749)
		(stroke
			(width 0.04445)
			(type default)
		)
		(layer "B.Cu")
	)
	(gr_line
		(start 204.33538 -75.57389)
		(end 204.357478 -75.57389)
		(stroke
			(width 0.04445)
			(type default)
		)
		(layer "B.Cu")
	)
	(gr_line
		(start 204.33538 -75.16749)
		(end 204.357478 -75.16749)
		(stroke
			(width 0.04445)
			(type default)
		)
		(layer "B.Cu")
	)
	(gr_line
		(start 204.527912 -72.32523)
		(end 204.567282 -72.3646)
		(stroke
			(width 0.04445)
			(type default)
		)
		(layer "B.Cu")
	)
	(gr_line
		(start 204.527912 -72.13473)
		(end 204.567282 -72.09536)
		(stroke
			(width 0.04445)
			(type default)
		)
		(layer "B.Cu")
	)
	(gr_line
		(start 204.56906 -72.366378)
		(end 204.635862 -72.43318)
		(stroke
			(width 0.04445)
			(type default)
		)
		(layer "B.Cu")
	)
	(gr_line
		(start 204.56906 -72.093582)
		(end 204.635862 -72.02678)
		(stroke
			(width 0.04445)
			(type default)
		)
		(layer "B.Cu")
	)
	(gr_line
		(start 204.57033 -43.487086)
		(end 204.606652 -43.494452)
		(stroke
			(width 0.06223)
			(type default)
		)
		(layer "B.Cu")
	)
	(gr_line
		(start 204.606652 -43.494452)
		(end 204.637894 -43.515534)
		(stroke
			(width 0.06223)
			(type default)
		)
		(layer "B.Cu")
	)
	(gr_line
		(start 204.635862 -72.43318)
		(end 204.65796 -72.43318)
		(stroke
			(width 0.04445)
			(type default)
		)
		(layer "B.Cu")
	)
	(gr_line
		(start 204.635862 -72.02678)
		(end 204.65796 -72.02678)
		(stroke
			(width 0.04445)
			(type default)
		)
		(layer "B.Cu")
	)
	(gr_line
		(start 205.599538 -42.38244)
		(end 205.646274 -42.391838)
		(stroke
			(width 0.06223)
			(type default)
		)
		(layer "B.Cu")
	)
	(gr_line
		(start 205.646274 -42.391838)
		(end 205.684628 -42.420286)
		(stroke
			(width 0.06223)
			(type default)
		)
		(layer "B.Cu")
	)
	(gr_line
		(start 205.701646 -32.76219)
		(end 205.773782 -33.132776)
		(stroke
			(width 0.06223)
			(type default)
		)
		(layer "B.Cu")
	)
	(gr_line
		(start 205.773782 -33.132776)
		(end 206.083154 -33.341564)
		(stroke
			(width 0.06223)
			(type default)
		)
		(layer "B.Cu")
	)
	(gr_line
		(start 205.964536 -32.446214)
		(end 206.648558 -32.907478)
		(stroke
			(width 0.06223)
			(type default)
		)
		(layer "B.Cu")
	)
	(gr_line
		(start 205.990444 -70.188582)
		(end 206.029814 -70.227952)
		(stroke
			(width 0.04445)
			(type default)
		)
		(layer "B.Cu")
	)
	(gr_line
		(start 205.990444 -69.998082)
		(end 206.029814 -69.958712)
		(stroke
			(width 0.04445)
			(type default)
		)
		(layer "B.Cu")
	)
	(gr_line
		(start 206.031592 -70.22973)
		(end 206.098394 -70.296532)
		(stroke
			(width 0.04445)
			(type default)
		)
		(layer "B.Cu")
	)
	(gr_line
		(start 206.031592 -69.956934)
		(end 206.098394 -69.890132)
		(stroke
			(width 0.04445)
			(type default)
		)
		(layer "B.Cu")
	)
	(gr_line
		(start 206.083154 -33.341564)
		(end 206.453994 -33.269428)
		(stroke
			(width 0.06223)
			(type default)
		)
		(layer "B.Cu")
	)
	(gr_line
		(start 206.098394 -70.296532)
		(end 206.120492 -70.296532)
		(stroke
			(width 0.04445)
			(type default)
		)
		(layer "B.Cu")
	)
	(gr_line
		(start 206.098394 -69.890132)
		(end 206.120492 -69.890132)
		(stroke
			(width 0.04445)
			(type default)
		)
		(layer "B.Cu")
	)
	(gr_line
		(start 206.151734 -30.215332)
		(end 206.22387 -30.585918)
		(stroke
			(width 0.06223)
			(type default)
		)
		(layer "B.Cu")
	)
	(gr_line
		(start 206.180436 -41.20769)
		(end 206.226918 -41.217088)
		(stroke
			(width 0.06223)
			(type default)
		)
		(layer "B.Cu")
	)
	(gr_line
		(start 206.209392 -71.82485)
		(end 206.248762 -71.86422)
		(stroke
			(width 0.04445)
			(type default)
		)
		(layer "B.Cu")
	)
	(gr_line
		(start 206.209392 -71.63435)
		(end 206.248762 -71.59498)
		(stroke
			(width 0.04445)
			(type default)
		)
		(layer "B.Cu")
	)
	(gr_line
		(start 206.22387 -30.585918)
		(end 206.533496 -30.794706)
		(stroke
			(width 0.06223)
			(type default)
		)
		(layer "B.Cu")
	)
	(gr_line
		(start 206.226918 -41.217088)
		(end 206.26451 -41.245282)
		(stroke
			(width 0.06223)
			(type default)
		)
		(layer "B.Cu")
	)
	(gr_line
		(start 206.25054 -71.865998)
		(end 206.317342 -71.9328)
		(stroke
			(width 0.04445)
			(type default)
		)
		(layer "B.Cu")
	)
	(gr_line
		(start 206.25054 -71.593202)
		(end 206.317342 -71.5264)
		(stroke
			(width 0.04445)
			(type default)
		)
		(layer "B.Cu")
	)
	(gr_line
		(start 206.317342 -71.9328)
		(end 206.33944 -71.9328)
		(stroke
			(width 0.04445)
			(type default)
		)
		(layer "B.Cu")
	)
	(gr_line
		(start 206.317342 -71.5264)
		(end 206.33944 -71.5264)
		(stroke
			(width 0.04445)
			(type default)
		)
		(layer "B.Cu")
	)
	(gr_line
		(start 206.412846 -29.897832)
		(end 207.098392 -30.360366)
		(stroke
			(width 0.06223)
			(type default)
		)
		(layer "B.Cu")
	)
	(gr_line
		(start 206.415894 -28.257754)
		(end 206.489808 -28.627832)
		(stroke
			(width 0.06223)
			(type default)
		)
		(layer "B.Cu")
	)
	(gr_line
		(start 206.489808 -28.627832)
		(end 206.80045 -28.834842)
		(stroke
			(width 0.06223)
			(type default)
		)
		(layer "B.Cu")
	)
	(gr_line
		(start 206.533496 -30.794706)
		(end 206.904082 -30.722824)
		(stroke
			(width 0.06223)
			(type default)
		)
		(layer "B.Cu")
	)
	(gr_line
		(start 206.676752 -27.940254)
		(end 207.363822 -28.397962)
		(stroke
			(width 0.06223)
			(type default)
		)
		(layer "B.Cu")
	)
	(gr_line
		(start 206.700374 -39.98722)
		(end 206.74584 -39.996364)
		(stroke
			(width 0.06223)
			(type default)
		)
		(layer "B.Cu")
	)
	(gr_line
		(start 206.74584 -39.996364)
		(end 206.783432 -40.024304)
		(stroke
			(width 0.06223)
			(type default)
		)
		(layer "B.Cu")
	)
	(gr_line
		(start 206.767176 -33.48101)
		(end 206.839312 -33.851596)
		(stroke
			(width 0.06223)
			(type default)
		)
		(layer "B.Cu")
	)
	(gr_line
		(start 206.80045 -28.834842)
		(end 207.170528 -28.760928)
		(stroke
			(width 0.06223)
			(type default)
		)
		(layer "B.Cu")
	)
	(gr_line
		(start 206.839312 -33.851596)
		(end 207.148684 -34.060384)
		(stroke
			(width 0.06223)
			(type default)
		)
		(layer "B.Cu")
	)
	(gr_line
		(start 207.029304 -33.164272)
		(end 207.715104 -33.626806)
		(stroke
			(width 0.06223)
			(type default)
		)
		(layer "B.Cu")
	)
	(gr_line
		(start 207.111346 -74.59345)
		(end 207.150716 -74.63282)
		(stroke
			(width 0.04445)
			(type default)
		)
		(layer "B.Cu")
	)
	(gr_line
		(start 207.111346 -74.40295)
		(end 207.150716 -74.36358)
		(stroke
			(width 0.04445)
			(type default)
		)
		(layer "B.Cu")
	)
	(gr_line
		(start 207.148684 -34.060384)
		(end 207.519524 -33.988248)
		(stroke
			(width 0.06223)
			(type default)
		)
		(layer "B.Cu")
	)
	(gr_line
		(start 207.152494 -74.634598)
		(end 207.219296 -74.7014)
		(stroke
			(width 0.04445)
			(type default)
		)
		(layer "B.Cu")
	)
	(gr_line
		(start 207.152494 -74.361802)
		(end 207.219296 -74.295)
		(stroke
			(width 0.04445)
			(type default)
		)
		(layer "B.Cu")
	)
	(gr_line
		(start 207.169766 -68.220082)
		(end 207.209136 -68.259452)
		(stroke
			(width 0.04445)
			(type default)
		)
		(layer "B.Cu")
	)
	(gr_line
		(start 207.169766 -68.029582)
		(end 207.209136 -67.990212)
		(stroke
			(width 0.04445)
			(type default)
		)
		(layer "B.Cu")
	)
	(gr_line
		(start 207.169766 -67.003422)
		(end 207.209136 -67.042792)
		(stroke
			(width 0.04445)
			(type default)
		)
		(layer "B.Cu")
	)
	(gr_line
		(start 207.169766 -66.812922)
		(end 207.209136 -66.773552)
		(stroke
			(width 0.04445)
			(type default)
		)
		(layer "B.Cu")
	)
	(gr_line
		(start 207.210914 -68.26123)
		(end 207.277716 -68.328032)
		(stroke
			(width 0.04445)
			(type default)
		)
		(layer "B.Cu")
	)
	(gr_line
		(start 207.210914 -67.988434)
		(end 207.277716 -67.921632)
		(stroke
			(width 0.04445)
			(type default)
		)
		(layer "B.Cu")
	)
	(gr_line
		(start 207.210914 -67.04457)
		(end 207.277716 -67.111372)
		(stroke
			(width 0.04445)
			(type default)
		)
		(layer "B.Cu")
	)
	(gr_line
		(start 207.210914 -66.771774)
		(end 207.277716 -66.704972)
		(stroke
			(width 0.04445)
			(type default)
		)
		(layer "B.Cu")
	)
	(gr_line
		(start 207.217264 -30.934152)
		(end 207.2894 -31.304738)
		(stroke
			(width 0.06223)
			(type default)
		)
		(layer "B.Cu")
	)
	(gr_line
		(start 207.219296 -74.7014)
		(end 207.241394 -74.7014)
		(stroke
			(width 0.04445)
			(type default)
		)
		(layer "B.Cu")
	)
	(gr_line
		(start 207.219296 -74.295)
		(end 207.241394 -74.295)
		(stroke
			(width 0.04445)
			(type default)
		)
		(layer "B.Cu")
	)
	(gr_line
		(start 207.277716 -68.328032)
		(end 207.299814 -68.328032)
		(stroke
			(width 0.04445)
			(type default)
		)
		(layer "B.Cu")
	)
	(gr_line
		(start 207.277716 -67.921632)
		(end 207.299814 -67.921632)
		(stroke
			(width 0.04445)
			(type default)
		)
		(layer "B.Cu")
	)
	(gr_line
		(start 207.277716 -67.111372)
		(end 207.299814 -67.111372)
		(stroke
			(width 0.04445)
			(type default)
		)
		(layer "B.Cu")
	)
	(gr_line
		(start 207.277716 -66.704972)
		(end 207.299814 -66.704972)
		(stroke
			(width 0.04445)
			(type default)
		)
		(layer "B.Cu")
	)
	(gr_line
		(start 207.2894 -31.304738)
		(end 207.599026 -31.513526)
		(stroke
			(width 0.06223)
			(type default)
		)
		(layer "B.Cu")
	)
	(gr_line
		(start 207.4799 -30.617668)
		(end 208.163922 -31.079186)
		(stroke
			(width 0.06223)
			(type default)
		)
		(layer "B.Cu")
	)
	(gr_line
		(start 207.485234 -28.970478)
		(end 207.559148 -29.340556)
		(stroke
			(width 0.06223)
			(type default)
		)
		(layer "B.Cu")
	)
	(gr_line
		(start 207.559148 -29.340556)
		(end 207.86979 -29.547566)
		(stroke
			(width 0.06223)
			(type default)
		)
		(layer "B.Cu")
	)
	(gr_line
		(start 207.599026 -31.513526)
		(end 207.969612 -31.44139)
		(stroke
			(width 0.06223)
			(type default)
		)
		(layer "B.Cu")
	)
	(gr_line
		(start 207.745076 -28.652216)
		(end 208.43367 -29.11094)
		(stroke
			(width 0.06223)
			(type default)
		)
		(layer "B.Cu")
	)
	(gr_line
		(start 207.832706 -34.199576)
		(end 207.904842 -34.570162)
		(stroke
			(width 0.06223)
			(type default)
		)
		(layer "B.Cu")
	)
	(gr_line
		(start 207.86979 -29.547566)
		(end 208.239868 -29.473652)
		(stroke
			(width 0.06223)
			(type default)
		)
		(layer "B.Cu")
	)
	(gr_line
		(start 207.904842 -34.570162)
		(end 208.214214 -34.77895)
		(stroke
			(width 0.06223)
			(type default)
		)
		(layer "B.Cu")
	)
	(gr_line
		(start 208.09458 -33.882838)
		(end 208.675986 -34.275014)
		(stroke
			(width 0.06223)
			(type default)
		)
		(layer "B.Cu")
	)
	(gr_line
		(start 208.214214 -34.77895)
		(end 208.585054 -34.706814)
		(stroke
			(width 0.06223)
			(type default)
		)
		(layer "B.Cu")
	)
	(gr_line
		(start 208.282794 -31.652718)
		(end 208.35493 -32.023304)
		(stroke
			(width 0.06223)
			(type default)
		)
		(layer "B.Cu")
	)
	(gr_line
		(start 208.35493 -32.023304)
		(end 208.664556 -32.232092)
		(stroke
			(width 0.06223)
			(type default)
		)
		(layer "B.Cu")
	)
	(gr_line
		(start 208.511902 -27.817572)
		(end 208.585816 -28.18765)
		(stroke
			(width 0.06223)
			(type default)
		)
		(layer "B.Cu")
	)
	(gr_line
		(start 208.54543 -31.336742)
		(end 209.229452 -31.798006)
		(stroke
			(width 0.06223)
			(type default)
		)
		(layer "B.Cu")
	)
	(gr_line
		(start 208.554574 -29.683202)
		(end 208.628488 -30.05328)
		(stroke
			(width 0.06223)
			(type default)
		)
		(layer "B.Cu")
	)
	(gr_line
		(start 208.585816 -28.18765)
		(end 208.896458 -28.39466)
		(stroke
			(width 0.06223)
			(type default)
		)
		(layer "B.Cu")
	)
	(gr_line
		(start 208.628488 -30.05328)
		(end 208.939384 -30.260544)
		(stroke
			(width 0.06223)
			(type default)
		)
		(layer "B.Cu")
	)
	(gr_line
		(start 208.664556 -32.232092)
		(end 209.034634 -32.16021)
		(stroke
			(width 0.06223)
			(type default)
		)
		(layer "B.Cu")
	)
	(gr_line
		(start 208.675986 -34.275014)
		(end 208.780126 -34.345118)
		(stroke
			(width 0.06223)
			(type default)
		)
		(layer "B.Cu")
	)
	(gr_line
		(start 208.77276 -27.500072)
		(end 209.45983 -27.95778)
		(stroke
			(width 0.06223)
			(type default)
		)
		(layer "B.Cu")
	)
	(gr_line
		(start 208.814924 -29.365194)
		(end 209.502756 -29.823664)
		(stroke
			(width 0.06223)
			(type default)
		)
		(layer "B.Cu")
	)
	(gr_line
		(start 208.896458 -28.39466)
		(end 209.26679 -28.320492)
		(stroke
			(width 0.06223)
			(type default)
		)
		(layer "B.Cu")
	)
	(gr_line
		(start 208.939384 -30.260544)
		(end 209.309462 -30.18663)
		(stroke
			(width 0.06223)
			(type default)
		)
		(layer "B.Cu")
	)
	(gr_line
		(start 209.466688 -46.774354)
		(end 209.568288 -46.842934)
		(stroke
			(width 0.06223)
			(type default)
		)
		(layer "B.Cu")
	)
	(gr_line
		(start 209.568288 -46.842934)
		(end 209.59191 -46.961552)
		(stroke
			(width 0.06223)
			(type default)
		)
		(layer "B.Cu")
	)
	(gr_line
		(start 209.580988 -28.530042)
		(end 209.65541 -28.900374)
		(stroke
			(width 0.06223)
			(type default)
		)
		(layer "B.Cu")
	)
	(gr_line
		(start 209.65541 -28.900374)
		(end 209.966052 -29.107384)
		(stroke
			(width 0.06223)
			(type default)
		)
		(layer "B.Cu")
	)
	(gr_line
		(start 209.841338 -28.212034)
		(end 210.528916 -28.67025)
		(stroke
			(width 0.06223)
			(type default)
		)
		(layer "B.Cu")
	)
	(gr_line
		(start 209.966052 -29.107384)
		(end 210.336384 -29.033216)
		(stroke
			(width 0.06223)
			(type default)
		)
		(layer "B.Cu")
	)
	(gr_line
		(start 210.358228 -35.409886)
		(end 210.387184 -35.429444)
		(stroke
			(width 0.06223)
			(type default)
		)
		(layer "B.Cu")
	)
	(gr_line
		(start 210.387184 -35.429444)
		(end 210.406742 -35.4584)
		(stroke
			(width 0.06223)
			(type default)
		)
		(layer "B.Cu")
	)
	(gr_line
		(start 210.508596 -46.006766)
		(end 210.5279 -46.021244)
		(stroke
			(width 0.06223)
			(type default)
		)
		(layer "B.Cu")
	)
	(gr_line
		(start 210.5279 -46.021244)
		(end 210.541108 -46.040802)
		(stroke
			(width 0.06223)
			(type default)
		)
		(layer "B.Cu")
	)
	(gr_line
		(start 210.650582 -29.242766)
		(end 210.72475 -29.613098)
		(stroke
			(width 0.06223)
			(type default)
		)
		(layer "B.Cu")
	)
	(gr_line
		(start 210.677252 -32.774636)
		(end 210.706208 -32.794194)
		(stroke
			(width 0.06223)
			(type default)
		)
		(layer "B.Cu")
	)
	(gr_line
		(start 210.706208 -32.794194)
		(end 210.725766 -32.82315)
		(stroke
			(width 0.06223)
			(type default)
		)
		(layer "B.Cu")
	)
	(gr_line
		(start 210.72475 -29.613098)
		(end 211.035646 -29.820108)
		(stroke
			(width 0.06223)
			(type default)
		)
		(layer "B.Cu")
	)
	(gr_line
		(start 210.911186 -28.925012)
		(end 211.49437 -29.313632)
		(stroke
			(width 0.06223)
			(type default)
		)
		(layer "B.Cu")
	)
	(gr_line
		(start 211.035646 -29.820108)
		(end 211.40547 -29.746194)
		(stroke
			(width 0.06223)
			(type default)
		)
		(layer "B.Cu")
	)
	(gr_line
		(start 211.487512 -47.442882)
		(end 211.507832 -47.473108)
		(stroke
			(width 0.06223)
			(type default)
		)
		(layer "B.Cu")
	)
	(gr_line
		(start 211.49437 -29.313886)
		(end 211.596986 -29.382212)
		(stroke
			(width 0.06223)
			(type default)
		)
		(layer "B.Cu")
	)
	(gr_line
		(start 211.49437 -29.313632)
		(end 211.49437 -29.313886)
		(stroke
			(width 0.06223)
			(type default)
		)
		(layer "B.Cu")
	)
	(gr_line
		(start 211.507832 -47.473108)
		(end 211.514944 -47.508414)
		(stroke
			(width 0.06223)
			(type default)
		)
		(layer "B.Cu")
	)
	(gr_line
		(start 211.536534 -45.201078)
		(end 211.555076 -45.215048)
		(stroke
			(width 0.06223)
			(type default)
		)
		(layer "B.Cu")
	)
	(gr_line
		(start 211.555076 -45.215048)
		(end 211.567776 -45.233844)
		(stroke
			(width 0.06223)
			(type default)
		)
		(layer "B.Cu")
	)
	(gr_line
		(start 211.772246 -31.336488)
		(end 211.802472 -31.356808)
		(stroke
			(width 0.06223)
			(type default)
		)
		(layer "B.Cu")
	)
	(gr_line
		(start 211.802472 -31.356808)
		(end 211.822792 -31.387288)
		(stroke
			(width 0.06223)
			(type default)
		)
		(layer "B.Cu")
	)
	(gr_line
		(start 211.838286 -73.14946)
		(end 211.925408 -73.062338)
		(stroke
			(width 0.06223)
			(type default)
		)
		(layer "B.Cu")
	)
	(gr_line
		(start 212.085936 -36.047934)
		(end 212.157818 -35.677602)
		(stroke
			(width 0.06223)
			(type default)
		)
		(layer "B.Cu")
	)
	(gr_line
		(start 212.085936 -36.047934)
		(end 212.294724 -36.35756)
		(stroke
			(width 0.06223)
			(type default)
		)
		(layer "B.Cu")
	)
	(gr_line
		(start 212.243162 -61.653166)
		(end 212.258656 -61.575442)
		(stroke
			(width 0.06223)
			(type default)
		)
		(layer "B.Cu")
	)
	(gr_line
		(start 212.294724 -36.35756)
		(end 212.665056 -36.429696)
		(stroke
			(width 0.06223)
			(type default)
		)
		(layer "B.Cu")
	)
	(gr_line
		(start 212.381338 -60.961016)
		(end 212.38845 -60.925202)
		(stroke
			(width 0.06223)
			(type default)
		)
		(layer "B.Cu")
	)
	(gr_line
		(start 212.381338 -60.889642)
		(end 212.38845 -60.925202)
		(stroke
			(width 0.06223)
			(type default)
		)
		(layer "B.Cu")
	)
	(gr_line
		(start 212.381338 -60.88888)
		(end 212.381338 -60.889388)
		(stroke
			(width 0.06223)
			(type default)
		)
		(layer "B.Cu")
	)
	(gr_line
		(start 212.520022 -35.483038)
		(end 212.981794 -36.167568)
		(stroke
			(width 0.06223)
			(type default)
		)
		(layer "B.Cu")
	)
	(gr_line
		(start 212.536024 -44.29887)
		(end 212.556344 -44.313856)
		(stroke
			(width 0.06223)
			(type default)
		)
		(layer "B.Cu")
	)
	(gr_line
		(start 212.556344 -44.313856)
		(end 212.569806 -44.334176)
		(stroke
			(width 0.06223)
			(type default)
		)
		(layer "B.Cu")
	)
	(gr_line
		(start 212.563456 -30.026356)
		(end 212.593428 -30.046168)
		(stroke
			(width 0.06223)
			(type default)
		)
		(layer "B.Cu")
	)
	(gr_line
		(start 212.593428 -30.046168)
		(end 212.613748 -30.076394)
		(stroke
			(width 0.06223)
			(type default)
		)
		(layer "B.Cu")
	)
	(gr_line
		(start 212.60816 -56.41721)
		(end 212.681312 -56.783478)
		(stroke
			(width 0.06223)
			(type default)
		)
		(layer "B.Cu")
	)
	(gr_line
		(start 212.60816 -56.41721)
		(end 212.817456 -56.103266)
		(stroke
			(width 0.06223)
			(type default)
		)
		(layer "B.Cu")
	)
	(gr_line
		(start 212.681312 -56.783478)
		(end 212.995256 -56.99252)
		(stroke
			(width 0.06223)
			(type default)
		)
		(layer "B.Cu")
	)
	(gr_line
		(start 212.707982 -46.924214)
		(end 212.728302 -46.95444)
		(stroke
			(width 0.06223)
			(type default)
		)
		(layer "B.Cu")
	)
	(gr_line
		(start 212.728302 -46.95444)
		(end 212.735414 -46.99)
		(stroke
			(width 0.06223)
			(type default)
		)
		(layer "B.Cu")
	)
	(gr_line
		(start 212.804756 -37.113464)
		(end 212.876638 -36.743132)
		(stroke
			(width 0.06223)
			(type default)
		)
		(layer "B.Cu")
	)
	(gr_line
		(start 212.804756 -37.113464)
		(end 213.013544 -37.42309)
		(stroke
			(width 0.06223)
			(type default)
		)
		(layer "B.Cu")
	)
	(gr_line
		(start 212.860382 -57.677558)
		(end 212.933534 -58.043572)
		(stroke
			(width 0.06223)
			(type default)
		)
		(layer "B.Cu")
	)
	(gr_line
		(start 212.860382 -57.677558)
		(end 213.069678 -57.363614)
		(stroke
			(width 0.06223)
			(type default)
		)
		(layer "B.Cu")
	)
	(gr_line
		(start 212.933534 -58.043572)
		(end 213.247478 -58.253122)
		(stroke
			(width 0.06223)
			(type default)
		)
		(layer "B.Cu")
	)
	(gr_line
		(start 213.013544 -37.42309)
		(end 213.383876 -37.495226)
		(stroke
			(width 0.06223)
			(type default)
		)
		(layer "B.Cu")
	)
	(gr_line
		(start 213.11235 -58.937906)
		(end 213.185756 -59.30392)
		(stroke
			(width 0.06223)
			(type default)
		)
		(layer "B.Cu")
	)
	(gr_line
		(start 213.11235 -58.937906)
		(end 213.321646 -58.623962)
		(stroke
			(width 0.06223)
			(type default)
		)
		(layer "B.Cu")
	)
	(gr_line
		(start 213.185756 -59.30392)
		(end 213.4997 -59.512962)
		(stroke
			(width 0.06223)
			(type default)
		)
		(layer "B.Cu")
	)
	(gr_line
		(start 213.226396 -56.063388)
		(end 213.388194 -56.871362)
		(stroke
			(width 0.06223)
			(type default)
		)
		(layer "B.Cu")
	)
	(gr_line
		(start 213.23935 -36.54933)
		(end 213.699852 -37.232082)
		(stroke
			(width 0.06223)
			(type default)
		)
		(layer "B.Cu")
	)
	(gr_line
		(start 213.41207 -62.853062)
		(end 213.43493 -62.820804)
		(stroke
			(width 0.06223)
			(type default)
		)
		(layer "B.Cu")
	)
	(gr_line
		(start 213.43493 -62.820804)
		(end 213.443312 -62.779656)
		(stroke
			(width 0.06223)
			(type default)
		)
		(layer "B.Cu")
	)
	(gr_line
		(start 213.478618 -57.323736)
		(end 213.64067 -58.13298)
		(stroke
			(width 0.06223)
			(type default)
		)
		(layer "B.Cu")
	)
	(gr_line
		(start 213.523322 -38.178994)
		(end 213.595204 -37.808408)
		(stroke
			(width 0.06223)
			(type default)
		)
		(layer "B.Cu")
	)
	(gr_line
		(start 213.523322 -38.178994)
		(end 213.73211 -38.48862)
		(stroke
			(width 0.06223)
			(type default)
		)
		(layer "B.Cu")
	)
	(gr_line
		(start 213.731094 -58.584846)
		(end 213.892384 -59.391296)
		(stroke
			(width 0.06223)
			(type default)
		)
		(layer "B.Cu")
	)
	(gr_line
		(start 213.73211 -38.48862)
		(end 214.102696 -38.560502)
		(stroke
			(width 0.06223)
			(type default)
		)
		(layer "B.Cu")
	)
	(gr_line
		(start 213.905846 -46.314614)
		(end 213.926166 -46.34484)
		(stroke
			(width 0.06223)
			(type default)
		)
		(layer "B.Cu")
	)
	(gr_line
		(start 213.926166 -46.34484)
		(end 213.933278 -46.3804)
		(stroke
			(width 0.06223)
			(type default)
		)
		(layer "B.Cu")
	)
	(gr_line
		(start 213.958424 -37.615622)
		(end 214.418418 -38.297612)
		(stroke
			(width 0.06223)
			(type default)
		)
		(layer "B.Cu")
	)
	(gr_line
		(start 213.999572 -59.998864)
		(end 214.006684 -59.96305)
		(stroke
			(width 0.06223)
			(type default)
		)
		(layer "B.Cu")
	)
	(gr_line
		(start 213.999572 -59.926982)
		(end 214.006684 -59.96305)
		(stroke
			(width 0.06223)
			(type default)
		)
		(layer "B.Cu")
	)
	(gr_line
		(start 213.999572 -59.926728)
		(end 213.999572 -59.927236)
		(stroke
			(width 0.06223)
			(type default)
		)
		(layer "B.Cu")
	)
	(gr_line
		(start 214.33663 -41.285922)
		(end 214.357458 -41.316656)
		(stroke
			(width 0.06223)
			(type default)
		)
		(layer "B.Cu")
	)
	(gr_line
		(start 214.357458 -41.316656)
		(end 214.364824 -41.354248)
		(stroke
			(width 0.06223)
			(type default)
		)
		(layer "B.Cu")
	)
	(gr_line
		(start 214.739728 -63.636398)
		(end 214.758778 -63.607696)
		(stroke
			(width 0.06223)
			(type default)
		)
		(layer "B.Cu")
	)
	(gr_line
		(start 214.758778 -63.607696)
		(end 214.765636 -63.57366)
		(stroke
			(width 0.06223)
			(type default)
		)
		(layer "B.Cu")
	)
	(gr_line
		(start 215.342978 -66.978022)
		(end 215.358218 -66.901822)
		(stroke
			(width 0.06223)
			(type default)
		)
		(layer "B.Cu")
	)
	(gr_line
		(start 215.401652 -60.393834)
		(end 215.408764 -60.35802)
		(stroke
			(width 0.06223)
			(type default)
		)
		(layer "B.Cu")
	)
	(gr_line
		(start 215.401652 -60.321952)
		(end 215.408764 -60.35802)
		(stroke
			(width 0.06223)
			(type default)
		)
		(layer "B.Cu")
	)
	(gr_line
		(start 215.401652 -60.321698)
		(end 215.401652 -60.322206)
		(stroke
			(width 0.06223)
			(type default)
		)
		(layer "B.Cu")
	)
	(gr_line
		(start 215.495632 -39.89451)
		(end 215.51646 -39.925244)
		(stroke
			(width 0.06223)
			(type default)
		)
		(layer "B.Cu")
	)
	(gr_line
		(start 215.51646 -39.925244)
		(end 215.523826 -39.962836)
		(stroke
			(width 0.06223)
			(type default)
		)
		(layer "B.Cu")
	)
	(gr_line
		(start 216.611454 -68.376292)
		(end 216.668604 -68.319142)
		(stroke
			(width 0.06223)
			(type default)
		)
		(layer "B.Cu")
	)
	(gr_line
		(start 216.668604 -68.319142)
		(end 216.684098 -68.239894)
		(stroke
			(width 0.06223)
			(type default)
		)
		(layer "B.Cu")
	)
	(gr_line
		(start 216.686638 -38.683184)
		(end 216.705942 -38.712394)
		(stroke
			(width 0.06223)
			(type default)
		)
		(layer "B.Cu")
	)
	(gr_line
		(start 216.690448 -60.240164)
		(end 216.69756 -60.20435)
		(stroke
			(width 0.06223)
			(type default)
		)
		(layer "B.Cu")
	)
	(gr_line
		(start 216.690448 -60.168282)
		(end 216.69756 -60.20435)
		(stroke
			(width 0.06223)
			(type default)
		)
		(layer "B.Cu")
	)
	(gr_line
		(start 216.690448 -60.168028)
		(end 216.690448 -60.168536)
		(stroke
			(width 0.06223)
			(type default)
		)
		(layer "B.Cu")
	)
	(gr_line
		(start 216.705942 -38.712394)
		(end 216.7128 -38.746684)
		(stroke
			(width 0.06223)
			(type default)
		)
		(layer "B.Cu")
	)
	(gr_line
		(start 217.635328 -70.273418)
		(end 217.650568 -70.197218)
		(stroke
			(width 0.06223)
			(type default)
		)
		(layer "B.Cu")
	)
	(gr_line
		(start 217.813382 -37.87775)
		(end 217.832432 -37.906452)
		(stroke
			(width 0.06223)
			(type default)
		)
		(layer "B.Cu")
	)
	(gr_line
		(start 217.832432 -37.906452)
		(end 217.83929 -37.940742)
		(stroke
			(width 0.06223)
			(type default)
		)
		(layer "B.Cu")
	)
	(gr_line
		(start 218.13012 -60.794138)
		(end 218.13647 -60.761118)
		(stroke
			(width 0.06223)
			(type default)
		)
		(layer "B.Cu")
	)
	(gr_line
		(start 218.13012 -60.727844)
		(end 218.13647 -60.761118)
		(stroke
			(width 0.06223)
			(type default)
		)
		(layer "B.Cu")
	)
	(gr_line
		(start 218.13012 -60.72759)
		(end 218.13012 -60.728098)
		(stroke
			(width 0.06223)
			(type default)
		)
		(layer "B.Cu")
	)
	(gr_line
		(start 218.42095 -72.729852)
		(end 218.43619 -72.653906)
		(stroke
			(width 0.06223)
			(type default)
		)
		(layer "B.Cu")
	)
	(gr_line
		(start 219.304362 -74.716386)
		(end 219.319602 -74.640186)
		(stroke
			(width 0.06223)
			(type default)
		)
		(layer "B.Cu")
	)
	(gr_line
		(start 219.545408 -60.720224)
		(end 219.552266 -60.685934)
		(stroke
			(width 0.06223)
			(type default)
		)
		(layer "B.Cu")
	)
	(gr_line
		(start 219.545408 -60.650374)
		(end 219.552266 -60.685934)
		(stroke
			(width 0.06223)
			(type default)
		)
		(layer "B.Cu")
	)
	(gr_line
		(start 220.959172 -60.05322)
		(end 220.966284 -60.017406)
		(stroke
			(width 0.06223)
			(type default)
		)
		(layer "B.Cu")
	)
	(gr_line
		(start 220.959172 -59.981338)
		(end 220.966284 -60.017406)
		(stroke
			(width 0.06223)
			(type default)
		)
		(layer "B.Cu")
	)
	(gr_line
		(start 220.959172 -59.981084)
		(end 220.959172 -59.981592)
		(stroke
			(width 0.06223)
			(type default)
		)
		(layer "B.Cu")
	)
	(gr_line
		(start 222.24111 -60.023248)
		(end 222.248222 -59.987434)
		(stroke
			(width 0.06223)
			(type default)
		)
		(layer "B.Cu")
	)
	(gr_line
		(start 222.24111 -59.951366)
		(end 222.248222 -59.987434)
		(stroke
			(width 0.06223)
			(type default)
		)
		(layer "B.Cu")
	)
	(gr_line
		(start 222.24111 -59.951112)
		(end 222.24111 -59.95162)
		(stroke
			(width 0.06223)
			(type default)
		)
		(layer "B.Cu")
	)
	(gr_line
		(start 0 -183.76392)
		(end 0 -0.999998)
		(stroke
			(width 1.524)
			(type default)
		)
		(layer "In1.Cu")
	)
	(gr_arc
		(start 0 -183.76392)
		(mid 0.026807 -183.993715)
		(end 0.105664 -184.211214)
		(stroke
			(width 1.524)
			(type default)
		)
		(layer "In1.Cu")
	)
	(gr_arc
		(start 0.999998 0)
		(mid 0.292893 -0.292893)
		(end 0 -0.999998)
		(stroke
			(width 1.524)
			(type default)
		)
		(layer "In1.Cu")
	)
	(gr_line
		(start 0.999998 0)
		(end 29.53004 0)
		(stroke
			(width 1.524)
			(type default)
		)
		(layer "In1.Cu")
	)
	(gr_line
		(start 4.723638 -193.447162)
		(end 0.105664 -184.211214)
		(stroke
			(width 1.524)
			(type default)
		)
		(layer "In1.Cu")
	)
	(gr_arc
		(start 4.723638 -193.447162)
		(mid 5.092281 -193.850645)
		(end 5.617972 -194.00012)
		(stroke
			(width 1.524)
			(type default)
		)
		(layer "In1.Cu")
	)
	(gr_arc
		(start 30.530038 -109.050074)
		(mid 30.822931 -109.757179)
		(end 31.530036 -110.050072)
		(stroke
			(width 1.524)
			(type default)
		)
		(layer "In1.Cu")
	)
	(gr_arc
		(start 30.530038 -0.999998)
		(mid 30.237147 -0.29288)
		(end 29.53004 0)
		(stroke
			(width 1.524)
			(type default)
		)
		(layer "In1.Cu")
	)
	(gr_line
		(start 30.530038 -0.999998)
		(end 30.530038 -109.050074)
		(stroke
			(width 1.524)
			(type default)
		)
		(layer "In1.Cu")
	)
	(gr_line
		(start 31.530036 -110.050072)
		(end 72.030082 -110.050072)
		(stroke
			(width 1.524)
			(type default)
		)
		(layer "In1.Cu")
	)
	(gr_arc
		(start 72.030082 -110.050072)
		(mid 72.737187 -109.757179)
		(end 73.03008 -109.050074)
		(stroke
			(width 1.524)
			(type default)
		)
		(layer "In1.Cu")
	)
	(gr_line
		(start 73.03008 -109.050074)
		(end 73.03008 -0.999998)
		(stroke
			(width 1.524)
			(type default)
		)
		(layer "In1.Cu")
	)
	(gr_arc
		(start 74.030078 0)
		(mid 73.322986 -0.2929)
		(end 73.03008 -0.999998)
		(stroke
			(width 1.524)
			(type default)
		)
		(layer "In1.Cu")
	)
	(gr_line
		(start 74.030078 0)
		(end 234.00004 0)
		(stroke
			(width 1.524)
			(type default)
		)
		(layer "In1.Cu")
	)
	(gr_rect
		(start 74.446384 -92.69603)
		(end 76.503784 -94.00413)
		(stroke
			(width 0)
			(type default)
		)
		(fill no)
		(layer "In1.Cu")
	)
	(gr_rect
		(start 74.446384 -89.496138)
		(end 76.503784 -90.803984)
		(stroke
			(width 0)
			(type default)
		)
		(fill no)
		(layer "In1.Cu")
	)
	(gr_rect
		(start 74.446384 -86.295992)
		(end 76.503784 -87.604092)
		(stroke
			(width 0)
			(type default)
		)
		(fill no)
		(layer "In1.Cu")
	)
	(gr_rect
		(start 74.446384 -83.0961)
		(end 76.503784 -84.403946)
		(stroke
			(width 0)
			(type default)
		)
		(fill no)
		(layer "In1.Cu")
	)
	(gr_rect
		(start 74.446384 -79.895954)
		(end 76.503784 -81.204054)
		(stroke
			(width 0)
			(type default)
		)
		(fill no)
		(layer "In1.Cu")
	)
	(gr_rect
		(start 74.446384 -76.696062)
		(end 76.503784 -78.003908)
		(stroke
			(width 0)
			(type default)
		)
		(fill no)
		(layer "In1.Cu")
	)
	(gr_rect
		(start 74.446384 -73.495916)
		(end 76.503784 -74.804016)
		(stroke
			(width 0)
			(type default)
		)
		(fill no)
		(layer "In1.Cu")
	)
	(gr_rect
		(start 74.446384 -70.296024)
		(end 76.503784 -71.604124)
		(stroke
			(width 0)
			(type default)
		)
		(fill no)
		(layer "In1.Cu")
	)
	(gr_rect
		(start 74.446384 -67.096132)
		(end 76.503784 -68.403978)
		(stroke
			(width 0)
			(type default)
		)
		(fill no)
		(layer "In1.Cu")
	)
	(gr_arc
		(start 76.891134 -68.211192)
		(mid 77.274674 -68.594732)
		(end 77.658214 -68.211192)
		(stroke
			(width 0.2)
			(type default)
		)
		(layer "In1.Cu")
	)
	(gr_line
		(start 76.891134 -67.322192)
		(end 76.891134 -68.211192)
		(stroke
			(width 0.2)
			(type default)
		)
		(layer "In1.Cu")
	)
	(gr_arc
		(start 76.900278 -93.799914)
		(mid 77.283691 -94.183708)
		(end 77.667358 -93.800168)
		(stroke
			(width 0.2)
			(type default)
		)
		(layer "In1.Cu")
	)
	(gr_line
		(start 76.900278 -92.911168)
		(end 76.900278 -93.799914)
		(stroke
			(width 0.2)
			(type default)
		)
		(layer "In1.Cu")
	)
	(gr_arc
		(start 76.900278 -87.399114)
		(mid 77.283691 -87.782908)
		(end 77.667358 -87.399368)
		(stroke
			(width 0.2)
			(type default)
		)
		(layer "In1.Cu")
	)
	(gr_line
		(start 76.900278 -86.510368)
		(end 76.900278 -87.399114)
		(stroke
			(width 0.2)
			(type default)
		)
		(layer "In1.Cu")
	)
	(gr_arc
		(start 76.900278 -80.998314)
		(mid 77.283691 -81.382108)
		(end 77.667358 -80.998568)
		(stroke
			(width 0.2)
			(type default)
		)
		(layer "In1.Cu")
	)
	(gr_line
		(start 76.900278 -80.109568)
		(end 76.900278 -80.998314)
		(stroke
			(width 0.2)
			(type default)
		)
		(layer "In1.Cu")
	)
	(gr_arc
		(start 76.900278 -74.597514)
		(mid 77.283691 -74.981308)
		(end 77.667358 -74.597768)
		(stroke
			(width 0.2)
			(type default)
		)
		(layer "In1.Cu")
	)
	(gr_line
		(start 76.900278 -73.708768)
		(end 76.900278 -74.597514)
		(stroke
			(width 0.2)
			(type default)
		)
		(layer "In1.Cu")
	)
	(gr_line
		(start 77.658214 -68.211192)
		(end 77.658214 -67.322446)
		(stroke
			(width 0.2)
			(type default)
		)
		(layer "In1.Cu")
	)
	(gr_arc
		(start 77.658214 -67.322446)
		(mid 77.274801 -66.938652)
		(end 76.891134 -67.322192)
		(stroke
			(width 0.2)
			(type default)
		)
		(layer "In1.Cu")
	)
	(gr_line
		(start 77.667358 -93.800168)
		(end 77.667358 -92.911168)
		(stroke
			(width 0.2)
			(type default)
		)
		(layer "In1.Cu")
	)
	(gr_arc
		(start 77.667358 -92.911168)
		(mid 77.283818 -92.527628)
		(end 76.900278 -92.911168)
		(stroke
			(width 0.2)
			(type default)
		)
		(layer "In1.Cu")
	)
	(gr_line
		(start 77.667358 -87.399368)
		(end 77.667358 -86.510368)
		(stroke
			(width 0.2)
			(type default)
		)
		(layer "In1.Cu")
	)
	(gr_arc
		(start 77.667358 -86.510368)
		(mid 77.283818 -86.126828)
		(end 76.900278 -86.510368)
		(stroke
			(width 0.2)
			(type default)
		)
		(layer "In1.Cu")
	)
	(gr_line
		(start 77.667358 -80.998568)
		(end 77.667358 -80.109568)
		(stroke
			(width 0.2)
			(type default)
		)
		(layer "In1.Cu")
	)
	(gr_arc
		(start 77.667358 -80.109568)
		(mid 77.283818 -79.726028)
		(end 76.900278 -80.109568)
		(stroke
			(width 0.2)
			(type default)
		)
		(layer "In1.Cu")
	)
	(gr_line
		(start 77.667358 -74.597768)
		(end 77.667358 -73.708768)
		(stroke
			(width 0.2)
			(type default)
		)
		(layer "In1.Cu")
	)
	(gr_arc
		(start 77.667358 -73.708768)
		(mid 77.283818 -73.325228)
		(end 76.900278 -73.708768)
		(stroke
			(width 0.2)
			(type default)
		)
		(layer "In1.Cu")
	)
	(gr_arc
		(start 77.738478 -90.599514)
		(mid 78.121891 -90.983308)
		(end 78.505558 -90.599768)
		(stroke
			(width 0.2)
			(type default)
		)
		(layer "In1.Cu")
	)
	(gr_line
		(start 77.738478 -89.710768)
		(end 77.738478 -90.599514)
		(stroke
			(width 0.2)
			(type default)
		)
		(layer "In1.Cu")
	)
	(gr_arc
		(start 77.738478 -84.224114)
		(mid 78.121891 -84.607908)
		(end 78.505558 -84.224368)
		(stroke
			(width 0.2)
			(type default)
		)
		(layer "In1.Cu")
	)
	(gr_line
		(start 77.738478 -83.335368)
		(end 77.738478 -84.224114)
		(stroke
			(width 0.2)
			(type default)
		)
		(layer "In1.Cu")
	)
	(gr_arc
		(start 77.738478 -77.797914)
		(mid 78.121891 -78.181708)
		(end 78.505558 -77.798168)
		(stroke
			(width 0.2)
			(type default)
		)
		(layer "In1.Cu")
	)
	(gr_line
		(start 77.738478 -76.909168)
		(end 77.738478 -77.797914)
		(stroke
			(width 0.2)
			(type default)
		)
		(layer "In1.Cu")
	)
	(gr_arc
		(start 77.738478 -71.397114)
		(mid 78.121891 -71.780908)
		(end 78.505558 -71.397368)
		(stroke
			(width 0.2)
			(type default)
		)
		(layer "In1.Cu")
	)
	(gr_line
		(start 77.738478 -70.508368)
		(end 77.738478 -71.397114)
		(stroke
			(width 0.2)
			(type default)
		)
		(layer "In1.Cu")
	)
	(gr_line
		(start 78.505558 -90.599768)
		(end 78.505558 -89.710768)
		(stroke
			(width 0.2)
			(type default)
		)
		(layer "In1.Cu")
	)
	(gr_arc
		(start 78.505558 -89.710768)
		(mid 78.122018 -89.327228)
		(end 77.738478 -89.710768)
		(stroke
			(width 0.2)
			(type default)
		)
		(layer "In1.Cu")
	)
	(gr_line
		(start 78.505558 -84.224368)
		(end 78.505558 -83.335368)
		(stroke
			(width 0.2)
			(type default)
		)
		(layer "In1.Cu")
	)
	(gr_arc
		(start 78.505558 -83.335368)
		(mid 78.122018 -82.951828)
		(end 77.738478 -83.335368)
		(stroke
			(width 0.2)
			(type default)
		)
		(layer "In1.Cu")
	)
	(gr_line
		(start 78.505558 -77.798168)
		(end 78.505558 -76.909168)
		(stroke
			(width 0.2)
			(type default)
		)
		(layer "In1.Cu")
	)
	(gr_arc
		(start 78.505558 -76.909168)
		(mid 78.122018 -76.525628)
		(end 77.738478 -76.909168)
		(stroke
			(width 0.2)
			(type default)
		)
		(layer "In1.Cu")
	)
	(gr_line
		(start 78.505558 -71.397368)
		(end 78.505558 -70.508368)
		(stroke
			(width 0.2)
			(type default)
		)
		(layer "In1.Cu")
	)
	(gr_arc
		(start 78.505558 -70.508368)
		(mid 78.122018 -70.124828)
		(end 77.738478 -70.508368)
		(stroke
			(width 0.2)
			(type default)
		)
		(layer "In1.Cu")
	)
	(gr_rect
		(start 78.896464 -94.295976)
		(end 80.953864 -95.604076)
		(stroke
			(width 0)
			(type default)
		)
		(fill no)
		(layer "In1.Cu")
	)
	(gr_rect
		(start 78.896464 -91.096084)
		(end 80.953864 -92.40393)
		(stroke
			(width 0)
			(type default)
		)
		(fill no)
		(layer "In1.Cu")
	)
	(gr_rect
		(start 78.896464 -87.895938)
		(end 80.953864 -89.204038)
		(stroke
			(width 0)
			(type default)
		)
		(fill no)
		(layer "In1.Cu")
	)
	(gr_rect
		(start 78.896464 -84.696046)
		(end 80.953864 -86.004146)
		(stroke
			(width 0)
			(type default)
		)
		(fill no)
		(layer "In1.Cu")
	)
	(gr_rect
		(start 78.896464 -81.4959)
		(end 80.953864 -82.804)
		(stroke
			(width 0)
			(type default)
		)
		(fill no)
		(layer "In1.Cu")
	)
	(gr_rect
		(start 78.896464 -78.296008)
		(end 80.953864 -79.604108)
		(stroke
			(width 0)
			(type default)
		)
		(fill no)
		(layer "In1.Cu")
	)
	(gr_rect
		(start 78.896464 -75.096116)
		(end 80.953864 -76.403962)
		(stroke
			(width 0)
			(type default)
		)
		(fill no)
		(layer "In1.Cu")
	)
	(gr_rect
		(start 78.896464 -71.89597)
		(end 80.953864 -73.20407)
		(stroke
			(width 0)
			(type default)
		)
		(fill no)
		(layer "In1.Cu")
	)
	(gr_arc
		(start 82.974688 -95.381318)
		(mid 83.358101 -95.765112)
		(end 83.741768 -95.381572)
		(stroke
			(width 0.2)
			(type default)
		)
		(layer "In1.Cu")
	)
	(gr_line
		(start 82.974688 -94.492572)
		(end 82.974688 -95.381318)
		(stroke
			(width 0.2)
			(type default)
		)
		(layer "In1.Cu")
	)
	(gr_arc
		(start 82.974688 -88.994234)
		(mid 83.358228 -89.377774)
		(end 83.741768 -88.994234)
		(stroke
			(width 0.2)
			(type default)
		)
		(layer "In1.Cu")
	)
	(gr_line
		(start 82.974688 -88.105234)
		(end 82.974688 -88.994234)
		(stroke
			(width 0.2)
			(type default)
		)
		(layer "In1.Cu")
	)
	(gr_arc
		(start 82.974688 -82.593942)
		(mid 83.358101 -82.977736)
		(end 83.741768 -82.594196)
		(stroke
			(width 0.2)
			(type default)
		)
		(layer "In1.Cu")
	)
	(gr_line
		(start 82.974688 -81.705196)
		(end 82.974688 -82.593942)
		(stroke
			(width 0.2)
			(type default)
		)
		(layer "In1.Cu")
	)
	(gr_arc
		(start 82.974688 -76.193904)
		(mid 83.358101 -76.577698)
		(end 83.741768 -76.194158)
		(stroke
			(width 0.2)
			(type default)
		)
		(layer "In1.Cu")
	)
	(gr_line
		(start 82.974688 -75.305158)
		(end 82.974688 -76.193904)
		(stroke
			(width 0.2)
			(type default)
		)
		(layer "In1.Cu")
	)
	(gr_line
		(start 83.741768 -95.381572)
		(end 83.741768 -94.492572)
		(stroke
			(width 0.2)
			(type default)
		)
		(layer "In1.Cu")
	)
	(gr_arc
		(start 83.741768 -94.492572)
		(mid 83.358228 -94.109032)
		(end 82.974688 -94.492572)
		(stroke
			(width 0.2)
			(type default)
		)
		(layer "In1.Cu")
	)
	(gr_line
		(start 83.741768 -88.994234)
		(end 83.741768 -88.105488)
		(stroke
			(width 0.2)
			(type default)
		)
		(layer "In1.Cu")
	)
	(gr_arc
		(start 83.741768 -88.105488)
		(mid 83.358355 -87.721694)
		(end 82.974688 -88.105234)
		(stroke
			(width 0.2)
			(type default)
		)
		(layer "In1.Cu")
	)
	(gr_line
		(start 83.741768 -82.594196)
		(end 83.741768 -81.705196)
		(stroke
			(width 0.2)
			(type default)
		)
		(layer "In1.Cu")
	)
	(gr_arc
		(start 83.741768 -81.705196)
		(mid 83.358228 -81.321656)
		(end 82.974688 -81.705196)
		(stroke
			(width 0.2)
			(type default)
		)
		(layer "In1.Cu")
	)
	(gr_line
		(start 83.741768 -76.194158)
		(end 83.741768 -75.305158)
		(stroke
			(width 0.2)
			(type default)
		)
		(layer "In1.Cu")
	)
	(gr_arc
		(start 83.741768 -75.305158)
		(mid 83.358228 -74.921618)
		(end 82.974688 -75.305158)
		(stroke
			(width 0.2)
			(type default)
		)
		(layer "In1.Cu")
	)
	(gr_arc
		(start 84.600288 -92.195142)
		(mid 84.983701 -92.578936)
		(end 85.367368 -92.195396)
		(stroke
			(width 0.2)
			(type default)
		)
		(layer "In1.Cu")
	)
	(gr_line
		(start 84.600288 -91.306396)
		(end 84.600288 -92.195142)
		(stroke
			(width 0.2)
			(type default)
		)
		(layer "In1.Cu")
	)
	(gr_arc
		(start 84.600288 -85.79358)
		(mid 84.983701 -86.177374)
		(end 85.367368 -85.793834)
		(stroke
			(width 0.2)
			(type default)
		)
		(layer "In1.Cu")
	)
	(gr_line
		(start 84.600288 -84.904834)
		(end 84.600288 -85.79358)
		(stroke
			(width 0.2)
			(type default)
		)
		(layer "In1.Cu")
	)
	(gr_arc
		(start 84.600288 -79.393542)
		(mid 84.983701 -79.777336)
		(end 85.367368 -79.393796)
		(stroke
			(width 0.2)
			(type default)
		)
		(layer "In1.Cu")
	)
	(gr_line
		(start 84.600288 -78.504796)
		(end 84.600288 -79.393542)
		(stroke
			(width 0.2)
			(type default)
		)
		(layer "In1.Cu")
	)
	(gr_arc
		(start 84.600288 -72.970136)
		(mid 84.983828 -73.353676)
		(end 85.367368 -72.970136)
		(stroke
			(width 0.2)
			(type default)
		)
		(layer "In1.Cu")
	)
	(gr_line
		(start 84.600288 -72.081136)
		(end 84.600288 -72.970136)
		(stroke
			(width 0.2)
			(type default)
		)
		(layer "In1.Cu")
	)
	(gr_line
		(start 85.367368 -92.195396)
		(end 85.367368 -91.306396)
		(stroke
			(width 0.2)
			(type default)
		)
		(layer "In1.Cu")
	)
	(gr_arc
		(start 85.367368 -91.306396)
		(mid 84.983828 -90.922856)
		(end 84.600288 -91.306396)
		(stroke
			(width 0.2)
			(type default)
		)
		(layer "In1.Cu")
	)
	(gr_line
		(start 85.367368 -85.793834)
		(end 85.367368 -84.904834)
		(stroke
			(width 0.2)
			(type default)
		)
		(layer "In1.Cu")
	)
	(gr_arc
		(start 85.367368 -84.904834)
		(mid 84.983828 -84.521294)
		(end 84.600288 -84.904834)
		(stroke
			(width 0.2)
			(type default)
		)
		(layer "In1.Cu")
	)
	(gr_line
		(start 85.367368 -79.393796)
		(end 85.367368 -78.504796)
		(stroke
			(width 0.2)
			(type default)
		)
		(layer "In1.Cu")
	)
	(gr_arc
		(start 85.367368 -78.504796)
		(mid 84.983828 -78.121256)
		(end 84.600288 -78.504796)
		(stroke
			(width 0.2)
			(type default)
		)
		(layer "In1.Cu")
	)
	(gr_line
		(start 85.367368 -72.970136)
		(end 85.367368 -72.08139)
		(stroke
			(width 0.2)
			(type default)
		)
		(layer "In1.Cu")
	)
	(gr_arc
		(start 85.367368 -72.08139)
		(mid 84.983955 -71.697596)
		(end 84.600288 -72.081136)
		(stroke
			(width 0.2)
			(type default)
		)
		(layer "In1.Cu")
	)
	(gr_line
		(start 98.081846 -194.00012)
		(end 5.617972 -194.00012)
		(stroke
			(width 1.524)
			(type default)
		)
		(layer "In1.Cu")
	)
	(gr_arc
		(start 98.081846 -194.00012)
		(mid 98.607706 -193.850755)
		(end 98.976434 -193.447162)
		(stroke
			(width 1.524)
			(type default)
		)
		(layer "In1.Cu")
	)
	(gr_line
		(start 103.594408 -184.211214)
		(end 98.976434 -193.447162)
		(stroke
			(width 1.524)
			(type default)
		)
		(layer "In1.Cu")
	)
	(gr_arc
		(start 103.594408 -184.211214)
		(mid 103.673311 -183.993725)
		(end 103.700072 -183.76392)
		(stroke
			(width 1.524)
			(type default)
		)
		(layer "In1.Cu")
	)
	(gr_line
		(start 103.700072 -47.999904)
		(end 103.700072 -183.76392)
		(stroke
			(width 1.524)
			(type default)
		)
		(layer "In1.Cu")
	)
	(gr_arc
		(start 104.70007 -47.999904)
		(mid 104.200198 -47.500032)
		(end 103.700072 -47.999904)
		(stroke
			(width 1.524)
			(type default)
		)
		(layer "In1.Cu")
	)
	(gr_arc
		(start 106.614722 -38.200076)
		(mid 107.099862 -38.685216)
		(end 107.585002 -38.200076)
		(stroke
			(width 0.2)
			(type default)
		)
		(layer "In1.Cu")
	)
	(gr_line
		(start 106.614722 -36.800028)
		(end 106.614722 -38.200076)
		(stroke
			(width 0.2)
			(type default)
		)
		(layer "In1.Cu")
	)
	(gr_arc
		(start 106.614722 -34.600134)
		(mid 107.099862 -35.085274)
		(end 107.585002 -34.600134)
		(stroke
			(width 0.2)
			(type default)
		)
		(layer "In1.Cu")
	)
	(gr_line
		(start 106.614722 -33.200086)
		(end 106.614722 -34.600134)
		(stroke
			(width 0.2)
			(type default)
		)
		(layer "In1.Cu")
	)
	(gr_line
		(start 107.585002 -38.200076)
		(end 107.585002 -36.800282)
		(stroke
			(width 0.2)
			(type default)
		)
		(layer "In1.Cu")
	)
	(gr_arc
		(start 107.585002 -36.800282)
		(mid 107.099989 -36.314888)
		(end 106.614722 -36.800028)
		(stroke
			(width 0.2)
			(type default)
		)
		(layer "In1.Cu")
	)
	(gr_line
		(start 107.585002 -34.600134)
		(end 107.585002 -33.20034)
		(stroke
			(width 0.2)
			(type default)
		)
		(layer "In1.Cu")
	)
	(gr_arc
		(start 107.585002 -33.20034)
		(mid 107.099989 -32.714946)
		(end 106.614722 -33.200086)
		(stroke
			(width 0.2)
			(type default)
		)
		(layer "In1.Cu")
	)
	(gr_arc
		(start 108.41482 -37.00018)
		(mid 108.89996 -37.48532)
		(end 109.3851 -37.00018)
		(stroke
			(width 0.2)
			(type default)
		)
		(layer "In1.Cu")
	)
	(gr_line
		(start 108.41482 -35.600132)
		(end 108.41482 -37.00018)
		(stroke
			(width 0.2)
			(type default)
		)
		(layer "In1.Cu")
	)
	(gr_arc
		(start 108.41482 -33.399984)
		(mid 108.89996 -33.885124)
		(end 109.3851 -33.399984)
		(stroke
			(width 0.2)
			(type default)
		)
		(layer "In1.Cu")
	)
	(gr_line
		(start 108.41482 -32.00019)
		(end 108.41482 -33.399984)
		(stroke
			(width 0.2)
			(type default)
		)
		(layer "In1.Cu")
	)
	(gr_line
		(start 109.3851 -37.00018)
		(end 109.3851 -35.600386)
		(stroke
			(width 0.2)
			(type default)
		)
		(layer "In1.Cu")
	)
	(gr_arc
		(start 109.3851 -35.600386)
		(mid 108.900087 -35.114992)
		(end 108.41482 -35.600132)
		(stroke
			(width 0.2)
			(type default)
		)
		(layer "In1.Cu")
	)
	(gr_line
		(start 109.3851 -33.399984)
		(end 109.3851 -32.000444)
		(stroke
			(width 0.2)
			(type default)
		)
		(layer "In1.Cu")
	)
	(gr_arc
		(start 109.3851 -32.000444)
		(mid 108.900087 -31.51505)
		(end 108.41482 -32.00019)
		(stroke
			(width 0.2)
			(type default)
		)
		(layer "In1.Cu")
	)
	(gr_line
		(start 109.73816 -15.19428)
		(end 110.92688 -16.383)
		(stroke
			(width 0.381)
			(type default)
		)
		(layer "In1.Cu")
	)
	(gr_line
		(start 109.73816 -6.68528)
		(end 109.73816 -15.19428)
		(stroke
			(width 0.381)
			(type default)
		)
		(layer "In1.Cu")
	)
	(gr_arc
		(start 110.214918 -38.200076)
		(mid 110.700058 -38.685216)
		(end 111.185198 -38.200076)
		(stroke
			(width 0.2)
			(type default)
		)
		(layer "In1.Cu")
	)
	(gr_line
		(start 110.214918 -36.800028)
		(end 110.214918 -38.200076)
		(stroke
			(width 0.2)
			(type default)
		)
		(layer "In1.Cu")
	)
	(gr_arc
		(start 110.214918 -34.600134)
		(mid 110.700058 -35.085274)
		(end 111.185198 -34.600134)
		(stroke
			(width 0.2)
			(type default)
		)
		(layer "In1.Cu")
	)
	(gr_line
		(start 110.214918 -33.200086)
		(end 110.214918 -34.600134)
		(stroke
			(width 0.2)
			(type default)
		)
		(layer "In1.Cu")
	)
	(gr_line
		(start 110.92688 -16.383)
		(end 111.6076 -16.383)
		(stroke
			(width 0.381)
			(type default)
		)
		(layer "In1.Cu")
	)
	(gr_line
		(start 111.185198 -38.200076)
		(end 111.185198 -36.800282)
		(stroke
			(width 0.2)
			(type default)
		)
		(layer "In1.Cu")
	)
	(gr_arc
		(start 111.185198 -36.800282)
		(mid 110.700185 -36.314888)
		(end 110.214918 -36.800028)
		(stroke
			(width 0.2)
			(type default)
		)
		(layer "In1.Cu")
	)
	(gr_line
		(start 111.185198 -34.600134)
		(end 111.185198 -33.20034)
		(stroke
			(width 0.2)
			(type default)
		)
		(layer "In1.Cu")
	)
	(gr_arc
		(start 111.185198 -33.20034)
		(mid 110.700185 -32.714946)
		(end 110.214918 -33.200086)
		(stroke
			(width 0.2)
			(type default)
		)
		(layer "In1.Cu")
	)
	(gr_line
		(start 111.6076 -16.383)
		(end 120.5357 -16.383)
		(stroke
			(width 0.381)
			(type default)
		)
		(layer "In1.Cu")
	)
	(gr_line
		(start 111.897414 -4.526026)
		(end 109.73816 -6.68528)
		(stroke
			(width 0.381)
			(type default)
		)
		(layer "In1.Cu")
	)
	(gr_arc
		(start 112.014762 -37.00018)
		(mid 112.499902 -37.48532)
		(end 112.985042 -37.00018)
		(stroke
			(width 0.2)
			(type default)
		)
		(layer "In1.Cu")
	)
	(gr_line
		(start 112.014762 -35.600132)
		(end 112.014762 -37.00018)
		(stroke
			(width 0.2)
			(type default)
		)
		(layer "In1.Cu")
	)
	(gr_arc
		(start 112.014762 -33.399984)
		(mid 112.499902 -33.885124)
		(end 112.985042 -33.399984)
		(stroke
			(width 0.2)
			(type default)
		)
		(layer "In1.Cu")
	)
	(gr_line
		(start 112.014762 -32.00019)
		(end 112.014762 -33.399984)
		(stroke
			(width 0.2)
			(type default)
		)
		(layer "In1.Cu")
	)
	(gr_line
		(start 112.985042 -37.00018)
		(end 112.985042 -35.600386)
		(stroke
			(width 0.2)
			(type default)
		)
		(layer "In1.Cu")
	)
	(gr_arc
		(start 112.985042 -35.600386)
		(mid 112.500029 -35.114992)
		(end 112.014762 -35.600132)
		(stroke
			(width 0.2)
			(type default)
		)
		(layer "In1.Cu")
	)
	(gr_line
		(start 112.985042 -33.399984)
		(end 112.985042 -32.000444)
		(stroke
			(width 0.2)
			(type default)
		)
		(layer "In1.Cu")
	)
	(gr_arc
		(start 112.985042 -32.000444)
		(mid 112.500029 -31.51505)
		(end 112.014762 -32.00019)
		(stroke
			(width 0.2)
			(type default)
		)
		(layer "In1.Cu")
	)
	(gr_arc
		(start 113.81486 -38.200076)
		(mid 114.3 -38.685216)
		(end 114.78514 -38.200076)
		(stroke
			(width 0.2)
			(type default)
		)
		(layer "In1.Cu")
	)
	(gr_line
		(start 113.81486 -36.800028)
		(end 113.81486 -38.200076)
		(stroke
			(width 0.2)
			(type default)
		)
		(layer "In1.Cu")
	)
	(gr_arc
		(start 113.81486 -34.600134)
		(mid 114.3 -35.085274)
		(end 114.78514 -34.600134)
		(stroke
			(width 0.2)
			(type default)
		)
		(layer "In1.Cu")
	)
	(gr_line
		(start 113.81486 -33.200086)
		(end 113.81486 -34.600134)
		(stroke
			(width 0.2)
			(type default)
		)
		(layer "In1.Cu")
	)
	(gr_line
		(start 114.78514 -38.200076)
		(end 114.78514 -36.800282)
		(stroke
			(width 0.2)
			(type default)
		)
		(layer "In1.Cu")
	)
	(gr_arc
		(start 114.78514 -36.800282)
		(mid 114.300127 -36.314888)
		(end 113.81486 -36.800028)
		(stroke
			(width 0.2)
			(type default)
		)
		(layer "In1.Cu")
	)
	(gr_line
		(start 114.78514 -34.600134)
		(end 114.78514 -33.20034)
		(stroke
			(width 0.2)
			(type default)
		)
		(layer "In1.Cu")
	)
	(gr_arc
		(start 114.78514 -33.20034)
		(mid 114.300127 -32.714946)
		(end 113.81486 -33.200086)
		(stroke
			(width 0.2)
			(type default)
		)
		(layer "In1.Cu")
	)
	(gr_arc
		(start 115.614704 -37.00018)
		(mid 116.099844 -37.48532)
		(end 116.584984 -37.00018)
		(stroke
			(width 0.2)
			(type default)
		)
		(layer "In1.Cu")
	)
	(gr_line
		(start 115.614704 -35.600132)
		(end 115.614704 -37.00018)
		(stroke
			(width 0.2)
			(type default)
		)
		(layer "In1.Cu")
	)
	(gr_arc
		(start 115.614704 -33.399984)
		(mid 116.099844 -33.885124)
		(end 116.584984 -33.399984)
		(stroke
			(width 0.2)
			(type default)
		)
		(layer "In1.Cu")
	)
	(gr_line
		(start 115.614704 -32.00019)
		(end 115.614704 -33.399984)
		(stroke
			(width 0.2)
			(type default)
		)
		(layer "In1.Cu")
	)
	(gr_line
		(start 116.584984 -37.00018)
		(end 116.584984 -35.600386)
		(stroke
			(width 0.2)
			(type default)
		)
		(layer "In1.Cu")
	)
	(gr_arc
		(start 116.584984 -35.600386)
		(mid 116.099971 -35.114992)
		(end 115.614704 -35.600132)
		(stroke
			(width 0.2)
			(type default)
		)
		(layer "In1.Cu")
	)
	(gr_line
		(start 116.584984 -33.399984)
		(end 116.584984 -32.000444)
		(stroke
			(width 0.2)
			(type default)
		)
		(layer "In1.Cu")
	)
	(gr_arc
		(start 116.584984 -32.000444)
		(mid 116.099971 -31.51505)
		(end 115.614704 -32.00019)
		(stroke
			(width 0.2)
			(type default)
		)
		(layer "In1.Cu")
	)
	(gr_arc
		(start 117.414802 -38.200076)
		(mid 117.899942 -38.685216)
		(end 118.385082 -38.200076)
		(stroke
			(width 0.2)
			(type default)
		)
		(layer "In1.Cu")
	)
	(gr_line
		(start 117.414802 -36.800028)
		(end 117.414802 -38.200076)
		(stroke
			(width 0.2)
			(type default)
		)
		(layer "In1.Cu")
	)
	(gr_arc
		(start 117.414802 -34.600134)
		(mid 117.899942 -35.085274)
		(end 118.385082 -34.600134)
		(stroke
			(width 0.2)
			(type default)
		)
		(layer "In1.Cu")
	)
	(gr_line
		(start 117.414802 -33.200086)
		(end 117.414802 -34.600134)
		(stroke
			(width 0.2)
			(type default)
		)
		(layer "In1.Cu")
	)
	(gr_line
		(start 118.385082 -38.200076)
		(end 118.385082 -36.800282)
		(stroke
			(width 0.2)
			(type default)
		)
		(layer "In1.Cu")
	)
	(gr_arc
		(start 118.385082 -36.800282)
		(mid 117.900069 -36.314888)
		(end 117.414802 -36.800028)
		(stroke
			(width 0.2)
			(type default)
		)
		(layer "In1.Cu")
	)
	(gr_line
		(start 118.385082 -34.600134)
		(end 118.385082 -33.20034)
		(stroke
			(width 0.2)
			(type default)
		)
		(layer "In1.Cu")
	)
	(gr_arc
		(start 118.385082 -33.20034)
		(mid 117.900069 -32.714946)
		(end 117.414802 -33.200086)
		(stroke
			(width 0.2)
			(type default)
		)
		(layer "In1.Cu")
	)
	(gr_arc
		(start 119.2149 -37.00018)
		(mid 119.70004 -37.48532)
		(end 120.18518 -37.00018)
		(stroke
			(width 0.2)
			(type default)
		)
		(layer "In1.Cu")
	)
	(gr_line
		(start 119.2149 -35.600132)
		(end 119.2149 -37.00018)
		(stroke
			(width 0.2)
			(type default)
		)
		(layer "In1.Cu")
	)
	(gr_arc
		(start 119.2149 -33.399984)
		(mid 119.70004 -33.885124)
		(end 120.18518 -33.399984)
		(stroke
			(width 0.2)
			(type default)
		)
		(layer "In1.Cu")
	)
	(gr_line
		(start 119.2149 -32.00019)
		(end 119.2149 -33.399984)
		(stroke
			(width 0.2)
			(type default)
		)
		(layer "In1.Cu")
	)
	(gr_line
		(start 119.295164 -4.526026)
		(end 111.897414 -4.526026)
		(stroke
			(width 0.381)
			(type default)
		)
		(layer "In1.Cu")
	)
	(gr_line
		(start 119.775732 -4.045458)
		(end 119.295164 -4.526026)
		(stroke
			(width 0.381)
			(type default)
		)
		(layer "In1.Cu")
	)
	(gr_line
		(start 120.18518 -37.00018)
		(end 120.18518 -35.600386)
		(stroke
			(width 0.2)
			(type default)
		)
		(layer "In1.Cu")
	)
	(gr_arc
		(start 120.18518 -35.600386)
		(mid 119.700167 -35.114992)
		(end 119.2149 -35.600132)
		(stroke
			(width 0.2)
			(type default)
		)
		(layer "In1.Cu")
	)
	(gr_line
		(start 120.18518 -33.399984)
		(end 120.18518 -32.000444)
		(stroke
			(width 0.2)
			(type default)
		)
		(layer "In1.Cu")
	)
	(gr_arc
		(start 120.18518 -32.000444)
		(mid 119.700167 -31.51505)
		(end 119.2149 -32.00019)
		(stroke
			(width 0.2)
			(type default)
		)
		(layer "In1.Cu")
	)
	(gr_line
		(start 120.5357 -16.383)
		(end 120.7135 -16.5608)
		(stroke
			(width 0.381)
			(type default)
		)
		(layer "In1.Cu")
	)
	(gr_line
		(start 120.7135 -17.7546)
		(end 121.3612 -18.4023)
		(stroke
			(width 0.381)
			(type default)
		)
		(layer "In1.Cu")
	)
	(gr_line
		(start 120.7135 -16.5608)
		(end 120.7135 -17.7546)
		(stroke
			(width 0.381)
			(type default)
		)
		(layer "In1.Cu")
	)
	(gr_line
		(start 121.3612 -18.4023)
		(end 126.7714 -18.4023)
		(stroke
			(width 0.381)
			(type default)
		)
		(layer "In1.Cu")
	)
	(gr_line
		(start 126.43485 -4.045458)
		(end 119.775732 -4.045458)
		(stroke
			(width 0.381)
			(type default)
		)
		(layer "In1.Cu")
	)
	(gr_line
		(start 126.648718 -9.978898)
		(end 126.648718 -4.259326)
		(stroke
			(width 0.381)
			(type default)
		)
		(layer "In1.Cu")
	)
	(gr_line
		(start 126.648718 -4.259326)
		(end 126.43485 -4.045458)
		(stroke
			(width 0.381)
			(type default)
		)
		(layer "In1.Cu")
	)
	(gr_line
		(start 126.7714 -18.4023)
		(end 128.7145 -16.4592)
		(stroke
			(width 0.381)
			(type default)
		)
		(layer "In1.Cu")
	)
	(gr_arc
		(start 128.214882 -38.200076)
		(mid 128.700022 -38.685216)
		(end 129.185162 -38.200076)
		(stroke
			(width 0.2)
			(type default)
		)
		(layer "In1.Cu")
	)
	(gr_line
		(start 128.214882 -36.800028)
		(end 128.214882 -38.200076)
		(stroke
			(width 0.2)
			(type default)
		)
		(layer "In1.Cu")
	)
	(gr_arc
		(start 128.214882 -34.600134)
		(mid 128.700022 -35.085274)
		(end 129.185162 -34.600134)
		(stroke
			(width 0.2)
			(type default)
		)
		(layer "In1.Cu")
	)
	(gr_line
		(start 128.214882 -33.200086)
		(end 128.214882 -34.600134)
		(stroke
			(width 0.2)
			(type default)
		)
		(layer "In1.Cu")
	)
	(gr_line
		(start 128.7145 -16.4592)
		(end 128.7145 -12.04468)
		(stroke
			(width 0.381)
			(type default)
		)
		(layer "In1.Cu")
	)
	(gr_line
		(start 128.7145 -12.04468)
		(end 126.648718 -9.978898)
		(stroke
			(width 0.381)
			(type default)
		)
		(layer "In1.Cu")
	)
	(gr_line
		(start 129.185162 -38.200076)
		(end 129.185162 -36.800282)
		(stroke
			(width 0.2)
			(type default)
		)
		(layer "In1.Cu")
	)
	(gr_arc
		(start 129.185162 -36.800282)
		(mid 128.700149 -36.314888)
		(end 128.214882 -36.800028)
		(stroke
			(width 0.2)
			(type default)
		)
		(layer "In1.Cu")
	)
	(gr_line
		(start 129.185162 -34.600134)
		(end 129.185162 -33.20034)
		(stroke
			(width 0.2)
			(type default)
		)
		(layer "In1.Cu")
	)
	(gr_arc
		(start 129.185162 -33.20034)
		(mid 128.700149 -32.714946)
		(end 128.214882 -33.200086)
		(stroke
			(width 0.2)
			(type default)
		)
		(layer "In1.Cu")
	)
	(gr_arc
		(start 130.014726 -37.00018)
		(mid 130.499866 -37.48532)
		(end 130.985006 -37.00018)
		(stroke
			(width 0.2)
			(type default)
		)
		(layer "In1.Cu")
	)
	(gr_line
		(start 130.014726 -35.600132)
		(end 130.014726 -37.00018)
		(stroke
			(width 0.2)
			(type default)
		)
		(layer "In1.Cu")
	)
	(gr_arc
		(start 130.014726 -33.399984)
		(mid 130.499866 -33.885124)
		(end 130.985006 -33.399984)
		(stroke
			(width 0.2)
			(type default)
		)
		(layer "In1.Cu")
	)
	(gr_line
		(start 130.014726 -32.00019)
		(end 130.014726 -33.399984)
		(stroke
			(width 0.2)
			(type default)
		)
		(layer "In1.Cu")
	)
	(gr_line
		(start 130.985006 -37.00018)
		(end 130.985006 -35.600386)
		(stroke
			(width 0.2)
			(type default)
		)
		(layer "In1.Cu")
	)
	(gr_arc
		(start 130.985006 -35.600386)
		(mid 130.499993 -35.114992)
		(end 130.014726 -35.600132)
		(stroke
			(width 0.2)
			(type default)
		)
		(layer "In1.Cu")
	)
	(gr_line
		(start 130.985006 -33.399984)
		(end 130.985006 -32.000444)
		(stroke
			(width 0.2)
			(type default)
		)
		(layer "In1.Cu")
	)
	(gr_arc
		(start 130.985006 -32.000444)
		(mid 130.499993 -31.51505)
		(end 130.014726 -32.00019)
		(stroke
			(width 0.2)
			(type default)
		)
		(layer "In1.Cu")
	)
	(gr_arc
		(start 131.814824 -38.200076)
		(mid 132.299964 -38.685216)
		(end 132.785104 -38.200076)
		(stroke
			(width 0.2)
			(type default)
		)
		(layer "In1.Cu")
	)
	(gr_line
		(start 131.814824 -36.800028)
		(end 131.814824 -38.200076)
		(stroke
			(width 0.2)
			(type default)
		)
		(layer "In1.Cu")
	)
	(gr_arc
		(start 131.814824 -34.600134)
		(mid 132.299964 -35.085274)
		(end 132.785104 -34.600134)
		(stroke
			(width 0.2)
			(type default)
		)
		(layer "In1.Cu")
	)
	(gr_line
		(start 131.814824 -33.200086)
		(end 131.814824 -34.600134)
		(stroke
			(width 0.2)
			(type default)
		)
		(layer "In1.Cu")
	)
	(gr_line
		(start 132.785104 -38.200076)
		(end 132.785104 -36.800282)
		(stroke
			(width 0.2)
			(type default)
		)
		(layer "In1.Cu")
	)
	(gr_arc
		(start 132.785104 -36.800282)
		(mid 132.300091 -36.314888)
		(end 131.814824 -36.800028)
		(stroke
			(width 0.2)
			(type default)
		)
		(layer "In1.Cu")
	)
	(gr_line
		(start 132.785104 -34.600134)
		(end 132.785104 -33.20034)
		(stroke
			(width 0.2)
			(type default)
		)
		(layer "In1.Cu")
	)
	(gr_arc
		(start 132.785104 -33.20034)
		(mid 132.300091 -32.714946)
		(end 131.814824 -33.200086)
		(stroke
			(width 0.2)
			(type default)
		)
		(layer "In1.Cu")
	)
	(gr_arc
		(start 133.614922 -37.00018)
		(mid 134.100062 -37.48532)
		(end 134.585202 -37.00018)
		(stroke
			(width 0.2)
			(type default)
		)
		(layer "In1.Cu")
	)
	(gr_line
		(start 133.614922 -35.600132)
		(end 133.614922 -37.00018)
		(stroke
			(width 0.2)
			(type default)
		)
		(layer "In1.Cu")
	)
	(gr_arc
		(start 133.614922 -33.399984)
		(mid 134.100062 -33.885124)
		(end 134.585202 -33.399984)
		(stroke
			(width 0.2)
			(type default)
		)
		(layer "In1.Cu")
	)
	(gr_line
		(start 133.614922 -32.00019)
		(end 133.614922 -33.399984)
		(stroke
			(width 0.2)
			(type default)
		)
		(layer "In1.Cu")
	)
	(gr_line
		(start 134.585202 -37.00018)
		(end 134.585202 -35.600386)
		(stroke
			(width 0.2)
			(type default)
		)
		(layer "In1.Cu")
	)
	(gr_arc
		(start 134.585202 -35.600386)
		(mid 134.100189 -35.114992)
		(end 133.614922 -35.600132)
		(stroke
			(width 0.2)
			(type default)
		)
		(layer "In1.Cu")
	)
	(gr_line
		(start 134.585202 -33.399984)
		(end 134.585202 -32.000444)
		(stroke
			(width 0.2)
			(type default)
		)
		(layer "In1.Cu")
	)
	(gr_arc
		(start 134.585202 -32.000444)
		(mid 134.100189 -31.51505)
		(end 133.614922 -32.00019)
		(stroke
			(width 0.2)
			(type default)
		)
		(layer "In1.Cu")
	)
	(gr_arc
		(start 135.414766 -38.200076)
		(mid 135.899906 -38.685216)
		(end 136.385046 -38.200076)
		(stroke
			(width 0.2)
			(type default)
		)
		(layer "In1.Cu")
	)
	(gr_line
		(start 135.414766 -36.800028)
		(end 135.414766 -38.200076)
		(stroke
			(width 0.2)
			(type default)
		)
		(layer "In1.Cu")
	)
	(gr_arc
		(start 135.414766 -34.600134)
		(mid 135.899906 -35.085274)
		(end 136.385046 -34.600134)
		(stroke
			(width 0.2)
			(type default)
		)
		(layer "In1.Cu")
	)
	(gr_line
		(start 135.414766 -33.200086)
		(end 135.414766 -34.600134)
		(stroke
			(width 0.2)
			(type default)
		)
		(layer "In1.Cu")
	)
	(gr_line
		(start 136.385046 -38.200076)
		(end 136.385046 -36.800282)
		(stroke
			(width 0.2)
			(type default)
		)
		(layer "In1.Cu")
	)
	(gr_arc
		(start 136.385046 -36.800282)
		(mid 135.900033 -36.314888)
		(end 135.414766 -36.800028)
		(stroke
			(width 0.2)
			(type default)
		)
		(layer "In1.Cu")
	)
	(gr_line
		(start 136.385046 -34.600134)
		(end 136.385046 -33.20034)
		(stroke
			(width 0.2)
			(type default)
		)
		(layer "In1.Cu")
	)
	(gr_arc
		(start 136.385046 -33.20034)
		(mid 135.900033 -32.714946)
		(end 135.414766 -33.200086)
		(stroke
			(width 0.2)
			(type default)
		)
		(layer "In1.Cu")
	)
	(gr_arc
		(start 137.214864 -37.00018)
		(mid 137.700004 -37.48532)
		(end 138.185144 -37.00018)
		(stroke
			(width 0.2)
			(type default)
		)
		(layer "In1.Cu")
	)
	(gr_line
		(start 137.214864 -35.600132)
		(end 137.214864 -37.00018)
		(stroke
			(width 0.2)
			(type default)
		)
		(layer "In1.Cu")
	)
	(gr_arc
		(start 137.214864 -33.399984)
		(mid 137.700004 -33.885124)
		(end 138.185144 -33.399984)
		(stroke
			(width 0.2)
			(type default)
		)
		(layer "In1.Cu")
	)
	(gr_line
		(start 137.214864 -32.00019)
		(end 137.214864 -33.399984)
		(stroke
			(width 0.2)
			(type default)
		)
		(layer "In1.Cu")
	)
	(gr_line
		(start 138.185144 -37.00018)
		(end 138.185144 -35.600386)
		(stroke
			(width 0.2)
			(type default)
		)
		(layer "In1.Cu")
	)
	(gr_arc
		(start 138.185144 -35.600386)
		(mid 137.700131 -35.114992)
		(end 137.214864 -35.600132)
		(stroke
			(width 0.2)
			(type default)
		)
		(layer "In1.Cu")
	)
	(gr_line
		(start 138.185144 -33.399984)
		(end 138.185144 -32.000444)
		(stroke
			(width 0.2)
			(type default)
		)
		(layer "In1.Cu")
	)
	(gr_arc
		(start 138.185144 -32.000444)
		(mid 137.700131 -31.51505)
		(end 137.214864 -32.00019)
		(stroke
			(width 0.2)
			(type default)
		)
		(layer "In1.Cu")
	)
	(gr_arc
		(start 139.014708 -38.200076)
		(mid 139.499848 -38.685216)
		(end 139.984988 -38.200076)
		(stroke
			(width 0.2)
			(type default)
		)
		(layer "In1.Cu")
	)
	(gr_line
		(start 139.014708 -36.800028)
		(end 139.014708 -38.200076)
		(stroke
			(width 0.2)
			(type default)
		)
		(layer "In1.Cu")
	)
	(gr_arc
		(start 139.014708 -34.600134)
		(mid 139.499848 -35.085274)
		(end 139.984988 -34.600134)
		(stroke
			(width 0.2)
			(type default)
		)
		(layer "In1.Cu")
	)
	(gr_line
		(start 139.014708 -33.200086)
		(end 139.014708 -34.600134)
		(stroke
			(width 0.2)
			(type default)
		)
		(layer "In1.Cu")
	)
	(gr_line
		(start 139.984988 -38.200076)
		(end 139.984988 -36.800282)
		(stroke
			(width 0.2)
			(type default)
		)
		(layer "In1.Cu")
	)
	(gr_arc
		(start 139.984988 -36.800282)
		(mid 139.499975 -36.314888)
		(end 139.014708 -36.800028)
		(stroke
			(width 0.2)
			(type default)
		)
		(layer "In1.Cu")
	)
	(gr_line
		(start 139.984988 -34.600134)
		(end 139.984988 -33.20034)
		(stroke
			(width 0.2)
			(type default)
		)
		(layer "In1.Cu")
	)
	(gr_arc
		(start 139.984988 -33.20034)
		(mid 139.499975 -32.714946)
		(end 139.014708 -33.200086)
		(stroke
			(width 0.2)
			(type default)
		)
		(layer "In1.Cu")
	)
	(gr_arc
		(start 140.814806 -37.00018)
		(mid 141.299946 -37.48532)
		(end 141.785086 -37.00018)
		(stroke
			(width 0.2)
			(type default)
		)
		(layer "In1.Cu")
	)
	(gr_line
		(start 140.814806 -35.600132)
		(end 140.814806 -37.00018)
		(stroke
			(width 0.2)
			(type default)
		)
		(layer "In1.Cu")
	)
	(gr_arc
		(start 140.814806 -33.399984)
		(mid 141.299946 -33.885124)
		(end 141.785086 -33.399984)
		(stroke
			(width 0.2)
			(type default)
		)
		(layer "In1.Cu")
	)
	(gr_line
		(start 140.814806 -32.00019)
		(end 140.814806 -33.399984)
		(stroke
			(width 0.2)
			(type default)
		)
		(layer "In1.Cu")
	)
	(gr_line
		(start 141.785086 -37.00018)
		(end 141.785086 -35.600386)
		(stroke
			(width 0.2)
			(type default)
		)
		(layer "In1.Cu")
	)
	(gr_arc
		(start 141.785086 -35.600386)
		(mid 141.300073 -35.114992)
		(end 140.814806 -35.600132)
		(stroke
			(width 0.2)
			(type default)
		)
		(layer "In1.Cu")
	)
	(gr_line
		(start 141.785086 -33.399984)
		(end 141.785086 -32.000444)
		(stroke
			(width 0.2)
			(type default)
		)
		(layer "In1.Cu")
	)
	(gr_arc
		(start 141.785086 -32.000444)
		(mid 141.300073 -31.51505)
		(end 140.814806 -32.00019)
		(stroke
			(width 0.2)
			(type default)
		)
		(layer "In1.Cu")
	)
	(gr_line
		(start 143.299942 -47.999904)
		(end 104.70007 -47.999904)
		(stroke
			(width 1.524)
			(type default)
		)
		(layer "In1.Cu")
	)
	(gr_line
		(start 144.29994 -183.76392)
		(end 144.29994 -47.999904)
		(stroke
			(width 1.524)
			(type default)
		)
		(layer "In1.Cu")
	)
	(gr_arc
		(start 144.29994 -183.76392)
		(mid 144.326755 -183.993712)
		(end 144.405604 -184.211214)
		(stroke
			(width 1.524)
			(type default)
		)
		(layer "In1.Cu")
	)
	(gr_arc
		(start 144.29994 -47.999904)
		(mid 143.800068 -47.500032)
		(end 143.299942 -47.999904)
		(stroke
			(width 1.524)
			(type default)
		)
		(layer "In1.Cu")
	)
	(gr_line
		(start 149.023578 -193.447162)
		(end 144.405604 -184.211214)
		(stroke
			(width 1.524)
			(type default)
		)
		(layer "In1.Cu")
	)
	(gr_arc
		(start 149.023578 -193.447162)
		(mid 149.392225 -193.85063)
		(end 149.917912 -194.00012)
		(stroke
			(width 1.524)
			(type default)
		)
		(layer "In1.Cu")
	)
	(gr_arc
		(start 158.833566 -30.277054)
		(mid 159.027114 -30.916626)
		(end 159.666686 -30.723078)
		(stroke
			(width 0.2)
			(type default)
		)
		(layer "In1.Cu")
	)
	(gr_arc
		(start 158.833566 -26.47696)
		(mid 159.027114 -27.116532)
		(end 159.666686 -26.922984)
		(stroke
			(width 0.2)
			(type default)
		)
		(layer "In1.Cu")
	)
	(gr_arc
		(start 158.833566 -18.877026)
		(mid 159.027114 -19.516598)
		(end 159.666686 -19.32305)
		(stroke
			(width 0.2)
			(type default)
		)
		(layer "In1.Cu")
	)
	(gr_arc
		(start 158.836614 -22.671278)
		(mid 159.024316 -23.31492)
		(end 159.666686 -23.12289)
		(stroke
			(width 0.2)
			(type default)
		)
		(layer "In1.Cu")
	)
	(gr_line
		(start 159.583374 -28.877006)
		(end 158.833566 -30.277054)
		(stroke
			(width 0.2)
			(type default)
		)
		(layer "In1.Cu")
	)
	(gr_line
		(start 159.583374 -25.076912)
		(end 158.833566 -26.47696)
		(stroke
			(width 0.2)
			(type default)
		)
		(layer "In1.Cu")
	)
	(gr_line
		(start 159.583374 -21.277072)
		(end 158.836614 -22.671278)
		(stroke
			(width 0.2)
			(type default)
		)
		(layer "In1.Cu")
	)
	(gr_line
		(start 159.583374 -17.476978)
		(end 158.833566 -18.877026)
		(stroke
			(width 0.2)
			(type default)
		)
		(layer "In1.Cu")
	)
	(gr_line
		(start 159.666686 -30.723078)
		(end 160.413446 -29.328618)
		(stroke
			(width 0.2)
			(type default)
		)
		(layer "In1.Cu")
	)
	(gr_line
		(start 159.666686 -26.922984)
		(end 160.413446 -25.528524)
		(stroke
			(width 0.2)
			(type default)
		)
		(layer "In1.Cu")
	)
	(gr_line
		(start 159.666686 -23.12289)
		(end 160.416494 -21.723096)
		(stroke
			(width 0.2)
			(type default)
		)
		(layer "In1.Cu")
	)
	(gr_line
		(start 159.666686 -19.32305)
		(end 160.413446 -17.92859)
		(stroke
			(width 0.2)
			(type default)
		)
		(layer "In1.Cu")
	)
	(gr_arc
		(start 160.413446 -29.328618)
		(mid 160.225744 -28.684976)
		(end 159.583374 -28.877006)
		(stroke
			(width 0.2)
			(type default)
		)
		(layer "In1.Cu")
	)
	(gr_arc
		(start 160.413446 -25.528524)
		(mid 160.225744 -24.884882)
		(end 159.583374 -25.076912)
		(stroke
			(width 0.2)
			(type default)
		)
		(layer "In1.Cu")
	)
	(gr_arc
		(start 160.413446 -17.92859)
		(mid 160.225744 -17.284948)
		(end 159.583374 -17.476978)
		(stroke
			(width 0.2)
			(type default)
		)
		(layer "In1.Cu")
	)
	(gr_arc
		(start 160.416494 -21.723096)
		(mid 160.222946 -21.083524)
		(end 159.583374 -21.277072)
		(stroke
			(width 0.2)
			(type default)
		)
		(layer "In1.Cu")
	)
	(gr_line
		(start 161.081466 -22.675596)
		(end 161.083752 -22.676866)
		(stroke
			(width 0.2)
			(type default)
		)
		(layer "In1.Cu")
	)
	(gr_arc
		(start 161.083498 -30.277054)
		(mid 161.277046 -30.916626)
		(end 161.916618 -30.723078)
		(stroke
			(width 0.2)
			(type default)
		)
		(layer "In1.Cu")
	)
	(gr_arc
		(start 161.083498 -26.47696)
		(mid 161.277046 -27.116532)
		(end 161.916618 -26.922984)
		(stroke
			(width 0.2)
			(type default)
		)
		(layer "In1.Cu")
	)
	(gr_arc
		(start 161.083498 -18.877026)
		(mid 161.277046 -19.516598)
		(end 161.916618 -19.32305)
		(stroke
			(width 0.2)
			(type default)
		)
		(layer "In1.Cu")
	)
	(gr_arc
		(start 161.083752 -22.676866)
		(mid 161.277046 -23.316184)
		(end 161.916364 -23.12289)
		(stroke
			(width 0.2)
			(type default)
		)
		(layer "In1.Cu")
	)
	(gr_line
		(start 161.831528 -21.275802)
		(end 161.081466 -22.675596)
		(stroke
			(width 0.2)
			(type default)
		)
		(layer "In1.Cu")
	)
	(gr_line
		(start 161.83356 -28.877006)
		(end 161.083498 -30.277054)
		(stroke
			(width 0.2)
			(type default)
		)
		(layer "In1.Cu")
	)
	(gr_line
		(start 161.83356 -25.076912)
		(end 161.083498 -26.47696)
		(stroke
			(width 0.2)
			(type default)
		)
		(layer "In1.Cu")
	)
	(gr_line
		(start 161.83356 -17.476978)
		(end 161.083498 -18.877026)
		(stroke
			(width 0.2)
			(type default)
		)
		(layer "In1.Cu")
	)
	(gr_line
		(start 161.833814 -21.277072)
		(end 161.831528 -21.275802)
		(stroke
			(width 0.2)
			(type default)
		)
		(layer "In1.Cu")
	)
	(gr_line
		(start 161.916364 -23.12289)
		(end 161.91865 -23.12416)
		(stroke
			(width 0.2)
			(type default)
		)
		(layer "In1.Cu")
	)
	(gr_line
		(start 161.916618 -30.723078)
		(end 162.663632 -29.328618)
		(stroke
			(width 0.2)
			(type default)
		)
		(layer "In1.Cu")
	)
	(gr_line
		(start 161.916618 -26.922984)
		(end 162.663632 -25.528524)
		(stroke
			(width 0.2)
			(type default)
		)
		(layer "In1.Cu")
	)
	(gr_line
		(start 161.916618 -19.32305)
		(end 162.663632 -17.92859)
		(stroke
			(width 0.2)
			(type default)
		)
		(layer "In1.Cu")
	)
	(gr_line
		(start 161.91865 -23.12416)
		(end 162.668712 -21.72462)
		(stroke
			(width 0.2)
			(type default)
		)
		(layer "In1.Cu")
	)
	(gr_arc
		(start 162.663632 -29.328618)
		(mid 162.47593 -28.684976)
		(end 161.83356 -28.877006)
		(stroke
			(width 0.2)
			(type default)
		)
		(layer "In1.Cu")
	)
	(gr_arc
		(start 162.663632 -25.528524)
		(mid 162.47593 -24.884882)
		(end 161.83356 -25.076912)
		(stroke
			(width 0.2)
			(type default)
		)
		(layer "In1.Cu")
	)
	(gr_arc
		(start 162.663632 -17.92859)
		(mid 162.47593 -17.284948)
		(end 161.83356 -17.476978)
		(stroke
			(width 0.2)
			(type default)
		)
		(layer "In1.Cu")
	)
	(gr_arc
		(start 162.666426 -21.72335)
		(mid 162.473287 -21.083725)
		(end 161.833814 -21.277072)
		(stroke
			(width 0.2)
			(type default)
		)
		(layer "In1.Cu")
	)
	(gr_line
		(start 162.668458 -21.724366)
		(end 162.666426 -21.72335)
		(stroke
			(width 0.2)
			(type default)
		)
		(layer "In1.Cu")
	)
	(gr_line
		(start 162.668712 -21.72462)
		(end 162.668458 -21.724366)
		(stroke
			(width 0.2)
			(type default)
		)
		(layer "In1.Cu")
	)
	(gr_arc
		(start 178.811174 -26.465022)
		(mid 179.015136 -27.138884)
		(end 179.688998 -26.934922)
		(stroke
			(width 0.2)
			(type default)
		)
		(layer "In1.Cu")
	)
	(gr_arc
		(start 178.833526 -30.277054)
		(mid 179.027074 -30.916626)
		(end 179.666646 -30.723078)
		(stroke
			(width 0.2)
			(type default)
		)
		(layer "In1.Cu")
	)
	(gr_arc
		(start 178.833526 -18.877026)
		(mid 179.027074 -19.516598)
		(end 179.666646 -19.32305)
		(stroke
			(width 0.2)
			(type default)
		)
		(layer "In1.Cu")
	)
	(gr_arc
		(start 178.836574 -22.671278)
		(mid 179.024276 -23.31492)
		(end 179.666646 -23.12289)
		(stroke
			(width 0.2)
			(type default)
		)
		(layer "In1.Cu")
	)
	(gr_line
		(start 179.560982 -25.064974)
		(end 178.811174 -26.465022)
		(stroke
			(width 0.2)
			(type default)
		)
		(layer "In1.Cu")
	)
	(gr_line
		(start 179.583334 -28.877006)
		(end 178.833526 -30.277054)
		(stroke
			(width 0.2)
			(type default)
		)
		(layer "In1.Cu")
	)
	(gr_line
		(start 179.583334 -21.277072)
		(end 178.836574 -22.671278)
		(stroke
			(width 0.2)
			(type default)
		)
		(layer "In1.Cu")
	)
	(gr_line
		(start 179.583334 -17.476978)
		(end 178.833526 -18.877026)
		(stroke
			(width 0.2)
			(type default)
		)
		(layer "In1.Cu")
	)
	(gr_line
		(start 179.666646 -30.723078)
		(end 180.413406 -29.328618)
		(stroke
			(width 0.2)
			(type default)
		)
		(layer "In1.Cu")
	)
	(gr_line
		(start 179.666646 -23.12289)
		(end 180.416454 -21.723096)
		(stroke
			(width 0.2)
			(type default)
		)
		(layer "In1.Cu")
	)
	(gr_line
		(start 179.666646 -19.32305)
		(end 180.413406 -17.92859)
		(stroke
			(width 0.2)
			(type default)
		)
		(layer "In1.Cu")
	)
	(gr_line
		(start 179.688998 -26.934922)
		(end 180.43398 -25.543764)
		(stroke
			(width 0.2)
			(type default)
		)
		(layer "In1.Cu")
	)
	(gr_arc
		(start 180.413406 -29.328618)
		(mid 180.225704 -28.684976)
		(end 179.583334 -28.877006)
		(stroke
			(width 0.2)
			(type default)
		)
		(layer "In1.Cu")
	)
	(gr_arc
		(start 180.413406 -17.92859)
		(mid 180.225704 -17.284948)
		(end 179.583334 -17.476978)
		(stroke
			(width 0.2)
			(type default)
		)
		(layer "In1.Cu")
	)
	(gr_arc
		(start 180.416454 -21.723096)
		(mid 180.222906 -21.083524)
		(end 179.583334 -21.277072)
		(stroke
			(width 0.2)
			(type default)
		)
		(layer "In1.Cu")
	)
	(gr_arc
		(start 180.43398 -25.543764)
		(mid 180.239312 -24.863383)
		(end 179.560982 -25.064974)
		(stroke
			(width 0.2)
			(type default)
		)
		(layer "In1.Cu")
	)
	(gr_arc
		(start 181.061106 -26.464768)
		(mid 181.264814 -27.138884)
		(end 181.93893 -26.935176)
		(stroke
			(width 0.2)
			(type default)
		)
		(layer "In1.Cu")
	)
	(gr_line
		(start 181.081426 -22.675596)
		(end 181.083712 -22.676866)
		(stroke
			(width 0.2)
			(type default)
		)
		(layer "In1.Cu")
	)
	(gr_arc
		(start 181.083458 -30.277054)
		(mid 181.277006 -30.916626)
		(end 181.916578 -30.723078)
		(stroke
			(width 0.2)
			(type default)
		)
		(layer "In1.Cu")
	)
	(gr_arc
		(start 181.083458 -18.877026)
		(mid 181.277006 -19.516598)
		(end 181.916578 -19.32305)
		(stroke
			(width 0.2)
			(type default)
		)
		(layer "In1.Cu")
	)
	(gr_arc
		(start 181.083712 -22.676866)
		(mid 181.277006 -23.316184)
		(end 181.916324 -23.12289)
		(stroke
			(width 0.2)
			(type default)
		)
		(layer "In1.Cu")
	)
	(gr_line
		(start 181.811168 -25.06472)
		(end 181.061106 -26.464768)
		(stroke
			(width 0.2)
			(type default)
		)
		(layer "In1.Cu")
	)
	(gr_line
		(start 181.831488 -21.275802)
		(end 181.081426 -22.675596)
		(stroke
			(width 0.2)
			(type default)
		)
		(layer "In1.Cu")
	)
	(gr_line
		(start 181.83352 -28.877006)
		(end 181.083458 -30.277054)
		(stroke
			(width 0.2)
			(type default)
		)
		(layer "In1.Cu")
	)
	(gr_line
		(start 181.83352 -17.476978)
		(end 181.083458 -18.877026)
		(stroke
			(width 0.2)
			(type default)
		)
		(layer "In1.Cu")
	)
	(gr_line
		(start 181.833774 -21.277072)
		(end 181.831488 -21.275802)
		(stroke
			(width 0.2)
			(type default)
		)
		(layer "In1.Cu")
	)
	(gr_line
		(start 181.916324 -23.12289)
		(end 181.91861 -23.12416)
		(stroke
			(width 0.2)
			(type default)
		)
		(layer "In1.Cu")
	)
	(gr_line
		(start 181.916578 -30.723078)
		(end 182.663592 -29.328618)
		(stroke
			(width 0.2)
			(type default)
		)
		(layer "In1.Cu")
	)
	(gr_line
		(start 181.916578 -19.32305)
		(end 182.663592 -17.92859)
		(stroke
			(width 0.2)
			(type default)
		)
		(layer "In1.Cu")
	)
	(gr_line
		(start 181.91861 -23.12416)
		(end 182.668672 -21.72462)
		(stroke
			(width 0.2)
			(type default)
		)
		(layer "In1.Cu")
	)
	(gr_line
		(start 181.93893 -26.935176)
		(end 182.684166 -25.543764)
		(stroke
			(width 0.2)
			(type default)
		)
		(layer "In1.Cu")
	)
	(gr_arc
		(start 182.663592 -29.328618)
		(mid 182.47589 -28.684976)
		(end 181.83352 -28.877006)
		(stroke
			(width 0.2)
			(type default)
		)
		(layer "In1.Cu")
	)
	(gr_arc
		(start 182.663592 -17.92859)
		(mid 182.47589 -17.284948)
		(end 181.83352 -17.476978)
		(stroke
			(width 0.2)
			(type default)
		)
		(layer "In1.Cu")
	)
	(gr_arc
		(start 182.666386 -21.72335)
		(mid 182.473247 -21.083725)
		(end 181.833774 -21.277072)
		(stroke
			(width 0.2)
			(type default)
		)
		(layer "In1.Cu")
	)
	(gr_line
		(start 182.668418 -21.724366)
		(end 182.666386 -21.72335)
		(stroke
			(width 0.2)
			(type default)
		)
		(layer "In1.Cu")
	)
	(gr_line
		(start 182.668672 -21.72462)
		(end 182.668418 -21.724366)
		(stroke
			(width 0.2)
			(type default)
		)
		(layer "In1.Cu")
	)
	(gr_arc
		(start 182.684166 -25.543764)
		(mid 182.489596 -24.863437)
		(end 181.811168 -25.06472)
		(stroke
			(width 0.2)
			(type default)
		)
		(layer "In1.Cu")
	)
	(gr_arc
		(start 189.286134 -84.241132)
		(mid 189.279055 -84.782246)
		(end 189.820296 -84.784692)
		(stroke
			(width 0.2)
			(type default)
		)
		(layer "In1.Cu")
	)
	(gr_line
		(start 189.820296 -84.784692)
		(end 190.448692 -84.156296)
		(stroke
			(width 0.2)
			(type default)
		)
		(layer "In1.Cu")
	)
	(gr_line
		(start 189.909704 -83.617308)
		(end 189.286134 -84.241132)
		(stroke
			(width 0.2)
			(type default)
		)
		(layer "In1.Cu")
	)
	(gr_arc
		(start 190.448692 -84.156296)
		(mid 190.448692 -83.617308)
		(end 189.909704 -83.617308)
		(stroke
			(width 0.2)
			(type default)
		)
		(layer "In1.Cu")
	)
	(gr_arc
		(start 190.835534 -87.035132)
		(mid 190.828455 -87.576246)
		(end 191.369696 -87.578692)
		(stroke
			(width 0.2)
			(type default)
		)
		(layer "In1.Cu")
	)
	(gr_line
		(start 191.369696 -87.578692)
		(end 191.998092 -86.950296)
		(stroke
			(width 0.2)
			(type default)
		)
		(layer "In1.Cu")
	)
	(gr_line
		(start 191.459104 -86.411308)
		(end 190.835534 -87.035132)
		(stroke
			(width 0.2)
			(type default)
		)
		(layer "In1.Cu")
	)
	(gr_arc
		(start 191.64173 -74.699622)
		(mid 191.99987 -75.057762)
		(end 192.35801 -74.699622)
		(stroke
			(width 0.2)
			(type default)
		)
		(layer "In1.Cu")
	)
	(gr_line
		(start 191.64173 -73.899776)
		(end 191.64173 -74.699622)
		(stroke
			(width 0.2)
			(type default)
		)
		(layer "In1.Cu")
	)
	(gr_arc
		(start 191.998092 -86.950296)
		(mid 191.998092 -86.411308)
		(end 191.459104 -86.411308)
		(stroke
			(width 0.2)
			(type default)
		)
		(layer "In1.Cu")
	)
	(gr_line
		(start 192.35801 -74.699622)
		(end 192.35801 -73.90003)
		(stroke
			(width 0.2)
			(type default)
		)
		(layer "In1.Cu")
	)
	(gr_arc
		(start 192.35801 -73.90003)
		(mid 191.999997 -73.541636)
		(end 191.64173 -73.899776)
		(stroke
			(width 0.2)
			(type default)
		)
		(layer "In1.Cu")
	)
	(gr_line
		(start 192.441576 -73.90003)
		(end 192.44183 -74.699876)
		(stroke
			(width 0.2)
			(type default)
		)
		(layer "In1.Cu")
	)
	(gr_arc
		(start 192.44183 -74.699876)
		(mid 192.800097 -75.058016)
		(end 193.15811 -74.699622)
		(stroke
			(width 0.2)
			(type default)
		)
		(layer "In1.Cu")
	)
	(gr_line
		(start 193.157856 -74.257916)
		(end 193.157856 -73.90003)
		(stroke
			(width 0.2)
			(type default)
		)
		(layer "In1.Cu")
	)
	(gr_arc
		(start 193.157856 -73.90003)
		(mid 192.799716 -73.541636)
		(end 192.441576 -73.90003)
		(stroke
			(width 0.2)
			(type default)
		)
		(layer "In1.Cu")
	)
	(gr_line
		(start 193.15811 -74.699622)
		(end 193.157856 -74.257916)
		(stroke
			(width 0.2)
			(type default)
		)
		(layer "In1.Cu")
	)
	(gr_arc
		(start 193.557906 -88.736932)
		(mid 193.550827 -89.278046)
		(end 194.092068 -89.280492)
		(stroke
			(width 0.2)
			(type default)
		)
		(layer "In1.Cu")
	)
	(gr_arc
		(start 193.781934 -84.012532)
		(mid 193.774855 -84.553646)
		(end 194.316096 -84.556092)
		(stroke
			(width 0.2)
			(type default)
		)
		(layer "In1.Cu")
	)
	(gr_arc
		(start 194.03441 -74.698606)
		(mid 194.389248 -75.060048)
		(end 194.75069 -74.70521)
		(stroke
			(width 0.2)
			(type default)
		)
		(layer "In1.Cu")
	)
	(gr_line
		(start 194.041522 -73.896474)
		(end 194.03441 -74.698606)
		(stroke
			(width 0.2)
			(type default)
		)
		(layer "In1.Cu")
	)
	(gr_line
		(start 194.092068 -89.280492)
		(end 194.720464 -88.652096)
		(stroke
			(width 0.2)
			(type default)
		)
		(layer "In1.Cu")
	)
	(gr_line
		(start 194.181476 -88.113108)
		(end 193.557906 -88.736932)
		(stroke
			(width 0.2)
			(type default)
		)
		(layer "In1.Cu")
	)
	(gr_line
		(start 194.316096 -84.556092)
		(end 194.944492 -83.927696)
		(stroke
			(width 0.2)
			(type default)
		)
		(layer "In1.Cu")
	)
	(gr_line
		(start 194.405504 -83.388708)
		(end 193.781934 -84.012532)
		(stroke
			(width 0.2)
			(type default)
		)
		(layer "In1.Cu")
	)
	(gr_arc
		(start 194.720464 -88.652096)
		(mid 194.720464 -88.113108)
		(end 194.181476 -88.113108)
		(stroke
			(width 0.2)
			(type default)
		)
		(layer "In1.Cu")
	)
	(gr_line
		(start 194.75069 -74.70521)
		(end 194.757802 -73.903332)
		(stroke
			(width 0.2)
			(type default)
		)
		(layer "In1.Cu")
	)
	(gr_arc
		(start 194.757802 -73.903332)
		(mid 194.403091 -73.541891)
		(end 194.041522 -73.896474)
		(stroke
			(width 0.2)
			(type default)
		)
		(layer "In1.Cu")
	)
	(gr_arc
		(start 194.840352 -74.706988)
		(mid 195.197984 -75.065636)
		(end 195.556632 -74.708004)
		(stroke
			(width 0.2)
			(type default)
		)
		(layer "In1.Cu")
	)
	(gr_line
		(start 194.841622 -73.899268)
		(end 194.840352 -74.706988)
		(stroke
			(width 0.2)
			(type default)
		)
		(layer "In1.Cu")
	)
	(gr_arc
		(start 194.944492 -83.927696)
		(mid 194.944492 -83.388708)
		(end 194.405504 -83.388708)
		(stroke
			(width 0.2)
			(type default)
		)
		(layer "In1.Cu")
	)
	(gr_line
		(start 195.556632 -74.708004)
		(end 195.556632 -74.707496)
		(stroke
			(width 0.2)
			(type default)
		)
		(layer "In1.Cu")
	)
	(gr_line
		(start 195.556632 -74.707496)
		(end 195.557902 -73.900538)
		(stroke
			(width 0.2)
			(type default)
		)
		(layer "In1.Cu")
	)
	(gr_arc
		(start 195.557902 -73.900538)
		(mid 195.200397 -73.54189)
		(end 194.841622 -73.899268)
		(stroke
			(width 0.2)
			(type default)
		)
		(layer "In1.Cu")
	)
	(gr_line
		(start 196.441568 -73.903586)
		(end 196.44995 -74.702162)
		(stroke
			(width 0.2)
			(type default)
		)
		(layer "In1.Cu")
	)
	(gr_arc
		(start 196.44995 -74.702162)
		(mid 196.8119 -75.056492)
		(end 197.16623 -74.694542)
		(stroke
			(width 0.2)
			(type default)
		)
		(layer "In1.Cu")
	)
	(gr_arc
		(start 196.631306 -85.688932)
		(mid 196.624227 -86.230046)
		(end 197.165468 -86.232492)
		(stroke
			(width 0.2)
			(type default)
		)
		(layer "In1.Cu")
	)
	(gr_arc
		(start 197.157848 -73.89622)
		(mid 196.796025 -73.541889)
		(end 196.441568 -73.903586)
		(stroke
			(width 0.2)
			(type default)
		)
		(layer "In1.Cu")
	)
	(gr_line
		(start 197.165468 -86.232492)
		(end 197.793864 -85.604096)
		(stroke
			(width 0.2)
			(type default)
		)
		(layer "In1.Cu")
	)
	(gr_line
		(start 197.16623 -74.694542)
		(end 197.157848 -73.89622)
		(stroke
			(width 0.2)
			(type default)
		)
		(layer "In1.Cu")
	)
	(gr_line
		(start 197.241668 -73.904094)
		(end 197.251066 -74.70394)
		(stroke
			(width 0.2)
			(type default)
		)
		(layer "In1.Cu")
	)
	(gr_arc
		(start 197.251066 -74.70394)
		(mid 197.613524 -75.057762)
		(end 197.967346 -74.695304)
		(stroke
			(width 0.2)
			(type default)
		)
		(layer "In1.Cu")
	)
	(gr_line
		(start 197.254876 -85.065108)
		(end 196.631306 -85.688932)
		(stroke
			(width 0.2)
			(type default)
		)
		(layer "In1.Cu")
	)
	(gr_arc
		(start 197.793864 -85.604096)
		(mid 197.793864 -85.065108)
		(end 197.254876 -85.065108)
		(stroke
			(width 0.2)
			(type default)
		)
		(layer "In1.Cu")
	)
	(gr_arc
		(start 197.922134 -88.813132)
		(mid 197.915055 -89.354246)
		(end 198.456296 -89.356692)
		(stroke
			(width 0.2)
			(type default)
		)
		(layer "In1.Cu")
	)
	(gr_arc
		(start 197.957948 -73.895712)
		(mid 197.595617 -73.541888)
		(end 197.241668 -73.904094)
		(stroke
			(width 0.2)
			(type default)
		)
		(layer "In1.Cu")
	)
	(gr_line
		(start 197.967346 -74.695304)
		(end 197.957948 -73.895712)
		(stroke
			(width 0.2)
			(type default)
		)
		(layer "In1.Cu")
	)
	(gr_line
		(start 198.456296 -89.356692)
		(end 199.084692 -88.728296)
		(stroke
			(width 0.2)
			(type default)
		)
		(layer "In1.Cu")
	)
	(gr_line
		(start 198.545704 -88.189308)
		(end 197.922134 -88.813132)
		(stroke
			(width 0.2)
			(type default)
		)
		(layer "In1.Cu")
	)
	(gr_line
		(start 198.841614 -73.900538)
		(end 198.843392 -74.693018)
		(stroke
			(width 0.2)
			(type default)
		)
		(layer "In1.Cu")
	)
	(gr_arc
		(start 198.843392 -74.693018)
		(mid 199.202294 -75.050396)
		(end 199.559672 -74.691494)
		(stroke
			(width 0.2)
			(type default)
		)
		(layer "In1.Cu")
	)
	(gr_arc
		(start 199.084692 -88.728296)
		(mid 199.084692 -88.189308)
		(end 198.545704 -88.189308)
		(stroke
			(width 0.2)
			(type default)
		)
		(layer "In1.Cu")
	)
	(gr_line
		(start 199.557894 -73.899776)
		(end 199.557894 -73.899268)
		(stroke
			(width 0.2)
			(type default)
		)
		(layer "In1.Cu")
	)
	(gr_arc
		(start 199.557894 -73.899268)
		(mid 199.199119 -73.54189)
		(end 198.841614 -73.900538)
		(stroke
			(width 0.2)
			(type default)
		)
		(layer "In1.Cu")
	)
	(gr_line
		(start 199.559672 -74.691494)
		(end 199.557894 -73.899776)
		(stroke
			(width 0.2)
			(type default)
		)
		(layer "In1.Cu")
	)
	(gr_line
		(start 199.641714 -73.900538)
		(end 199.643492 -74.695558)
		(stroke
			(width 0.2)
			(type default)
		)
		(layer "In1.Cu")
	)
	(gr_arc
		(start 199.643492 -74.695558)
		(mid 200.002394 -75.052936)
		(end 200.359772 -74.694034)
		(stroke
			(width 0.2)
			(type default)
		)
		(layer "In1.Cu")
	)
	(gr_line
		(start 200.357994 -73.899776)
		(end 200.357994 -73.899268)
		(stroke
			(width 0.2)
			(type default)
		)
		(layer "In1.Cu")
	)
	(gr_arc
		(start 200.357994 -73.899268)
		(mid 199.999219 -73.54189)
		(end 199.641714 -73.900538)
		(stroke
			(width 0.2)
			(type default)
		)
		(layer "In1.Cu")
	)
	(gr_line
		(start 200.359772 -74.694034)
		(end 200.357994 -73.899776)
		(stroke
			(width 0.2)
			(type default)
		)
		(layer "In1.Cu")
	)
	(gr_line
		(start 200.79843 -74.287126)
		(end 201.598276 -74.287126)
		(stroke
			(width 0.2)
			(type default)
		)
		(layer "In1.Cu")
	)
	(gr_arc
		(start 200.798684 -73.520046)
		(mid 200.41489 -73.903459)
		(end 200.79843 -74.287126)
		(stroke
			(width 0.2)
			(type default)
		)
		(layer "In1.Cu")
	)
	(gr_arc
		(start 200.944734 -85.815932)
		(mid 200.937655 -86.357046)
		(end 201.478896 -86.359492)
		(stroke
			(width 0.2)
			(type default)
		)
		(layer "In1.Cu")
	)
	(gr_arc
		(start 201.209656 -67.49923)
		(mid 201.590021 -67.886073)
		(end 201.976736 -67.50558)
		(stroke
			(width 0.2)
			(type default)
		)
		(layer "In1.Cu")
	)
	(gr_arc
		(start 201.20991 -72.297036)
		(mid 201.592815 -72.681338)
		(end 201.97699 -72.298306)
		(stroke
			(width 0.2)
			(type default)
		)
		(layer "In1.Cu")
	)
	(gr_line
		(start 201.210926 -71.502524)
		(end 201.20991 -72.297036)
		(stroke
			(width 0.2)
			(type default)
		)
		(layer "In1.Cu")
	)
	(gr_line
		(start 201.211688 -69.111114)
		(end 201.225658 -69.906388)
		(stroke
			(width 0.2)
			(type default)
		)
		(layer "In1.Cu")
	)
	(gr_line
		(start 201.216006 -66.705988)
		(end 201.209656 -67.49923)
		(stroke
			(width 0.2)
			(type default)
		)
		(layer "In1.Cu")
	)
	(gr_arc
		(start 201.225658 -69.906388)
		(mid 201.615929 -70.283322)
		(end 201.992738 -69.892926)
		(stroke
			(width 0.2)
			(type default)
		)
		(layer "In1.Cu")
	)
	(gr_line
		(start 201.478896 -86.359492)
		(end 202.107292 -85.731096)
		(stroke
			(width 0.2)
			(type default)
		)
		(layer "In1.Cu")
	)
	(gr_line
		(start 201.568304 -85.192108)
		(end 200.944734 -85.815932)
		(stroke
			(width 0.2)
			(type default)
		)
		(layer "In1.Cu")
	)
	(gr_line
		(start 201.591672 -68.678806)
		(end 202.39609 -68.68668)
		(stroke
			(width 0.2)
			(type default)
		)
		(layer "In1.Cu")
	)
	(gr_line
		(start 201.592688 -71.086218)
		(end 202.40371 -71.087996)
		(stroke
			(width 0.2)
			(type default)
		)
		(layer "In1.Cu")
	)
	(gr_arc
		(start 201.594466 -70.319138)
		(mid 201.210164 -70.701789)
		(end 201.592688 -71.086218)
		(stroke
			(width 0.2)
			(type default)
		)
		(layer "In1.Cu")
	)
	(gr_arc
		(start 201.598276 -74.287126)
		(mid 201.981816 -73.903586)
		(end 201.598276 -73.520046)
		(stroke
			(width 0.2)
			(type default)
		)
		(layer "In1.Cu")
	)
	(gr_line
		(start 201.598276 -73.520046)
		(end 200.798684 -73.520046)
		(stroke
			(width 0.2)
			(type default)
		)
		(layer "In1.Cu")
	)
	(gr_arc
		(start 201.599292 -72.716898)
		(mid 201.217276 -73.101835)
		(end 201.602086 -73.483978)
		(stroke
			(width 0.2)
			(type default)
		)
		(layer "In1.Cu")
	)
	(gr_arc
		(start 201.599546 -67.911726)
		(mid 201.212197 -68.291329)
		(end 201.591672 -68.678806)
		(stroke
			(width 0.2)
			(type default)
		)
		(layer "In1.Cu")
	)
	(gr_line
		(start 201.5998 -75.883262)
		(end 202.399646 -75.883262)
		(stroke
			(width 0.2)
			(type default)
		)
		(layer "In1.Cu")
	)
	(gr_arc
		(start 201.600054 -75.116182)
		(mid 201.21626 -75.499595)
		(end 201.5998 -75.883262)
		(stroke
			(width 0.2)
			(type default)
		)
		(layer "In1.Cu")
	)
	(gr_line
		(start 201.602086 -73.483978)
		(end 202.39863 -73.480676)
		(stroke
			(width 0.2)
			(type default)
		)
		(layer "In1.Cu")
	)
	(gr_line
		(start 201.976736 -67.50558)
		(end 201.983086 -66.712084)
		(stroke
			(width 0.2)
			(type default)
		)
		(layer "In1.Cu")
	)
	(gr_line
		(start 201.97699 -72.298306)
		(end 201.97699 -72.297798)
		(stroke
			(width 0.2)
			(type default)
		)
		(layer "In1.Cu")
	)
	(gr_line
		(start 201.97699 -72.297798)
		(end 201.978006 -71.50354)
		(stroke
			(width 0.2)
			(type default)
		)
		(layer "In1.Cu")
	)
	(gr_arc
		(start 201.978006 -71.50354)
		(mid 201.594974 -71.119492)
		(end 201.210926 -71.502524)
		(stroke
			(width 0.2)
			(type default)
		)
		(layer "In1.Cu")
	)
	(gr_arc
		(start 201.978768 -69.097398)
		(mid 201.58837 -68.720716)
		(end 201.211688 -69.111114)
		(stroke
			(width 0.2)
			(type default)
		)
		(layer "In1.Cu")
	)
	(gr_arc
		(start 201.983086 -66.712084)
		(mid 201.602594 -66.325496)
		(end 201.216006 -66.705988)
		(stroke
			(width 0.2)
			(type default)
		)
		(layer "In1.Cu")
	)
	(gr_line
		(start 201.992738 -69.892926)
		(end 201.978768 -69.097398)
		(stroke
			(width 0.2)
			(type default)
		)
		(layer "In1.Cu")
	)
	(gr_arc
		(start 202.107292 -85.731096)
		(mid 202.107292 -85.192108)
		(end 201.568304 -85.192108)
		(stroke
			(width 0.2)
			(type default)
		)
		(layer "In1.Cu")
	)
	(gr_line
		(start 202.395582 -72.713596)
		(end 201.599292 -72.716898)
		(stroke
			(width 0.2)
			(type default)
		)
		(layer "In1.Cu")
	)
	(gr_arc
		(start 202.39609 -68.68668)
		(mid 202.78344 -68.30695)
		(end 202.40371 -67.9196)
		(stroke
			(width 0.2)
			(type default)
		)
		(layer "In1.Cu")
	)
	(gr_arc
		(start 202.39863 -73.480676)
		(mid 202.780646 -73.095612)
		(end 202.395582 -72.713596)
		(stroke
			(width 0.2)
			(type default)
		)
		(layer "In1.Cu")
	)
	(gr_arc
		(start 202.399646 -75.883262)
		(mid 202.783186 -75.499722)
		(end 202.399646 -75.116182)
		(stroke
			(width 0.2)
			(type default)
		)
		(layer "In1.Cu")
	)
	(gr_line
		(start 202.399646 -75.116182)
		(end 201.600054 -75.116182)
		(stroke
			(width 0.2)
			(type default)
		)
		(layer "In1.Cu")
	)
	(gr_arc
		(start 202.40371 -71.087996)
		(mid 202.788012 -70.705218)
		(end 202.405234 -70.320916)
		(stroke
			(width 0.2)
			(type default)
		)
		(layer "In1.Cu")
	)
	(gr_line
		(start 202.40371 -67.9196)
		(end 201.599546 -67.911726)
		(stroke
			(width 0.2)
			(type default)
		)
		(layer "In1.Cu")
	)
	(gr_line
		(start 202.405234 -70.320916)
		(end 201.594466 -70.319138)
		(stroke
			(width 0.2)
			(type default)
		)
		(layer "In1.Cu")
	)
	(gr_arc
		(start 203.535534 -85.231732)
		(mid 203.528455 -85.772846)
		(end 204.069696 -85.775292)
		(stroke
			(width 0.2)
			(type default)
		)
		(layer "In1.Cu")
	)
	(gr_line
		(start 204.069696 -85.775292)
		(end 204.698092 -85.146896)
		(stroke
			(width 0.2)
			(type default)
		)
		(layer "In1.Cu")
	)
	(gr_line
		(start 204.159104 -84.607908)
		(end 203.535534 -85.231732)
		(stroke
			(width 0.2)
			(type default)
		)
		(layer "In1.Cu")
	)
	(gr_arc
		(start 204.698092 -85.146896)
		(mid 204.698092 -84.607908)
		(end 204.159104 -84.607908)
		(stroke
			(width 0.2)
			(type default)
		)
		(layer "In1.Cu")
	)
	(gr_arc
		(start 207.598772 -76.8096)
		(mid 207.613651 -76.845521)
		(end 207.649572 -76.8604)
		(stroke
			(width 0.2)
			(type default)
		)
		(layer "In1.Cu")
	)
	(gr_line
		(start 207.598772 -76.6064)
		(end 207.598772 -76.8096)
		(stroke
			(width 0.2)
			(type default)
		)
		(layer "In1.Cu")
	)
	(gr_arc
		(start 207.598772 -76.2508)
		(mid 207.613651 -76.286721)
		(end 207.649572 -76.3016)
		(stroke
			(width 0.2)
			(type default)
		)
		(layer "In1.Cu")
	)
	(gr_line
		(start 207.598772 -76.0476)
		(end 207.598772 -76.2508)
		(stroke
			(width 0.2)
			(type default)
		)
		(layer "In1.Cu")
	)
	(gr_arc
		(start 207.598772 -75.1332)
		(mid 207.613651 -75.169121)
		(end 207.649572 -75.184)
		(stroke
			(width 0.2)
			(type default)
		)
		(layer "In1.Cu")
	)
	(gr_line
		(start 207.598772 -74.93)
		(end 207.598772 -75.1332)
		(stroke
			(width 0.2)
			(type default)
		)
		(layer "In1.Cu")
	)
	(gr_arc
		(start 207.598772 -74.5744)
		(mid 207.613651 -74.610321)
		(end 207.649572 -74.6252)
		(stroke
			(width 0.2)
			(type default)
		)
		(layer "In1.Cu")
	)
	(gr_line
		(start 207.598772 -74.3712)
		(end 207.598772 -74.5744)
		(stroke
			(width 0.2)
			(type default)
		)
		(layer "In1.Cu")
	)
	(gr_arc
		(start 207.598772 -73.4568)
		(mid 207.613651 -73.492721)
		(end 207.649572 -73.5076)
		(stroke
			(width 0.2)
			(type default)
		)
		(layer "In1.Cu")
	)
	(gr_line
		(start 207.598772 -73.2536)
		(end 207.598772 -73.4568)
		(stroke
			(width 0.2)
			(type default)
		)
		(layer "In1.Cu")
	)
	(gr_arc
		(start 207.598772 -72.898)
		(mid 207.613651 -72.933921)
		(end 207.649572 -72.9488)
		(stroke
			(width 0.2)
			(type default)
		)
		(layer "In1.Cu")
	)
	(gr_line
		(start 207.598772 -72.6948)
		(end 207.598772 -72.898)
		(stroke
			(width 0.2)
			(type default)
		)
		(layer "In1.Cu")
	)
	(gr_arc
		(start 207.598772 -71.7804)
		(mid 207.613651 -71.816321)
		(end 207.649572 -71.8312)
		(stroke
			(width 0.2)
			(type default)
		)
		(layer "In1.Cu")
	)
	(gr_line
		(start 207.598772 -71.5772)
		(end 207.598772 -71.7804)
		(stroke
			(width 0.2)
			(type default)
		)
		(layer "In1.Cu")
	)
	(gr_arc
		(start 207.598772 -71.2216)
		(mid 207.613651 -71.257521)
		(end 207.649572 -71.2724)
		(stroke
			(width 0.2)
			(type default)
		)
		(layer "In1.Cu")
	)
	(gr_line
		(start 207.598772 -71.0184)
		(end 207.598772 -71.2216)
		(stroke
			(width 0.2)
			(type default)
		)
		(layer "In1.Cu")
	)
	(gr_arc
		(start 207.598772 -70.104)
		(mid 207.613651 -70.139921)
		(end 207.649572 -70.1548)
		(stroke
			(width 0.2)
			(type default)
		)
		(layer "In1.Cu")
	)
	(gr_line
		(start 207.598772 -69.9008)
		(end 207.598772 -70.104)
		(stroke
			(width 0.2)
			(type default)
		)
		(layer "In1.Cu")
	)
	(gr_arc
		(start 207.598772 -69.5452)
		(mid 207.613651 -69.581121)
		(end 207.649572 -69.596)
		(stroke
			(width 0.2)
			(type default)
		)
		(layer "In1.Cu")
	)
	(gr_line
		(start 207.598772 -69.342)
		(end 207.598772 -69.5452)
		(stroke
			(width 0.2)
			(type default)
		)
		(layer "In1.Cu")
	)
	(gr_arc
		(start 207.598772 -68.4276)
		(mid 207.613651 -68.463521)
		(end 207.649572 -68.4784)
		(stroke
			(width 0.2)
			(type default)
		)
		(layer "In1.Cu")
	)
	(gr_line
		(start 207.598772 -68.2244)
		(end 207.598772 -68.4276)
		(stroke
			(width 0.2)
			(type default)
		)
		(layer "In1.Cu")
	)
	(gr_arc
		(start 207.598772 -67.8688)
		(mid 207.613651 -67.904721)
		(end 207.649572 -67.9196)
		(stroke
			(width 0.2)
			(type default)
		)
		(layer "In1.Cu")
	)
	(gr_line
		(start 207.598772 -67.6656)
		(end 207.598772 -67.8688)
		(stroke
			(width 0.2)
			(type default)
		)
		(layer "In1.Cu")
	)
	(gr_arc
		(start 207.598772 -66.7512)
		(mid 207.613651 -66.787121)
		(end 207.649572 -66.802)
		(stroke
			(width 0.2)
			(type default)
		)
		(layer "In1.Cu")
	)
	(gr_line
		(start 207.598772 -66.548)
		(end 207.598772 -66.7512)
		(stroke
			(width 0.2)
			(type default)
		)
		(layer "In1.Cu")
	)
	(gr_arc
		(start 207.598772 -66.1924)
		(mid 207.613651 -66.228321)
		(end 207.649572 -66.2432)
		(stroke
			(width 0.2)
			(type default)
		)
		(layer "In1.Cu")
	)
	(gr_line
		(start 207.598772 -65.9892)
		(end 207.598772 -66.1924)
		(stroke
			(width 0.2)
			(type default)
		)
		(layer "In1.Cu")
	)
	(gr_arc
		(start 207.598772 -65.0748)
		(mid 207.613651 -65.110721)
		(end 207.649572 -65.1256)
		(stroke
			(width 0.2)
			(type default)
		)
		(layer "In1.Cu")
	)
	(gr_line
		(start 207.598772 -64.8716)
		(end 207.598772 -65.0748)
		(stroke
			(width 0.2)
			(type default)
		)
		(layer "In1.Cu")
	)
	(gr_arc
		(start 207.598772 -64.516)
		(mid 207.613651 -64.551921)
		(end 207.649572 -64.5668)
		(stroke
			(width 0.2)
			(type default)
		)
		(layer "In1.Cu")
	)
	(gr_line
		(start 207.598772 -64.3128)
		(end 207.598772 -64.516)
		(stroke
			(width 0.2)
			(type default)
		)
		(layer "In1.Cu")
	)
	(gr_line
		(start 207.649572 -76.8604)
		(end 208.462372 -76.8604)
		(stroke
			(width 0.2)
			(type default)
		)
		(layer "In1.Cu")
	)
	(gr_arc
		(start 207.649572 -76.5556)
		(mid 207.613651 -76.570479)
		(end 207.598772 -76.6064)
		(stroke
			(width 0.2)
			(type default)
		)
		(layer "In1.Cu")
	)
	(gr_line
		(start 207.649572 -76.3016)
		(end 208.462372 -76.3016)
		(stroke
			(width 0.2)
			(type default)
		)
		(layer "In1.Cu")
	)
	(gr_arc
		(start 207.649572 -75.9968)
		(mid 207.613651 -76.011679)
		(end 207.598772 -76.0476)
		(stroke
			(width 0.2)
			(type default)
		)
		(layer "In1.Cu")
	)
	(gr_line
		(start 207.649572 -75.184)
		(end 208.462372 -75.184)
		(stroke
			(width 0.2)
			(type default)
		)
		(layer "In1.Cu")
	)
	(gr_arc
		(start 207.649572 -74.8792)
		(mid 207.613651 -74.894079)
		(end 207.598772 -74.93)
		(stroke
			(width 0.2)
			(type default)
		)
		(layer "In1.Cu")
	)
	(gr_line
		(start 207.649572 -74.6252)
		(end 208.462372 -74.6252)
		(stroke
			(width 0.2)
			(type default)
		)
		(layer "In1.Cu")
	)
	(gr_arc
		(start 207.649572 -74.3204)
		(mid 207.613651 -74.335279)
		(end 207.598772 -74.3712)
		(stroke
			(width 0.2)
			(type default)
		)
		(layer "In1.Cu")
	)
	(gr_line
		(start 207.649572 -73.5076)
		(end 208.462372 -73.5076)
		(stroke
			(width 0.2)
			(type default)
		)
		(layer "In1.Cu")
	)
	(gr_arc
		(start 207.649572 -73.2028)
		(mid 207.613651 -73.217679)
		(end 207.598772 -73.2536)
		(stroke
			(width 0.2)
			(type default)
		)
		(layer "In1.Cu")
	)
	(gr_line
		(start 207.649572 -72.9488)
		(end 208.462372 -72.9488)
		(stroke
			(width 0.2)
			(type default)
		)
		(layer "In1.Cu")
	)
	(gr_arc
		(start 207.649572 -72.644)
		(mid 207.613651 -72.658879)
		(end 207.598772 -72.6948)
		(stroke
			(width 0.2)
			(type default)
		)
		(layer "In1.Cu")
	)
	(gr_line
		(start 207.649572 -71.8312)
		(end 208.462372 -71.8312)
		(stroke
			(width 0.2)
			(type default)
		)
		(layer "In1.Cu")
	)
	(gr_arc
		(start 207.649572 -71.5264)
		(mid 207.613651 -71.541279)
		(end 207.598772 -71.5772)
		(stroke
			(width 0.2)
			(type default)
		)
		(layer "In1.Cu")
	)
	(gr_line
		(start 207.649572 -71.2724)
		(end 208.462372 -71.2724)
		(stroke
			(width 0.2)
			(type default)
		)
		(layer "In1.Cu")
	)
	(gr_arc
		(start 207.649572 -70.9676)
		(mid 207.613651 -70.982479)
		(end 207.598772 -71.0184)
		(stroke
			(width 0.2)
			(type default)
		)
		(layer "In1.Cu")
	)
	(gr_line
		(start 207.649572 -70.1548)
		(end 208.462372 -70.1548)
		(stroke
			(width 0.2)
			(type default)
		)
		(layer "In1.Cu")
	)
	(gr_arc
		(start 207.649572 -69.85)
		(mid 207.613651 -69.864879)
		(end 207.598772 -69.9008)
		(stroke
			(width 0.2)
			(type default)
		)
		(layer "In1.Cu")
	)
	(gr_line
		(start 207.649572 -69.596)
		(end 208.462372 -69.596)
		(stroke
			(width 0.2)
			(type default)
		)
		(layer "In1.Cu")
	)
	(gr_arc
		(start 207.649572 -69.2912)
		(mid 207.613651 -69.306079)
		(end 207.598772 -69.342)
		(stroke
			(width 0.2)
			(type default)
		)
		(layer "In1.Cu")
	)
	(gr_line
		(start 207.649572 -68.4784)
		(end 208.462372 -68.4784)
		(stroke
			(width 0.2)
			(type default)
		)
		(layer "In1.Cu")
	)
	(gr_arc
		(start 207.649572 -68.1736)
		(mid 207.613651 -68.188479)
		(end 207.598772 -68.2244)
		(stroke
			(width 0.2)
			(type default)
		)
		(layer "In1.Cu")
	)
	(gr_line
		(start 207.649572 -67.9196)
		(end 208.462372 -67.9196)
		(stroke
			(width 0.2)
			(type default)
		)
		(layer "In1.Cu")
	)
	(gr_arc
		(start 207.649572 -67.6148)
		(mid 207.613651 -67.629679)
		(end 207.598772 -67.6656)
		(stroke
			(width 0.2)
			(type default)
		)
		(layer "In1.Cu")
	)
	(gr_line
		(start 207.649572 -66.802)
		(end 208.462372 -66.802)
		(stroke
			(width 0.2)
			(type default)
		)
		(layer "In1.Cu")
	)
	(gr_arc
		(start 207.649572 -66.4972)
		(mid 207.613651 -66.512079)
		(end 207.598772 -66.548)
		(stroke
			(width 0.2)
			(type default)
		)
		(layer "In1.Cu")
	)
	(gr_line
		(start 207.649572 -66.2432)
		(end 208.462372 -66.2432)
		(stroke
			(width 0.2)
			(type default)
		)
		(layer "In1.Cu")
	)
	(gr_arc
		(start 207.649572 -65.9384)
		(mid 207.613651 -65.953279)
		(end 207.598772 -65.9892)
		(stroke
			(width 0.2)
			(type default)
		)
		(layer "In1.Cu")
	)
	(gr_line
		(start 207.649572 -65.1256)
		(end 208.462372 -65.1256)
		(stroke
			(width 0.2)
			(type default)
		)
		(layer "In1.Cu")
	)
	(gr_arc
		(start 207.649572 -64.8208)
		(mid 207.613651 -64.835679)
		(end 207.598772 -64.8716)
		(stroke
			(width 0.2)
			(type default)
		)
		(layer "In1.Cu")
	)
	(gr_line
		(start 207.649572 -64.5668)
		(end 208.462372 -64.5668)
		(stroke
			(width 0.2)
			(type default)
		)
		(layer "In1.Cu")
	)
	(gr_arc
		(start 207.649572 -64.262)
		(mid 207.613651 -64.276879)
		(end 207.598772 -64.3128)
		(stroke
			(width 0.2)
			(type default)
		)
		(layer "In1.Cu")
	)
	(gr_arc
		(start 208.462372 -76.8604)
		(mid 208.498293 -76.845521)
		(end 208.513172 -76.8096)
		(stroke
			(width 0.2)
			(type default)
		)
		(layer "In1.Cu")
	)
	(gr_line
		(start 208.462372 -76.5556)
		(end 207.649572 -76.5556)
		(stroke
			(width 0.2)
			(type default)
		)
		(layer "In1.Cu")
	)
	(gr_arc
		(start 208.462372 -76.3016)
		(mid 208.498293 -76.286721)
		(end 208.513172 -76.2508)
		(stroke
			(width 0.2)
			(type default)
		)
		(layer "In1.Cu")
	)
	(gr_line
		(start 208.462372 -75.9968)
		(end 207.649572 -75.9968)
		(stroke
			(width 0.2)
			(type default)
		)
		(layer "In1.Cu")
	)
	(gr_arc
		(start 208.462372 -75.184)
		(mid 208.498293 -75.169121)
		(end 208.513172 -75.1332)
		(stroke
			(width 0.2)
			(type default)
		)
		(layer "In1.Cu")
	)
	(gr_line
		(start 208.462372 -74.8792)
		(end 207.649572 -74.8792)
		(stroke
			(width 0.2)
			(type default)
		)
		(layer "In1.Cu")
	)
	(gr_arc
		(start 208.462372 -74.6252)
		(mid 208.498293 -74.610321)
		(end 208.513172 -74.5744)
		(stroke
			(width 0.2)
			(type default)
		)
		(layer "In1.Cu")
	)
	(gr_line
		(start 208.462372 -74.3204)
		(end 207.649572 -74.3204)
		(stroke
			(width 0.2)
			(type default)
		)
		(layer "In1.Cu")
	)
	(gr_arc
		(start 208.462372 -73.5076)
		(mid 208.498293 -73.492721)
		(end 208.513172 -73.4568)
		(stroke
			(width 0.2)
			(type default)
		)
		(layer "In1.Cu")
	)
	(gr_line
		(start 208.462372 -73.2028)
		(end 207.649572 -73.2028)
		(stroke
			(width 0.2)
			(type default)
		)
		(layer "In1.Cu")
	)
	(gr_arc
		(start 208.462372 -72.9488)
		(mid 208.498293 -72.933921)
		(end 208.513172 -72.898)
		(stroke
			(width 0.2)
			(type default)
		)
		(layer "In1.Cu")
	)
	(gr_line
		(start 208.462372 -72.644)
		(end 207.649572 -72.644)
		(stroke
			(width 0.2)
			(type default)
		)
		(layer "In1.Cu")
	)
	(gr_arc
		(start 208.462372 -71.8312)
		(mid 208.498293 -71.816321)
		(end 208.513172 -71.7804)
		(stroke
			(width 0.2)
			(type default)
		)
		(layer "In1.Cu")
	)
	(gr_line
		(start 208.462372 -71.5264)
		(end 207.649572 -71.5264)
		(stroke
			(width 0.2)
			(type default)
		)
		(layer "In1.Cu")
	)
	(gr_arc
		(start 208.462372 -71.2724)
		(mid 208.498293 -71.257521)
		(end 208.513172 -71.2216)
		(stroke
			(width 0.2)
			(type default)
		)
		(layer "In1.Cu")
	)
	(gr_line
		(start 208.462372 -70.9676)
		(end 207.649572 -70.9676)
		(stroke
			(width 0.2)
			(type default)
		)
		(layer "In1.Cu")
	)
	(gr_arc
		(start 208.462372 -70.1548)
		(mid 208.498293 -70.139921)
		(end 208.513172 -70.104)
		(stroke
			(width 0.2)
			(type default)
		)
		(layer "In1.Cu")
	)
	(gr_line
		(start 208.462372 -69.85)
		(end 207.649572 -69.85)
		(stroke
			(width 0.2)
			(type default)
		)
		(layer "In1.Cu")
	)
	(gr_arc
		(start 208.462372 -69.596)
		(mid 208.498293 -69.581121)
		(end 208.513172 -69.5452)
		(stroke
			(width 0.2)
			(type default)
		)
		(layer "In1.Cu")
	)
	(gr_line
		(start 208.462372 -69.2912)
		(end 207.649572 -69.2912)
		(stroke
			(width 0.2)
			(type default)
		)
		(layer "In1.Cu")
	)
	(gr_arc
		(start 208.462372 -68.4784)
		(mid 208.498293 -68.463521)
		(end 208.513172 -68.4276)
		(stroke
			(width 0.2)
			(type default)
		)
		(layer "In1.Cu")
	)
	(gr_line
		(start 208.462372 -68.1736)
		(end 207.649572 -68.1736)
		(stroke
			(width 0.2)
			(type default)
		)
		(layer "In1.Cu")
	)
	(gr_arc
		(start 208.462372 -67.9196)
		(mid 208.498293 -67.904721)
		(end 208.513172 -67.8688)
		(stroke
			(width 0.2)
			(type default)
		)
		(layer "In1.Cu")
	)
	(gr_line
		(start 208.462372 -67.6148)
		(end 207.649572 -67.6148)
		(stroke
			(width 0.2)
			(type default)
		)
		(layer "In1.Cu")
	)
	(gr_arc
		(start 208.462372 -66.802)
		(mid 208.498293 -66.787121)
		(end 208.513172 -66.7512)
		(stroke
			(width 0.2)
			(type default)
		)
		(layer "In1.Cu")
	)
	(gr_line
		(start 208.462372 -66.4972)
		(end 207.649572 -66.4972)
		(stroke
			(width 0.2)
			(type default)
		)
		(layer "In1.Cu")
	)
	(gr_arc
		(start 208.462372 -66.2432)
		(mid 208.498293 -66.228321)
		(end 208.513172 -66.1924)
		(stroke
			(width 0.2)
			(type default)
		)
		(layer "In1.Cu")
	)
	(gr_line
		(start 208.462372 -65.9384)
		(end 207.649572 -65.9384)
		(stroke
			(width 0.2)
			(type default)
		)
		(layer "In1.Cu")
	)
	(gr_arc
		(start 208.462372 -65.1256)
		(mid 208.498293 -65.110721)
		(end 208.513172 -65.0748)
		(stroke
			(width 0.2)
			(type default)
		)
		(layer "In1.Cu")
	)
	(gr_line
		(start 208.462372 -64.8208)
		(end 207.649572 -64.8208)
		(stroke
			(width 0.2)
			(type default)
		)
		(layer "In1.Cu")
	)
	(gr_arc
		(start 208.462372 -64.5668)
		(mid 208.498293 -64.551921)
		(end 208.513172 -64.516)
		(stroke
			(width 0.2)
			(type default)
		)
		(layer "In1.Cu")
	)
	(gr_line
		(start 208.462372 -64.262)
		(end 207.649572 -64.262)
		(stroke
			(width 0.2)
			(type default)
		)
		(layer "In1.Cu")
	)
	(gr_line
		(start 208.513172 -76.8096)
		(end 208.513172 -76.6064)
		(stroke
			(width 0.2)
			(type default)
		)
		(layer "In1.Cu")
	)
	(gr_arc
		(start 208.513172 -76.6064)
		(mid 208.498293 -76.570479)
		(end 208.462372 -76.5556)
		(stroke
			(width 0.2)
			(type default)
		)
		(layer "In1.Cu")
	)
	(gr_line
		(start 208.513172 -76.2508)
		(end 208.513172 -76.0476)
		(stroke
			(width 0.2)
			(type default)
		)
		(layer "In1.Cu")
	)
	(gr_arc
		(start 208.513172 -76.0476)
		(mid 208.498293 -76.011679)
		(end 208.462372 -75.9968)
		(stroke
			(width 0.2)
			(type default)
		)
		(layer "In1.Cu")
	)
	(gr_line
		(start 208.513172 -75.1332)
		(end 208.513172 -74.93)
		(stroke
			(width 0.2)
			(type default)
		)
		(layer "In1.Cu")
	)
	(gr_arc
		(start 208.513172 -74.93)
		(mid 208.498293 -74.894079)
		(end 208.462372 -74.8792)
		(stroke
			(width 0.2)
			(type default)
		)
		(layer "In1.Cu")
	)
	(gr_line
		(start 208.513172 -74.5744)
		(end 208.513172 -74.3712)
		(stroke
			(width 0.2)
			(type default)
		)
		(layer "In1.Cu")
	)
	(gr_arc
		(start 208.513172 -74.3712)
		(mid 208.498293 -74.335279)
		(end 208.462372 -74.3204)
		(stroke
			(width 0.2)
			(type default)
		)
		(layer "In1.Cu")
	)
	(gr_line
		(start 208.513172 -73.4568)
		(end 208.513172 -73.2536)
		(stroke
			(width 0.2)
			(type default)
		)
		(layer "In1.Cu")
	)
	(gr_arc
		(start 208.513172 -73.2536)
		(mid 208.498293 -73.217679)
		(end 208.462372 -73.2028)
		(stroke
			(width 0.2)
			(type default)
		)
		(layer "In1.Cu")
	)
	(gr_line
		(start 208.513172 -72.898)
		(end 208.513172 -72.6948)
		(stroke
			(width 0.2)
			(type default)
		)
		(layer "In1.Cu")
	)
	(gr_arc
		(start 208.513172 -72.6948)
		(mid 208.498293 -72.658879)
		(end 208.462372 -72.644)
		(stroke
			(width 0.2)
			(type default)
		)
		(layer "In1.Cu")
	)
	(gr_line
		(start 208.513172 -71.7804)
		(end 208.513172 -71.5772)
		(stroke
			(width 0.2)
			(type default)
		)
		(layer "In1.Cu")
	)
	(gr_arc
		(start 208.513172 -71.5772)
		(mid 208.498293 -71.541279)
		(end 208.462372 -71.5264)
		(stroke
			(width 0.2)
			(type default)
		)
		(layer "In1.Cu")
	)
	(gr_line
		(start 208.513172 -71.2216)
		(end 208.513172 -71.0184)
		(stroke
			(width 0.2)
			(type default)
		)
		(layer "In1.Cu")
	)
	(gr_arc
		(start 208.513172 -71.0184)
		(mid 208.498293 -70.982479)
		(end 208.462372 -70.9676)
		(stroke
			(width 0.2)
			(type default)
		)
		(layer "In1.Cu")
	)
	(gr_line
		(start 208.513172 -70.104)
		(end 208.513172 -69.9008)
		(stroke
			(width 0.2)
			(type default)
		)
		(layer "In1.Cu")
	)
	(gr_arc
		(start 208.513172 -69.9008)
		(mid 208.498293 -69.864879)
		(end 208.462372 -69.85)
		(stroke
			(width 0.2)
			(type default)
		)
		(layer "In1.Cu")
	)
	(gr_line
		(start 208.513172 -69.5452)
		(end 208.513172 -69.342)
		(stroke
			(width 0.2)
			(type default)
		)
		(layer "In1.Cu")
	)
	(gr_arc
		(start 208.513172 -69.342)
		(mid 208.498293 -69.306079)
		(end 208.462372 -69.2912)
		(stroke
			(width 0.2)
			(type default)
		)
		(layer "In1.Cu")
	)
	(gr_line
		(start 208.513172 -68.4276)
		(end 208.513172 -68.2244)
		(stroke
			(width 0.2)
			(type default)
		)
		(layer "In1.Cu")
	)
	(gr_arc
		(start 208.513172 -68.2244)
		(mid 208.498293 -68.188479)
		(end 208.462372 -68.1736)
		(stroke
			(width 0.2)
			(type default)
		)
		(layer "In1.Cu")
	)
	(gr_line
		(start 208.513172 -67.8688)
		(end 208.513172 -67.6656)
		(stroke
			(width 0.2)
			(type default)
		)
		(layer "In1.Cu")
	)
	(gr_arc
		(start 208.513172 -67.6656)
		(mid 208.498293 -67.629679)
		(end 208.462372 -67.6148)
		(stroke
			(width 0.2)
			(type default)
		)
		(layer "In1.Cu")
	)
	(gr_line
		(start 208.513172 -66.7512)
		(end 208.513172 -66.548)
		(stroke
			(width 0.2)
			(type default)
		)
		(layer "In1.Cu")
	)
	(gr_arc
		(start 208.513172 -66.548)
		(mid 208.498293 -66.512079)
		(end 208.462372 -66.4972)
		(stroke
			(width 0.2)
			(type default)
		)
		(layer "In1.Cu")
	)
	(gr_line
		(start 208.513172 -66.1924)
		(end 208.513172 -65.9892)
		(stroke
			(width 0.2)
			(type default)
		)
		(layer "In1.Cu")
	)
	(gr_arc
		(start 208.513172 -65.9892)
		(mid 208.498293 -65.953279)
		(end 208.462372 -65.9384)
		(stroke
			(width 0.2)
			(type default)
		)
		(layer "In1.Cu")
	)
	(gr_line
		(start 208.513172 -65.0748)
		(end 208.513172 -64.8716)
		(stroke
			(width 0.2)
			(type default)
		)
		(layer "In1.Cu")
	)
	(gr_arc
		(start 208.513172 -64.8716)
		(mid 208.498293 -64.835679)
		(end 208.462372 -64.8208)
		(stroke
			(width 0.2)
			(type default)
		)
		(layer "In1.Cu")
	)
	(gr_line
		(start 208.513172 -64.516)
		(end 208.513172 -64.3128)
		(stroke
			(width 0.2)
			(type default)
		)
		(layer "In1.Cu")
	)
	(gr_arc
		(start 208.513172 -64.3128)
		(mid 208.498293 -64.276879)
		(end 208.462372 -64.262)
		(stroke
			(width 0.2)
			(type default)
		)
		(layer "In1.Cu")
	)
	(gr_line
		(start 210.790536 -63.655194)
		(end 210.79079 -63.655448)
		(stroke
			(width 0.2)
			(type default)
		)
		(layer "In1.Cu")
	)
	(gr_arc
		(start 210.79079 -63.655448)
		(mid 210.79079 -64.193928)
		(end 211.32927 -64.193928)
		(stroke
			(width 0.2)
			(type default)
		)
		(layer "In1.Cu")
	)
	(gr_line
		(start 210.959192 -66.09842)
		(end 210.959446 -66.098674)
		(stroke
			(width 0.2)
			(type default)
		)
		(layer "In1.Cu")
	)
	(gr_arc
		(start 210.959446 -66.098674)
		(mid 210.959446 -66.637154)
		(end 211.497926 -66.637154)
		(stroke
			(width 0.2)
			(type default)
		)
		(layer "In1.Cu")
	)
	(gr_line
		(start 211.32927 -64.193928)
		(end 211.329524 -64.194182)
		(stroke
			(width 0.2)
			(type default)
		)
		(layer "In1.Cu")
	)
	(gr_line
		(start 211.329524 -64.194182)
		(end 212.137498 -63.385954)
		(stroke
			(width 0.2)
			(type default)
		)
		(layer "In1.Cu")
	)
	(gr_line
		(start 211.497926 -66.637154)
		(end 211.49818 -66.637408)
		(stroke
			(width 0.2)
			(type default)
		)
		(layer "In1.Cu")
	)
	(gr_line
		(start 211.49818 -66.637408)
		(end 212.306154 -65.82918)
		(stroke
			(width 0.2)
			(type default)
		)
		(layer "In1.Cu")
	)
	(gr_line
		(start 211.598764 -62.846966)
		(end 210.790536 -63.655194)
		(stroke
			(width 0.2)
			(type default)
		)
		(layer "In1.Cu")
	)
	(gr_line
		(start 211.599018 -62.84722)
		(end 211.598764 -62.846966)
		(stroke
			(width 0.2)
			(type default)
		)
		(layer "In1.Cu")
	)
	(gr_line
		(start 211.76742 -65.290192)
		(end 210.959192 -66.09842)
		(stroke
			(width 0.2)
			(type default)
		)
		(layer "In1.Cu")
	)
	(gr_line
		(start 211.767674 -65.290446)
		(end 211.76742 -65.290192)
		(stroke
			(width 0.2)
			(type default)
		)
		(layer "In1.Cu")
	)
	(gr_line
		(start 212.137498 -63.385954)
		(end 212.137498 -63.3857)
		(stroke
			(width 0.2)
			(type default)
		)
		(layer "In1.Cu")
	)
	(gr_arc
		(start 212.137498 -63.3857)
		(mid 212.137498 -62.84722)
		(end 211.599018 -62.84722)
		(stroke
			(width 0.2)
			(type default)
		)
		(layer "In1.Cu")
	)
	(gr_line
		(start 212.306154 -65.82918)
		(end 212.306154 -65.828926)
		(stroke
			(width 0.2)
			(type default)
		)
		(layer "In1.Cu")
	)
	(gr_arc
		(start 212.306154 -65.828926)
		(mid 212.306154 -65.290446)
		(end 211.767674 -65.290446)
		(stroke
			(width 0.2)
			(type default)
		)
		(layer "In1.Cu")
	)
	(gr_line
		(start 212.432392 -67.74942)
		(end 212.432646 -67.749674)
		(stroke
			(width 0.2)
			(type default)
		)
		(layer "In1.Cu")
	)
	(gr_arc
		(start 212.432646 -67.749674)
		(mid 212.432646 -68.288154)
		(end 212.971126 -68.288154)
		(stroke
			(width 0.2)
			(type default)
		)
		(layer "In1.Cu")
	)
	(gr_line
		(start 212.971126 -68.288154)
		(end 212.97138 -68.288408)
		(stroke
			(width 0.2)
			(type default)
		)
		(layer "In1.Cu")
	)
	(gr_line
		(start 212.97138 -68.288408)
		(end 213.779354 -67.48018)
		(stroke
			(width 0.2)
			(type default)
		)
		(layer "In1.Cu")
	)
	(gr_line
		(start 213.24062 -66.941192)
		(end 212.432392 -67.74942)
		(stroke
			(width 0.2)
			(type default)
		)
		(layer "In1.Cu")
	)
	(gr_line
		(start 213.240874 -66.941446)
		(end 213.24062 -66.941192)
		(stroke
			(width 0.2)
			(type default)
		)
		(layer "In1.Cu")
	)
	(gr_line
		(start 213.448392 -72.52462)
		(end 213.448646 -72.524874)
		(stroke
			(width 0.2)
			(type default)
		)
		(layer "In1.Cu")
	)
	(gr_arc
		(start 213.448646 -72.524874)
		(mid 213.448646 -73.063354)
		(end 213.987126 -73.063354)
		(stroke
			(width 0.2)
			(type default)
		)
		(layer "In1.Cu")
	)
	(gr_line
		(start 213.779354 -67.48018)
		(end 213.779354 -67.479926)
		(stroke
			(width 0.2)
			(type default)
		)
		(layer "In1.Cu")
	)
	(gr_arc
		(start 213.779354 -67.479926)
		(mid 213.779354 -66.941446)
		(end 213.240874 -66.941446)
		(stroke
			(width 0.2)
			(type default)
		)
		(layer "In1.Cu")
	)
	(gr_line
		(start 213.956392 -69.22262)
		(end 213.956646 -69.222874)
		(stroke
			(width 0.2)
			(type default)
		)
		(layer "In1.Cu")
	)
	(gr_arc
		(start 213.956646 -69.222874)
		(mid 213.956646 -69.761354)
		(end 214.495126 -69.761354)
		(stroke
			(width 0.2)
			(type default)
		)
		(layer "In1.Cu")
	)
	(gr_line
		(start 213.987126 -73.063354)
		(end 213.98738 -73.063608)
		(stroke
			(width 0.2)
			(type default)
		)
		(layer "In1.Cu")
	)
	(gr_line
		(start 213.98738 -73.063608)
		(end 214.795354 -72.25538)
		(stroke
			(width 0.2)
			(type default)
		)
		(layer "In1.Cu")
	)
	(gr_line
		(start 214.25662 -71.716392)
		(end 213.448392 -72.52462)
		(stroke
			(width 0.2)
			(type default)
		)
		(layer "In1.Cu")
	)
	(gr_line
		(start 214.256874 -71.716646)
		(end 214.25662 -71.716392)
		(stroke
			(width 0.2)
			(type default)
		)
		(layer "In1.Cu")
	)
	(gr_line
		(start 214.495126 -69.761354)
		(end 214.49538 -69.761608)
		(stroke
			(width 0.2)
			(type default)
		)
		(layer "In1.Cu")
	)
	(gr_line
		(start 214.49538 -69.761608)
		(end 215.303354 -68.95338)
		(stroke
			(width 0.2)
			(type default)
		)
		(layer "In1.Cu")
	)
	(gr_line
		(start 214.76462 -68.414392)
		(end 213.956392 -69.22262)
		(stroke
			(width 0.2)
			(type default)
		)
		(layer "In1.Cu")
	)
	(gr_line
		(start 214.764874 -68.414646)
		(end 214.76462 -68.414392)
		(stroke
			(width 0.2)
			(type default)
		)
		(layer "In1.Cu")
	)
	(gr_line
		(start 214.795354 -72.25538)
		(end 214.795354 -72.255126)
		(stroke
			(width 0.2)
			(type default)
		)
		(layer "In1.Cu")
	)
	(gr_arc
		(start 214.795354 -72.255126)
		(mid 214.795354 -71.716646)
		(end 214.256874 -71.716646)
		(stroke
			(width 0.2)
			(type default)
		)
		(layer "In1.Cu")
	)
	(gr_line
		(start 214.845392 -73.92162)
		(end 214.845646 -73.921874)
		(stroke
			(width 0.2)
			(type default)
		)
		(layer "In1.Cu")
	)
	(gr_arc
		(start 214.845646 -73.921874)
		(mid 214.845646 -74.460354)
		(end 215.384126 -74.460354)
		(stroke
			(width 0.2)
			(type default)
		)
		(layer "In1.Cu")
	)
	(gr_line
		(start 215.226392 -79.38262)
		(end 215.226646 -79.382874)
		(stroke
			(width 0.2)
			(type default)
		)
		(layer "In1.Cu")
	)
	(gr_arc
		(start 215.226646 -79.382874)
		(mid 215.226646 -79.921354)
		(end 215.765126 -79.921354)
		(stroke
			(width 0.2)
			(type default)
		)
		(layer "In1.Cu")
	)
	(gr_line
		(start 215.303354 -68.95338)
		(end 215.303354 -68.953126)
		(stroke
			(width 0.2)
			(type default)
		)
		(layer "In1.Cu")
	)
	(gr_arc
		(start 215.303354 -68.953126)
		(mid 215.303354 -68.414646)
		(end 214.764874 -68.414646)
		(stroke
			(width 0.2)
			(type default)
		)
		(layer "In1.Cu")
	)
	(gr_line
		(start 215.384126 -74.460354)
		(end 215.38438 -74.460608)
		(stroke
			(width 0.2)
			(type default)
		)
		(layer "In1.Cu")
	)
	(gr_line
		(start 215.38438 -74.460608)
		(end 216.192354 -73.65238)
		(stroke
			(width 0.2)
			(type default)
		)
		(layer "In1.Cu")
	)
	(gr_line
		(start 215.65362 -73.113392)
		(end 214.845392 -73.92162)
		(stroke
			(width 0.2)
			(type default)
		)
		(layer "In1.Cu")
	)
	(gr_line
		(start 215.653874 -73.113646)
		(end 215.65362 -73.113392)
		(stroke
			(width 0.2)
			(type default)
		)
		(layer "In1.Cu")
	)
	(gr_line
		(start 215.765126 -79.921354)
		(end 215.76538 -79.921608)
		(stroke
			(width 0.2)
			(type default)
		)
		(layer "In1.Cu")
	)
	(gr_line
		(start 215.76538 -79.921608)
		(end 216.573354 -79.11338)
		(stroke
			(width 0.2)
			(type default)
		)
		(layer "In1.Cu")
	)
	(gr_line
		(start 216.03462 -78.574392)
		(end 215.226392 -79.38262)
		(stroke
			(width 0.2)
			(type default)
		)
		(layer "In1.Cu")
	)
	(gr_line
		(start 216.034874 -78.574646)
		(end 216.03462 -78.574392)
		(stroke
			(width 0.2)
			(type default)
		)
		(layer "In1.Cu")
	)
	(gr_line
		(start 216.192354 -73.65238)
		(end 216.192354 -73.652126)
		(stroke
			(width 0.2)
			(type default)
		)
		(layer "In1.Cu")
	)
	(gr_arc
		(start 216.192354 -73.652126)
		(mid 216.192354 -73.113646)
		(end 215.653874 -73.113646)
		(stroke
			(width 0.2)
			(type default)
		)
		(layer "In1.Cu")
	)
	(gr_line
		(start 216.369392 -75.44562)
		(end 216.369646 -75.445874)
		(stroke
			(width 0.2)
			(type default)
		)
		(layer "In1.Cu")
	)
	(gr_arc
		(start 216.369646 -75.445874)
		(mid 216.369646 -75.984354)
		(end 216.908126 -75.984354)
		(stroke
			(width 0.2)
			(type default)
		)
		(layer "In1.Cu")
	)
	(gr_line
		(start 216.573354 -79.11338)
		(end 216.573354 -79.113126)
		(stroke
			(width 0.2)
			(type default)
		)
		(layer "In1.Cu")
	)
	(gr_arc
		(start 216.573354 -79.113126)
		(mid 216.573354 -78.574646)
		(end 216.034874 -78.574646)
		(stroke
			(width 0.2)
			(type default)
		)
		(layer "In1.Cu")
	)
	(gr_line
		(start 216.908126 -75.984354)
		(end 216.90838 -75.984608)
		(stroke
			(width 0.2)
			(type default)
		)
		(layer "In1.Cu")
	)
	(gr_line
		(start 216.90838 -75.984608)
		(end 217.716354 -75.17638)
		(stroke
			(width 0.2)
			(type default)
		)
		(layer "In1.Cu")
	)
	(gr_line
		(start 217.17762 -74.637392)
		(end 216.369392 -75.44562)
		(stroke
			(width 0.2)
			(type default)
		)
		(layer "In1.Cu")
	)
	(gr_line
		(start 217.177874 -74.637646)
		(end 217.17762 -74.637392)
		(stroke
			(width 0.2)
			(type default)
		)
		(layer "In1.Cu")
	)
	(gr_line
		(start 217.716354 -75.17638)
		(end 217.716354 -75.176126)
		(stroke
			(width 0.2)
			(type default)
		)
		(layer "In1.Cu")
	)
	(gr_arc
		(start 217.716354 -75.176126)
		(mid 217.716354 -74.637646)
		(end 217.177874 -74.637646)
		(stroke
			(width 0.2)
			(type default)
		)
		(layer "In1.Cu")
	)
	(gr_line
		(start 229.382066 -194.00012)
		(end 149.917912 -194.00012)
		(stroke
			(width 1.524)
			(type default)
		)
		(layer "In1.Cu")
	)
	(gr_arc
		(start 229.382066 -194.00012)
		(mid 229.907793 -193.850701)
		(end 230.2764 -193.447162)
		(stroke
			(width 1.524)
			(type default)
		)
		(layer "In1.Cu")
	)
	(gr_line
		(start 234.894374 -184.211214)
		(end 230.2764 -193.447162)
		(stroke
			(width 1.524)
			(type default)
		)
		(layer "In1.Cu")
	)
	(gr_arc
		(start 234.894374 -184.211214)
		(mid 234.97328 -183.993726)
		(end 235.000038 -183.76392)
		(stroke
			(width 1.524)
			(type default)
		)
		(layer "In1.Cu")
	)
	(gr_arc
		(start 235.000038 -0.999998)
		(mid 234.707147 -0.29288)
		(end 234.00004 0)
		(stroke
			(width 1.524)
			(type default)
		)
		(layer "In1.Cu")
	)
	(gr_line
		(start 235.000038 -0.999998)
		(end 235.000038 -183.76392)
		(stroke
			(width 1.524)
			(type default)
		)
		(layer "In1.Cu")
	)
	(gr_arc
		(start 18.174716 -144.500092)
		(mid 18.13829 -144.316857)
		(end 18.034508 -144.16151)
		(stroke
			(width 0.0508)
			(type default)
		)
		(layer "In2.Cu")
	)
	(gr_arc
		(start 18.734532 -144.16151)
		(mid 18.554197 -144.236193)
		(end 18.479516 -144.416526)
		(stroke
			(width 0.0508)
			(type default)
		)
		(layer "In2.Cu")
	)
	(gr_line
		(start 18.734532 -144.16151)
		(end 18.834608 -144.16151)
		(stroke
			(width 0.0508)
			(type default)
		)
		(layer "In2.Cu")
	)
	(gr_line
		(start 19.414998 -145.711672)
		(end 19.414998 -145.711926)
		(stroke
			(width 0.0508)
			(type default)
		)
		(layer "In2.Cu")
	)
	(gr_arc
		(start 21.117814 -144.823434)
		(mid 21.229941 -144.796865)
		(end 21.318474 -144.723104)
		(stroke
			(width 0.0508)
			(type default)
		)
		(layer "In2.Cu")
	)
	(gr_line
		(start 21.425154 -145.128234)
		(end 21.917914 -145.128234)
		(stroke
			(width 0.0508)
			(type default)
		)
		(layer "In2.Cu")
	)
	(gr_arc
		(start 21.519134 -144.622774)
		(mid 21.406977 -144.649298)
		(end 21.318474 -144.723104)
		(stroke
			(width 0.0508)
			(type default)
		)
		(layer "In2.Cu")
	)
	(gr_line
		(start 21.519134 -144.622774)
		(end 21.823934 -144.622774)
		(stroke
			(width 0.0508)
			(type default)
		)
		(layer "In2.Cu")
	)
	(gr_arc
		(start 22.024594 -144.723104)
		(mid 21.936068 -144.649344)
		(end 21.823934 -144.622774)
		(stroke
			(width 0.0508)
			(type default)
		)
		(layer "In2.Cu")
	)
	(gr_arc
		(start 22.024594 -144.723104)
		(mid 22.113107 -144.79689)
		(end 22.225254 -144.823434)
		(stroke
			(width 0.0508)
			(type default)
		)
		(layer "In2.Cu")
	)
	(gr_line
		(start 22.0345 -148.961602)
		(end 22.22246 -148.773642)
		(stroke
			(width 0.0508)
			(type default)
		)
		(layer "In2.Cu")
	)
	(gr_line
		(start 22.0345 -148.161502)
		(end 22.095968 -148.222716)
		(stroke
			(width 0.0508)
			(type default)
		)
		(layer "In2.Cu")
	)
	(gr_line
		(start 22.0345 -141.76121)
		(end 22.253194 -141.542516)
		(stroke
			(width 0.0508)
			(type default)
		)
		(layer "In2.Cu")
	)
	(gr_line
		(start 22.0345 -140.96111)
		(end 22.217126 -141.143736)
		(stroke
			(width 0.0508)
			(type default)
		)
		(layer "In2.Cu")
	)
	(gr_arc
		(start 22.095968 -148.222716)
		(mid 22.261209 -148.333186)
		(end 22.45614 -148.372068)
		(stroke
			(width 0.0508)
			(type default)
		)
		(layer "In2.Cu")
	)
	(gr_arc
		(start 22.45614 -148.676868)
		(mid 22.329679 -148.702016)
		(end 22.22246 -148.773642)
		(stroke
			(width 0.0508)
			(type default)
		)
		(layer "In2.Cu")
	)
	(gr_arc
		(start 22.530054 -144.823434)
		(mid 22.64217 -144.796851)
		(end 22.730714 -144.723104)
		(stroke
			(width 0.0508)
			(type default)
		)
		(layer "In2.Cu")
	)
	(gr_line
		(start 22.837394 -145.128234)
		(end 23.330154 -145.128234)
		(stroke
			(width 0.0508)
			(type default)
		)
		(layer "In2.Cu")
	)
	(gr_arc
		(start 22.931374 -144.622774)
		(mid 22.819217 -144.649298)
		(end 22.730714 -144.723104)
		(stroke
			(width 0.0508)
			(type default)
		)
		(layer "In2.Cu")
	)
	(gr_line
		(start 22.931374 -144.622774)
		(end 23.236174 -144.622774)
		(stroke
			(width 0.0508)
			(type default)
		)
		(layer "In2.Cu")
	)
	(gr_arc
		(start 23.436834 -144.723104)
		(mid 23.348308 -144.649344)
		(end 23.236174 -144.622774)
		(stroke
			(width 0.0508)
			(type default)
		)
		(layer "In2.Cu")
	)
	(gr_arc
		(start 23.436834 -144.723104)
		(mid 23.525343 -144.796911)
		(end 23.637494 -144.823434)
		(stroke
			(width 0.0508)
			(type default)
		)
		(layer "In2.Cu")
	)
	(gr_line
		(start 25.769316 -150.793958)
		(end 25.76957 -150.794212)
		(stroke
			(width 0.0508)
			(type default)
		)
		(layer "In2.Cu")
	)
	(gr_arc
		(start 25.769316 -150.793958)
		(mid 25.785413 -150.758016)
		(end 25.796748 -150.720298)
		(stroke
			(width 0.0508)
			(type default)
		)
		(layer "In2.Cu")
	)
	(gr_line
		(start 26.51506 -150.6093)
		(end 26.515314 -150.6093)
		(stroke
			(width 0.0508)
			(type default)
		)
		(layer "In2.Cu")
	)
	(gr_arc
		(start 27.862784 -150.67661)
		(mid 27.872741 -150.656732)
		(end 27.881326 -150.636224)
		(stroke
			(width 0.0508)
			(type default)
		)
		(layer "In2.Cu")
	)
	(gr_line
		(start 28.607512 -150.682198)
		(end 28.607766 -150.682198)
		(stroke
			(width 0.0508)
			(type default)
		)
		(layer "In2.Cu")
	)
	(gr_arc
		(start 32.092138 -144.667224)
		(mid 32.348973 -144.560839)
		(end 32.455358 -144.304004)
		(stroke
			(width 0.0508)
			(type default)
		)
		(layer "In2.Cu")
	)
	(gr_arc
		(start 32.760158 -144.273524)
		(mid 32.881429 -144.566273)
		(end 33.174178 -144.687544)
		(stroke
			(width 0.0508)
			(type default)
		)
		(layer "In2.Cu")
	)
	(gr_arc
		(start 36.44138 -149.456902)
		(mid 36.679463 -149.366917)
		(end 36.798504 -149.141942)
		(stroke
			(width 0.0508)
			(type default)
		)
		(layer "In2.Cu")
	)
	(gr_arc
		(start 36.798504 -150.076916)
		(mid 36.679392 -149.851755)
		(end 36.441126 -149.761702)
		(stroke
			(width 0.0508)
			(type default)
		)
		(layer "In2.Cu")
	)
	(gr_arc
		(start 37.221668 -146.559524)
		(mid 37.513144 -146.466179)
		(end 37.695886 -146.220688)
		(stroke
			(width 0.0508)
			(type default)
		)
		(layer "In2.Cu")
	)
	(gr_arc
		(start 37.695886 -147.155662)
		(mid 37.499952 -146.942973)
		(end 37.221668 -146.864324)
		(stroke
			(width 0.0508)
			(type default)
		)
		(layer "In2.Cu")
	)
	(gr_line
		(start 86.3854 -160.379918)
		(end 86.619588 -160.14573)
		(stroke
			(width 0.06985)
			(type default)
		)
		(layer "In2.Cu")
	)
	(gr_line
		(start 87.09025 -160.14573)
		(end 87.324438 -160.379918)
		(stroke
			(width 0.06985)
			(type default)
		)
		(layer "In2.Cu")
	)
	(gr_line
		(start 87.58555 -154.371294)
		(end 87.58555 -154.480514)
		(stroke
			(width 0.06985)
			(type default)
		)
		(layer "In2.Cu")
	)
	(gr_line
		(start 87.58555 -153.177494)
		(end 87.58555 -153.286714)
		(stroke
			(width 0.06985)
			(type default)
		)
		(layer "In2.Cu")
	)
	(gr_line
		(start 87.58555 -151.983694)
		(end 87.58555 -152.092914)
		(stroke
			(width 0.06985)
			(type default)
		)
		(layer "In2.Cu")
	)
	(gr_line
		(start 87.91829 -154.810714)
		(end 88.09355 -154.635454)
		(stroke
			(width 0.06985)
			(type default)
		)
		(layer "In2.Cu")
	)
	(gr_line
		(start 87.91829 -154.041094)
		(end 88.09355 -154.216354)
		(stroke
			(width 0.06985)
			(type default)
		)
		(layer "In2.Cu")
	)
	(gr_line
		(start 87.91829 -153.616914)
		(end 88.09355 -153.441654)
		(stroke
			(width 0.06985)
			(type default)
		)
		(layer "In2.Cu")
	)
	(gr_line
		(start 87.91829 -152.847294)
		(end 88.09355 -153.022554)
		(stroke
			(width 0.06985)
			(type default)
		)
		(layer "In2.Cu")
	)
	(gr_line
		(start 87.91829 -152.423114)
		(end 88.09355 -152.247854)
		(stroke
			(width 0.06985)
			(type default)
		)
		(layer "In2.Cu")
	)
	(gr_line
		(start 87.91829 -151.653494)
		(end 88.09355 -151.828754)
		(stroke
			(width 0.06985)
			(type default)
		)
		(layer "In2.Cu")
	)
	(gr_line
		(start 88.09355 -154.216354)
		(end 88.09355 -154.635454)
		(stroke
			(width 0.06985)
			(type default)
		)
		(layer "In2.Cu")
	)
	(gr_line
		(start 88.09355 -153.022554)
		(end 88.09355 -153.441654)
		(stroke
			(width 0.06985)
			(type default)
		)
		(layer "In2.Cu")
	)
	(gr_line
		(start 88.09355 -151.828754)
		(end 88.09355 -152.247854)
		(stroke
			(width 0.06985)
			(type default)
		)
		(layer "In2.Cu")
	)
	(gr_line
		(start 89.123012 -56.284114)
		(end 89.123012 -56.393334)
		(stroke
			(width 0.06985)
			(type default)
		)
		(layer "In2.Cu")
	)
	(gr_line
		(start 89.123012 -55.090314)
		(end 89.123012 -55.199534)
		(stroke
			(width 0.06985)
			(type default)
		)
		(layer "In2.Cu")
	)
	(gr_line
		(start 89.123012 -53.896514)
		(end 89.123012 -54.005734)
		(stroke
			(width 0.06985)
			(type default)
		)
		(layer "In2.Cu")
	)
	(gr_line
		(start 89.455752 -56.723534)
		(end 89.631012 -56.548274)
		(stroke
			(width 0.06985)
			(type default)
		)
		(layer "In2.Cu")
	)
	(gr_line
		(start 89.455752 -55.953914)
		(end 89.631012 -56.129174)
		(stroke
			(width 0.06985)
			(type default)
		)
		(layer "In2.Cu")
	)
	(gr_line
		(start 89.455752 -55.529734)
		(end 89.631012 -55.354474)
		(stroke
			(width 0.06985)
			(type default)
		)
		(layer "In2.Cu")
	)
	(gr_line
		(start 89.455752 -54.760114)
		(end 89.631012 -54.935374)
		(stroke
			(width 0.06985)
			(type default)
		)
		(layer "In2.Cu")
	)
	(gr_line
		(start 89.455752 -54.335934)
		(end 89.631012 -54.160674)
		(stroke
			(width 0.06985)
			(type default)
		)
		(layer "In2.Cu")
	)
	(gr_line
		(start 89.455752 -53.566314)
		(end 89.631012 -53.741574)
		(stroke
			(width 0.06985)
			(type default)
		)
		(layer "In2.Cu")
	)
	(gr_line
		(start 89.631012 -56.129174)
		(end 89.631012 -56.548274)
		(stroke
			(width 0.06985)
			(type default)
		)
		(layer "In2.Cu")
	)
	(gr_line
		(start 89.631012 -54.935374)
		(end 89.631012 -55.354474)
		(stroke
			(width 0.06985)
			(type default)
		)
		(layer "In2.Cu")
	)
	(gr_line
		(start 89.631012 -53.741574)
		(end 89.631012 -54.160674)
		(stroke
			(width 0.06985)
			(type default)
		)
		(layer "In2.Cu")
	)
	(gr_line
		(start 90.65768 -41.31818)
		(end 90.65768 -41.4274)
		(stroke
			(width 0.06985)
			(type default)
		)
		(layer "In2.Cu")
	)
	(gr_line
		(start 90.65768 -40.12438)
		(end 90.65768 -40.2336)
		(stroke
			(width 0.06985)
			(type default)
		)
		(layer "In2.Cu")
	)
	(gr_line
		(start 90.65768 -38.93058)
		(end 90.65768 -39.0398)
		(stroke
			(width 0.06985)
			(type default)
		)
		(layer "In2.Cu")
	)
	(gr_line
		(start 90.65768 -37.73678)
		(end 90.65768 -37.846)
		(stroke
			(width 0.06985)
			(type default)
		)
		(layer "In2.Cu")
	)
	(gr_line
		(start 90.99042 -41.7576)
		(end 91.16568 -41.58234)
		(stroke
			(width 0.06985)
			(type default)
		)
		(layer "In2.Cu")
	)
	(gr_line
		(start 90.99042 -40.98798)
		(end 91.16568 -41.16324)
		(stroke
			(width 0.06985)
			(type default)
		)
		(layer "In2.Cu")
	)
	(gr_line
		(start 90.99042 -40.5638)
		(end 91.16568 -40.38854)
		(stroke
			(width 0.06985)
			(type default)
		)
		(layer "In2.Cu")
	)
	(gr_line
		(start 90.99042 -39.79418)
		(end 91.16568 -39.96944)
		(stroke
			(width 0.06985)
			(type default)
		)
		(layer "In2.Cu")
	)
	(gr_line
		(start 90.99042 -39.37)
		(end 91.16568 -39.19474)
		(stroke
			(width 0.06985)
			(type default)
		)
		(layer "In2.Cu")
	)
	(gr_line
		(start 90.99042 -38.60038)
		(end 91.16568 -38.77564)
		(stroke
			(width 0.06985)
			(type default)
		)
		(layer "In2.Cu")
	)
	(gr_line
		(start 90.99042 -38.1762)
		(end 91.16568 -38.00094)
		(stroke
			(width 0.06985)
			(type default)
		)
		(layer "In2.Cu")
	)
	(gr_line
		(start 90.99042 -37.40658)
		(end 91.16568 -37.58184)
		(stroke
			(width 0.06985)
			(type default)
		)
		(layer "In2.Cu")
	)
	(gr_line
		(start 91.16568 -41.16324)
		(end 91.16568 -41.58234)
		(stroke
			(width 0.06985)
			(type default)
		)
		(layer "In2.Cu")
	)
	(gr_line
		(start 91.16568 -39.96944)
		(end 91.16568 -40.38854)
		(stroke
			(width 0.06985)
			(type default)
		)
		(layer "In2.Cu")
	)
	(gr_line
		(start 91.16568 -38.77564)
		(end 91.16568 -39.19474)
		(stroke
			(width 0.06985)
			(type default)
		)
		(layer "In2.Cu")
	)
	(gr_line
		(start 91.16568 -37.58184)
		(end 91.16568 -38.00094)
		(stroke
			(width 0.06985)
			(type default)
		)
		(layer "In2.Cu")
	)
	(gr_line
		(start 94.937834 -20.86991)
		(end 95.014796 -20.792948)
		(stroke
			(width 0.06985)
			(type default)
		)
		(layer "In2.Cu")
	)
	(gr_line
		(start 94.939612 -21.338794)
		(end 95.187516 -21.338794)
		(stroke
			(width 0.06985)
			(type default)
		)
		(layer "In2.Cu")
	)
	(gr_line
		(start 95.187516 -21.338794)
		(end 95.48368 -21.04263)
		(stroke
			(width 0.06985)
			(type default)
		)
		(layer "In2.Cu")
	)
	(gr_line
		(start 95.48368 -20.794726)
		(end 95.48368 -21.04263)
		(stroke
			(width 0.06985)
			(type default)
		)
		(layer "In2.Cu")
	)
	(gr_line
		(start 95.781876 -20.025868)
		(end 95.873316 -19.934428)
		(stroke
			(width 0.06985)
			(type default)
		)
		(layer "In2.Cu")
	)
	(gr_line
		(start 95.783654 -20.494752)
		(end 96.045782 -20.494752)
		(stroke
			(width 0.06985)
			(type default)
		)
		(layer "In2.Cu")
	)
	(gr_line
		(start 96.045782 -20.494752)
		(end 96.3422 -20.198588)
		(stroke
			(width 0.06985)
			(type default)
		)
		(layer "In2.Cu")
	)
	(gr_line
		(start 96.3422 -19.936206)
		(end 96.3422 -20.198588)
		(stroke
			(width 0.06985)
			(type default)
		)
		(layer "In2.Cu")
	)
	(gr_line
		(start 98.236786 -20.242022)
		(end 98.470974 -20.007834)
		(stroke
			(width 0.06985)
			(type default)
		)
		(layer "In2.Cu")
	)
	(gr_line
		(start 98.941636 -20.007834)
		(end 99.175824 -20.242022)
		(stroke
			(width 0.06985)
			(type default)
		)
		(layer "In2.Cu")
	)
	(gr_line
		(start 0 -183.76392)
		(end 0 -0.999998)
		(stroke
			(width 2.54)
			(type default)
		)
		(layer "In3.Cu")
	)
	(gr_arc
		(start 0 -183.76392)
		(mid 0.026807 -183.993715)
		(end 0.105664 -184.211214)
		(stroke
			(width 2.54)
			(type default)
		)
		(layer "In3.Cu")
	)
	(gr_line
		(start 0.413766 -183.291988)
		(end 0.959104 -182.74665)
		(stroke
			(width 0.381)
			(type default)
		)
		(layer "In3.Cu")
	)
	(gr_line
		(start 0.959104 -182.74665)
		(end 13.322554 -182.74665)
		(stroke
			(width 0.381)
			(type default)
		)
		(layer "In3.Cu")
	)
	(gr_arc
		(start 0.999998 0)
		(mid 0.292893 -0.292893)
		(end 0 -0.999998)
		(stroke
			(width 2.54)
			(type default)
		)
		(layer "In3.Cu")
	)
	(gr_line
		(start 0.999998 0)
		(end 29.53004 0)
		(stroke
			(width 2.54)
			(type default)
		)
		(layer "In3.Cu")
	)
	(gr_line
		(start 1.397 -182.7784)
		(end 1.016 -182.3974)
		(stroke
			(width 0.381)
			(type default)
		)
		(layer "In3.Cu")
	)
	(gr_line
		(start 1.397 -182.7784)
		(end 1.0922 -183.0832)
		(stroke
			(width 0.381)
			(type default)
		)
		(layer "In3.Cu")
	)
	(gr_line
		(start 1.397 -108.5596)
		(end 1.016 -108.1786)
		(stroke
			(width 0.381)
			(type default)
		)
		(layer "In3.Cu")
	)
	(gr_line
		(start 1.397 -108.5596)
		(end 1.0922 -108.8644)
		(stroke
			(width 0.381)
			(type default)
		)
		(layer "In3.Cu")
	)
	(gr_line
		(start 4.723638 -193.447162)
		(end 0.105664 -184.211214)
		(stroke
			(width 2.54)
			(type default)
		)
		(layer "In3.Cu")
	)
	(gr_arc
		(start 4.723638 -193.447162)
		(mid 5.092281 -193.850645)
		(end 5.617972 -194.00012)
		(stroke
			(width 2.54)
			(type default)
		)
		(layer "In3.Cu")
	)
	(gr_line
		(start 11.557 -169.799)
		(end 11.557 -155.05684)
		(stroke
			(width 0.381)
			(type default)
		)
		(layer "In3.Cu")
	)
	(gr_line
		(start 11.557 -155.05684)
		(end 11.557 -154.6098)
		(stroke
			(width 0.381)
			(type default)
		)
		(layer "In3.Cu")
	)
	(gr_line
		(start 11.557 -154.1653)
		(end 11.557 -154.6098)
		(stroke
			(width 0.381)
			(type default)
		)
		(layer "In3.Cu")
	)
	(gr_line
		(start 11.557 -154.1653)
		(end 11.557 -119.507)
		(stroke
			(width 0.381)
			(type default)
		)
		(layer "In3.Cu")
	)
	(gr_line
		(start 11.557 -119.507)
		(end 16.002 -115.062)
		(stroke
			(width 0.381)
			(type default)
		)
		(layer "In3.Cu")
	)
	(gr_line
		(start 11.684 -126.746)
		(end 32.80918 -126.746)
		(stroke
			(width 0.381)
			(type default)
		)
		(layer "In3.Cu")
	)
	(gr_line
		(start 11.7602 -160.7693)
		(end 11.5951 -160.9344)
		(stroke
			(width 0.4064)
			(type default)
		)
		(layer "In3.Cu")
	)
	(gr_line
		(start 11.7602 -160.7693)
		(end 11.7602 -160.7312)
		(stroke
			(width 0.4064)
			(type default)
		)
		(layer "In3.Cu")
	)
	(gr_line
		(start 11.7602 -160.7312)
		(end 11.5697 -160.5407)
		(stroke
			(width 0.4064)
			(type default)
		)
		(layer "In3.Cu")
	)
	(gr_line
		(start 11.9634 -126.746)
		(end 11.5824 -126.365)
		(stroke
			(width 0.381)
			(type default)
		)
		(layer "In3.Cu")
	)
	(gr_line
		(start 11.9634 -126.746)
		(end 11.6586 -127.0508)
		(stroke
			(width 0.381)
			(type default)
		)
		(layer "In3.Cu")
	)
	(gr_line
		(start 13.322554 -182.74665)
		(end 15.995904 -185.42)
		(stroke
			(width 0.381)
			(type default)
		)
		(layer "In3.Cu")
	)
	(gr_line
		(start 13.4874 -171.5516)
		(end 13.843 -171.196)
		(stroke
			(width 0.381)
			(type default)
		)
		(layer "In3.Cu")
	)
	(gr_line
		(start 13.6906 -171.3484)
		(end 13.151866 -171.3484)
		(stroke
			(width 0.381)
			(type default)
		)
		(layer "In3.Cu")
	)
	(gr_line
		(start 13.6906 -171.3484)
		(end 13.6906 -171.779438)
		(stroke
			(width 0.381)
			(type default)
		)
		(layer "In3.Cu")
	)
	(gr_line
		(start 13.843 -171.196)
		(end 22.86 -171.196)
		(stroke
			(width 0.381)
			(type default)
		)
		(layer "In3.Cu")
	)
	(gr_circle
		(center 14.249908 -6.249924)
		(end 15.141448 -6.249924)
		(stroke
			(width 0.2)
			(type default)
		)
		(fill no)
		(layer "In3.Cu")
	)
	(gr_line
		(start 15.995904 -185.42)
		(end 24.257 -185.42)
		(stroke
			(width 0.381)
			(type default)
		)
		(layer "In3.Cu")
	)
	(gr_line
		(start 16.002 -115.062)
		(end 80.01 -115.062)
		(stroke
			(width 0.381)
			(type default)
		)
		(layer "In3.Cu")
	)
	(gr_line
		(start 18.542 -176.784)
		(end 11.557 -169.799)
		(stroke
			(width 0.381)
			(type default)
		)
		(layer "In3.Cu")
	)
	(gr_line
		(start 22.86 -171.196)
		(end 25.273 -173.609)
		(stroke
			(width 0.381)
			(type default)
		)
		(layer "In3.Cu")
	)
	(gr_line
		(start 23.622 -176.784)
		(end 18.542 -176.784)
		(stroke
			(width 0.381)
			(type default)
		)
		(layer "In3.Cu")
	)
	(gr_line
		(start 24.257 -188.3664)
		(end 28.9306 -193.04)
		(stroke
			(width 0.381)
			(type default)
		)
		(layer "In3.Cu")
	)
	(gr_line
		(start 24.257 -185.42)
		(end 24.257 -188.3664)
		(stroke
			(width 0.381)
			(type default)
		)
		(layer "In3.Cu")
	)
	(gr_line
		(start 24.257 -185.42)
		(end 24.892 -184.785)
		(stroke
			(width 0.381)
			(type default)
		)
		(layer "In3.Cu")
	)
	(gr_line
		(start 24.3078 -160.7693)
		(end 11.7602 -160.7693)
		(stroke
			(width 0.381)
			(type default)
		)
		(layer "In3.Cu")
	)
	(gr_line
		(start 24.892 -184.785)
		(end 24.892 -178.054)
		(stroke
			(width 0.381)
			(type default)
		)
		(layer "In3.Cu")
	)
	(gr_line
		(start 24.892 -178.054)
		(end 23.622 -176.784)
		(stroke
			(width 0.381)
			(type default)
		)
		(layer "In3.Cu")
	)
	(gr_line
		(start 25.273 -173.609)
		(end 31.623 -173.609)
		(stroke
			(width 0.381)
			(type default)
		)
		(layer "In3.Cu")
	)
	(gr_line
		(start 25.5143 -159.5628)
		(end 24.3078 -160.7693)
		(stroke
			(width 0.381)
			(type default)
		)
		(layer "In3.Cu")
	)
	(gr_line
		(start 25.5143 -154.8765)
		(end 25.5143 -159.5628)
		(stroke
			(width 0.381)
			(type default)
		)
		(layer "In3.Cu")
	)
	(gr_line
		(start 25.9334 -154.4574)
		(end 25.5143 -154.8765)
		(stroke
			(width 0.381)
			(type default)
		)
		(layer "In3.Cu")
	)
	(gr_circle
		(center 26.249884 -8.750046)
		(end 27.141424 -8.750046)
		(stroke
			(width 0.2)
			(type default)
		)
		(fill no)
		(layer "In3.Cu")
	)
	(gr_line
		(start 28.448 -154.4574)
		(end 25.9334 -154.4574)
		(stroke
			(width 0.381)
			(type default)
		)
		(layer "In3.Cu")
	)
	(gr_line
		(start 28.7782 -154.7876)
		(end 28.448 -154.4574)
		(stroke
			(width 0.381)
			(type default)
		)
		(layer "In3.Cu")
	)
	(gr_line
		(start 28.9306 -193.04)
		(end 81.153 -193.04)
		(stroke
			(width 0.381)
			(type default)
		)
		(layer "In3.Cu")
	)
	(gr_line
		(start 30.1752 -108.588048)
		(end 0.649224 -108.588048)
		(stroke
			(width 0.381)
			(type default)
		)
		(layer "In3.Cu")
	)
	(gr_arc
		(start 30.530038 -109.050074)
		(mid 30.822931 -109.757179)
		(end 31.530036 -110.050072)
		(stroke
			(width 2.54)
			(type default)
		)
		(layer "In3.Cu")
	)
	(gr_arc
		(start 30.530038 -0.999998)
		(mid 30.237147 -0.29288)
		(end 29.53004 0)
		(stroke
			(width 2.54)
			(type default)
		)
		(layer "In3.Cu")
	)
	(gr_line
		(start 30.530038 -0.999998)
		(end 30.530038 -109.050074)
		(stroke
			(width 2.54)
			(type default)
		)
		(layer "In3.Cu")
	)
	(gr_line
		(start 31.530036 -110.050072)
		(end 72.030082 -110.050072)
		(stroke
			(width 2.54)
			(type default)
		)
		(layer "In3.Cu")
	)
	(gr_line
		(start 31.623 -173.609)
		(end 37.80536 -179.79136)
		(stroke
			(width 0.381)
			(type default)
		)
		(layer "In3.Cu")
	)
	(gr_line
		(start 32.80918 -126.746)
		(end 35.29838 -129.2352)
		(stroke
			(width 0.381)
			(type default)
		)
		(layer "In3.Cu")
	)
	(gr_line
		(start 35.29838 -131.13004)
		(end 37.07384 -132.9055)
		(stroke
			(width 0.381)
			(type default)
		)
		(layer "In3.Cu")
	)
	(gr_line
		(start 35.29838 -129.2352)
		(end 35.29838 -131.13004)
		(stroke
			(width 0.381)
			(type default)
		)
		(layer "In3.Cu")
	)
	(gr_line
		(start 36.5252 -154.7876)
		(end 28.7782 -154.7876)
		(stroke
			(width 0.381)
			(type default)
		)
		(layer "In3.Cu")
	)
	(gr_line
		(start 37.07384 -137.15238)
		(end 40.4749 -140.55344)
		(stroke
			(width 0.3048)
			(type default)
		)
		(layer "In3.Cu")
	)
	(gr_line
		(start 37.07384 -136.9822)
		(end 37.07384 -137.15238)
		(stroke
			(width 0.3048)
			(type default)
		)
		(layer "In3.Cu")
	)
	(gr_line
		(start 37.07384 -132.9055)
		(end 37.07384 -136.9822)
		(stroke
			(width 0.381)
			(type default)
		)
		(layer "In3.Cu")
	)
	(gr_line
		(start 37.80536 -179.79136)
		(end 38.80358 -179.79136)
		(stroke
			(width 0.381)
			(type default)
		)
		(layer "In3.Cu")
	)
	(gr_line
		(start 38.80358 -179.79136)
		(end 39.5478 -180.53558)
		(stroke
			(width 0.381)
			(type default)
		)
		(layer "In3.Cu")
	)
	(gr_line
		(start 39.5478 -181.5338)
		(end 46.355 -188.341)
		(stroke
			(width 0.381)
			(type default)
		)
		(layer "In3.Cu")
	)
	(gr_line
		(start 39.5478 -180.53558)
		(end 39.5478 -181.5338)
		(stroke
			(width 0.381)
			(type default)
		)
		(layer "In3.Cu")
	)
	(gr_line
		(start 39.6494 -151.6634)
		(end 36.5252 -154.7876)
		(stroke
			(width 0.381)
			(type default)
		)
		(layer "In3.Cu")
	)
	(gr_line
		(start 39.6494 -150.83536)
		(end 39.6494 -151.6634)
		(stroke
			(width 0.3048)
			(type default)
		)
		(layer "In3.Cu")
	)
	(gr_line
		(start 40.23868 -150.24608)
		(end 39.6494 -150.83536)
		(stroke
			(width 0.3048)
			(type default)
		)
		(layer "In3.Cu")
	)
	(gr_line
		(start 40.4749 -140.55344)
		(end 43.71848 -140.55344)
		(stroke
			(width 0.3048)
			(type default)
		)
		(layer "In3.Cu")
	)
	(gr_line
		(start 43.11142 -150.24608)
		(end 40.23868 -150.24608)
		(stroke
			(width 0.3048)
			(type default)
		)
		(layer "In3.Cu")
	)
	(gr_line
		(start 43.36288 -149.99462)
		(end 43.11142 -150.24608)
		(stroke
			(width 0.3048)
			(type default)
		)
		(layer "In3.Cu")
	)
	(gr_line
		(start 43.36288 -148.95322)
		(end 43.36288 -149.99462)
		(stroke
			(width 0.3048)
			(type default)
		)
		(layer "In3.Cu")
	)
	(gr_line
		(start 43.71848 -140.55344)
		(end 44.196 -141.03096)
		(stroke
			(width 0.3048)
			(type default)
		)
		(layer "In3.Cu")
	)
	(gr_line
		(start 44.196 -144.46504)
		(end 44.89196 -145.161)
		(stroke
			(width 0.3048)
			(type default)
		)
		(layer "In3.Cu")
	)
	(gr_line
		(start 44.196 -141.03096)
		(end 44.196 -144.46504)
		(stroke
			(width 0.3048)
			(type default)
		)
		(layer "In3.Cu")
	)
	(gr_line
		(start 44.89196 -147.42414)
		(end 43.36288 -148.95322)
		(stroke
			(width 0.3048)
			(type default)
		)
		(layer "In3.Cu")
	)
	(gr_line
		(start 44.89196 -145.161)
		(end 44.89196 -147.42414)
		(stroke
			(width 0.3048)
			(type default)
		)
		(layer "In3.Cu")
	)
	(gr_line
		(start 46.355 -188.341)
		(end 74.0156 -188.341)
		(stroke
			(width 0.381)
			(type default)
		)
		(layer "In3.Cu")
	)
	(gr_arc
		(start 72.030082 -110.050072)
		(mid 72.737187 -109.757179)
		(end 73.03008 -109.050074)
		(stroke
			(width 2.54)
			(type default)
		)
		(layer "In3.Cu")
	)
	(gr_line
		(start 73.03008 -109.050074)
		(end 73.03008 -0.999998)
		(stroke
			(width 2.54)
			(type default)
		)
		(layer "In3.Cu")
	)
	(gr_line
		(start 74.0156 -188.341)
		(end 76.4286 -185.928)
		(stroke
			(width 0.381)
			(type default)
		)
		(layer "In3.Cu")
	)
	(gr_arc
		(start 74.030078 0)
		(mid 73.322986 -0.2929)
		(end 73.03008 -0.999998)
		(stroke
			(width 2.54)
			(type default)
		)
		(layer "In3.Cu")
	)
	(gr_line
		(start 74.030078 0)
		(end 234.00004 0)
		(stroke
			(width 2.54)
			(type default)
		)
		(layer "In3.Cu")
	)
	(gr_line
		(start 75.819 -168.021)
		(end 75.819 -165.1)
		(stroke
			(width 0.381)
			(type default)
		)
		(layer "In3.Cu")
	)
	(gr_line
		(start 75.819 -165.1)
		(end 76.581 -164.338)
		(stroke
			(width 0.381)
			(type default)
		)
		(layer "In3.Cu")
	)
	(gr_line
		(start 76.2 -168.402)
		(end 75.819 -168.021)
		(stroke
			(width 0.381)
			(type default)
		)
		(layer "In3.Cu")
	)
	(gr_line
		(start 76.4286 -185.928)
		(end 79.883 -185.928)
		(stroke
			(width 0.381)
			(type default)
		)
		(layer "In3.Cu")
	)
	(gr_line
		(start 76.581 -164.338)
		(end 93.16212 -164.338)
		(stroke
			(width 0.381)
			(type default)
		)
		(layer "In3.Cu")
	)
	(gr_arc
		(start 76.891134 -68.211192)
		(mid 77.274674 -68.594732)
		(end 77.658214 -68.211192)
		(stroke
			(width 0.2)
			(type default)
		)
		(layer "In3.Cu")
	)
	(gr_line
		(start 76.891134 -67.322192)
		(end 76.891134 -68.211192)
		(stroke
			(width 0.2)
			(type default)
		)
		(layer "In3.Cu")
	)
	(gr_arc
		(start 76.900278 -93.799914)
		(mid 77.283691 -94.183708)
		(end 77.667358 -93.800168)
		(stroke
			(width 0.2)
			(type default)
		)
		(layer "In3.Cu")
	)
	(gr_line
		(start 76.900278 -92.911168)
		(end 76.900278 -93.799914)
		(stroke
			(width 0.2)
			(type default)
		)
		(layer "In3.Cu")
	)
	(gr_arc
		(start 76.900278 -87.399114)
		(mid 77.283691 -87.782908)
		(end 77.667358 -87.399368)
		(stroke
			(width 0.2)
			(type default)
		)
		(layer "In3.Cu")
	)
	(gr_line
		(start 76.900278 -86.510368)
		(end 76.900278 -87.399114)
		(stroke
			(width 0.2)
			(type default)
		)
		(layer "In3.Cu")
	)
	(gr_arc
		(start 76.900278 -80.998314)
		(mid 77.283691 -81.382108)
		(end 77.667358 -80.998568)
		(stroke
			(width 0.2)
			(type default)
		)
		(layer "In3.Cu")
	)
	(gr_line
		(start 76.900278 -80.109568)
		(end 76.900278 -80.998314)
		(stroke
			(width 0.2)
			(type default)
		)
		(layer "In3.Cu")
	)
	(gr_arc
		(start 76.900278 -74.597514)
		(mid 77.283691 -74.981308)
		(end 77.667358 -74.597768)
		(stroke
			(width 0.2)
			(type default)
		)
		(layer "In3.Cu")
	)
	(gr_line
		(start 76.900278 -73.708768)
		(end 76.900278 -74.597514)
		(stroke
			(width 0.2)
			(type default)
		)
		(layer "In3.Cu")
	)
	(gr_line
		(start 77.658214 -68.211192)
		(end 77.658214 -67.322446)
		(stroke
			(width 0.2)
			(type default)
		)
		(layer "In3.Cu")
	)
	(gr_arc
		(start 77.658214 -67.322446)
		(mid 77.274801 -66.938652)
		(end 76.891134 -67.322192)
		(stroke
			(width 0.2)
			(type default)
		)
		(layer "In3.Cu")
	)
	(gr_line
		(start 77.667358 -93.800168)
		(end 77.667358 -92.911168)
		(stroke
			(width 0.2)
			(type default)
		)
		(layer "In3.Cu")
	)
	(gr_arc
		(start 77.667358 -92.911168)
		(mid 77.283818 -92.527628)
		(end 76.900278 -92.911168)
		(stroke
			(width 0.2)
			(type default)
		)
		(layer "In3.Cu")
	)
	(gr_line
		(start 77.667358 -87.399368)
		(end 77.667358 -86.510368)
		(stroke
			(width 0.2)
			(type default)
		)
		(layer "In3.Cu")
	)
	(gr_arc
		(start 77.667358 -86.510368)
		(mid 77.283818 -86.126828)
		(end 76.900278 -86.510368)
		(stroke
			(width 0.2)
			(type default)
		)
		(layer "In3.Cu")
	)
	(gr_line
		(start 77.667358 -80.998568)
		(end 77.667358 -80.109568)
		(stroke
			(width 0.2)
			(type default)
		)
		(layer "In3.Cu")
	)
	(gr_arc
		(start 77.667358 -80.109568)
		(mid 77.283818 -79.726028)
		(end 76.900278 -80.109568)
		(stroke
			(width 0.2)
			(type default)
		)
		(layer "In3.Cu")
	)
	(gr_line
		(start 77.667358 -74.597768)
		(end 77.667358 -73.708768)
		(stroke
			(width 0.2)
			(type default)
		)
		(layer "In3.Cu")
	)
	(gr_arc
		(start 77.667358 -73.708768)
		(mid 77.283818 -73.325228)
		(end 76.900278 -73.708768)
		(stroke
			(width 0.2)
			(type default)
		)
		(layer "In3.Cu")
	)
	(gr_line
		(start 77.724 -168.402)
		(end 76.2 -168.402)
		(stroke
			(width 0.381)
			(type default)
		)
		(layer "In3.Cu")
	)
	(gr_arc
		(start 77.738478 -90.599514)
		(mid 78.121891 -90.983308)
		(end 78.505558 -90.599768)
		(stroke
			(width 0.2)
			(type default)
		)
		(layer "In3.Cu")
	)
	(gr_line
		(start 77.738478 -89.710768)
		(end 77.738478 -90.599514)
		(stroke
			(width 0.2)
			(type default)
		)
		(layer "In3.Cu")
	)
	(gr_arc
		(start 77.738478 -84.224114)
		(mid 78.121891 -84.607908)
		(end 78.505558 -84.224368)
		(stroke
			(width 0.2)
			(type default)
		)
		(layer "In3.Cu")
	)
	(gr_line
		(start 77.738478 -83.335368)
		(end 77.738478 -84.224114)
		(stroke
			(width 0.2)
			(type default)
		)
		(layer "In3.Cu")
	)
	(gr_arc
		(start 77.738478 -77.797914)
		(mid 78.121891 -78.181708)
		(end 78.505558 -77.798168)
		(stroke
			(width 0.2)
			(type default)
		)
		(layer "In3.Cu")
	)
	(gr_line
		(start 77.738478 -76.909168)
		(end 77.738478 -77.797914)
		(stroke
			(width 0.2)
			(type default)
		)
		(layer "In3.Cu")
	)
	(gr_arc
		(start 77.738478 -71.397114)
		(mid 78.121891 -71.780908)
		(end 78.505558 -71.397368)
		(stroke
			(width 0.2)
			(type default)
		)
		(layer "In3.Cu")
	)
	(gr_line
		(start 77.738478 -70.508368)
		(end 77.738478 -71.397114)
		(stroke
			(width 0.2)
			(type default)
		)
		(layer "In3.Cu")
	)
	(gr_line
		(start 78.105 -168.783)
		(end 77.724 -168.402)
		(stroke
			(width 0.381)
			(type default)
		)
		(layer "In3.Cu")
	)
	(gr_line
		(start 78.505558 -90.599768)
		(end 78.505558 -89.710768)
		(stroke
			(width 0.2)
			(type default)
		)
		(layer "In3.Cu")
	)
	(gr_arc
		(start 78.505558 -89.710768)
		(mid 78.122018 -89.327228)
		(end 77.738478 -89.710768)
		(stroke
			(width 0.2)
			(type default)
		)
		(layer "In3.Cu")
	)
	(gr_line
		(start 78.505558 -84.224368)
		(end 78.505558 -83.335368)
		(stroke
			(width 0.2)
			(type default)
		)
		(layer "In3.Cu")
	)
	(gr_arc
		(start 78.505558 -83.335368)
		(mid 78.122018 -82.951828)
		(end 77.738478 -83.335368)
		(stroke
			(width 0.2)
			(type default)
		)
		(layer "In3.Cu")
	)
	(gr_line
		(start 78.505558 -77.798168)
		(end 78.505558 -76.909168)
		(stroke
			(width 0.2)
			(type default)
		)
		(layer "In3.Cu")
	)
	(gr_arc
		(start 78.505558 -76.909168)
		(mid 78.122018 -76.525628)
		(end 77.738478 -76.909168)
		(stroke
			(width 0.2)
			(type default)
		)
		(layer "In3.Cu")
	)
	(gr_line
		(start 78.505558 -71.397368)
		(end 78.505558 -70.508368)
		(stroke
			(width 0.2)
			(type default)
		)
		(layer "In3.Cu")
	)
	(gr_arc
		(start 78.505558 -70.508368)
		(mid 78.122018 -70.124828)
		(end 77.738478 -70.508368)
		(stroke
			(width 0.2)
			(type default)
		)
		(layer "In3.Cu")
	)
	(gr_line
		(start 79.883 -185.928)
		(end 80.899 -184.912)
		(stroke
			(width 0.381)
			(type default)
		)
		(layer "In3.Cu")
	)
	(gr_line
		(start 80.01 -115.062)
		(end 88.5444 -106.5276)
		(stroke
			(width 0.381)
			(type default)
		)
		(layer "In3.Cu")
	)
	(gr_line
		(start 80.899 -184.912)
		(end 80.899 -178.56454)
		(stroke
			(width 0.381)
			(type default)
		)
		(layer "In3.Cu")
	)
	(gr_line
		(start 80.899 -178.56454)
		(end 83.59648 -175.86706)
		(stroke
			(width 0.381)
			(type default)
		)
		(layer "In3.Cu")
	)
	(gr_line
		(start 81.026 -168.783)
		(end 78.105 -168.783)
		(stroke
			(width 0.381)
			(type default)
		)
		(layer "In3.Cu")
	)
	(gr_arc
		(start 82.974688 -95.381318)
		(mid 83.358101 -95.765112)
		(end 83.741768 -95.381572)
		(stroke
			(width 0.2)
			(type default)
		)
		(layer "In3.Cu")
	)
	(gr_line
		(start 82.974688 -94.492572)
		(end 82.974688 -95.381318)
		(stroke
			(width 0.2)
			(type default)
		)
		(layer "In3.Cu")
	)
	(gr_arc
		(start 82.974688 -88.994234)
		(mid 83.358228 -89.377774)
		(end 83.741768 -88.994234)
		(stroke
			(width 0.2)
			(type default)
		)
		(layer "In3.Cu")
	)
	(gr_line
		(start 82.974688 -88.105234)
		(end 82.974688 -88.994234)
		(stroke
			(width 0.2)
			(type default)
		)
		(layer "In3.Cu")
	)
	(gr_arc
		(start 82.974688 -82.593942)
		(mid 83.358101 -82.977736)
		(end 83.741768 -82.594196)
		(stroke
			(width 0.2)
			(type default)
		)
		(layer "In3.Cu")
	)
	(gr_line
		(start 82.974688 -81.705196)
		(end 82.974688 -82.593942)
		(stroke
			(width 0.2)
			(type default)
		)
		(layer "In3.Cu")
	)
	(gr_arc
		(start 82.974688 -76.193904)
		(mid 83.358101 -76.577698)
		(end 83.741768 -76.194158)
		(stroke
			(width 0.2)
			(type default)
		)
		(layer "In3.Cu")
	)
	(gr_line
		(start 82.974688 -75.305158)
		(end 82.974688 -76.193904)
		(stroke
			(width 0.2)
			(type default)
		)
		(layer "In3.Cu")
	)
	(gr_line
		(start 83.59648 -175.86706)
		(end 83.59648 -171.35348)
		(stroke
			(width 0.381)
			(type default)
		)
		(layer "In3.Cu")
	)
	(gr_line
		(start 83.59648 -171.35348)
		(end 81.026 -168.783)
		(stroke
			(width 0.381)
			(type default)
		)
		(layer "In3.Cu")
	)
	(gr_line
		(start 83.741768 -95.381572)
		(end 83.741768 -94.492572)
		(stroke
			(width 0.2)
			(type default)
		)
		(layer "In3.Cu")
	)
	(gr_arc
		(start 83.741768 -94.492572)
		(mid 83.358228 -94.109032)
		(end 82.974688 -94.492572)
		(stroke
			(width 0.2)
			(type default)
		)
		(layer "In3.Cu")
	)
	(gr_line
		(start 83.741768 -88.994234)
		(end 83.741768 -88.105488)
		(stroke
			(width 0.2)
			(type default)
		)
		(layer "In3.Cu")
	)
	(gr_arc
		(start 83.741768 -88.105488)
		(mid 83.358355 -87.721694)
		(end 82.974688 -88.105234)
		(stroke
			(width 0.2)
			(type default)
		)
		(layer "In3.Cu")
	)
	(gr_line
		(start 83.741768 -82.594196)
		(end 83.741768 -81.705196)
		(stroke
			(width 0.2)
			(type default)
		)
		(layer "In3.Cu")
	)
	(gr_arc
		(start 83.741768 -81.705196)
		(mid 83.358228 -81.321656)
		(end 82.974688 -81.705196)
		(stroke
			(width 0.2)
			(type default)
		)
		(layer "In3.Cu")
	)
	(gr_line
		(start 83.741768 -76.194158)
		(end 83.741768 -75.305158)
		(stroke
			(width 0.2)
			(type default)
		)
		(layer "In3.Cu")
	)
	(gr_arc
		(start 83.741768 -75.305158)
		(mid 83.358228 -74.921618)
		(end 82.974688 -75.305158)
		(stroke
			(width 0.2)
			(type default)
		)
		(layer "In3.Cu")
	)
	(gr_line
		(start 84.0486 -97.023936)
		(end 84.0486 -52.388008)
		(stroke
			(width 0.381)
			(type default)
		)
		(layer "In3.Cu")
	)
	(gr_line
		(start 84.0486 -52.388008)
		(end 84.4296 -52.007008)
		(stroke
			(width 0.381)
			(type default)
		)
		(layer "In3.Cu")
	)
	(gr_line
		(start 84.4296 -52.007008)
		(end 92.899992 -52.007008)
		(stroke
			(width 0.381)
			(type default)
		)
		(layer "In3.Cu")
	)
	(gr_arc
		(start 84.600288 -92.195142)
		(mid 84.983701 -92.578936)
		(end 85.367368 -92.195396)
		(stroke
			(width 0.2)
			(type default)
		)
		(layer "In3.Cu")
	)
	(gr_line
		(start 84.600288 -91.306396)
		(end 84.600288 -92.195142)
		(stroke
			(width 0.2)
			(type default)
		)
		(layer "In3.Cu")
	)
	(gr_arc
		(start 84.600288 -85.79358)
		(mid 84.983701 -86.177374)
		(end 85.367368 -85.793834)
		(stroke
			(width 0.2)
			(type default)
		)
		(layer "In3.Cu")
	)
	(gr_line
		(start 84.600288 -84.904834)
		(end 84.600288 -85.79358)
		(stroke
			(width 0.2)
			(type default)
		)
		(layer "In3.Cu")
	)
	(gr_arc
		(start 84.600288 -79.393542)
		(mid 84.983701 -79.777336)
		(end 85.367368 -79.393796)
		(stroke
			(width 0.2)
			(type default)
		)
		(layer "In3.Cu")
	)
	(gr_line
		(start 84.600288 -78.504796)
		(end 84.600288 -79.393542)
		(stroke
			(width 0.2)
			(type default)
		)
		(layer "In3.Cu")
	)
	(gr_arc
		(start 84.600288 -72.970136)
		(mid 84.983828 -73.353676)
		(end 85.367368 -72.970136)
		(stroke
			(width 0.2)
			(type default)
		)
		(layer "In3.Cu")
	)
	(gr_line
		(start 84.600288 -72.081136)
		(end 84.600288 -72.970136)
		(stroke
			(width 0.2)
			(type default)
		)
		(layer "In3.Cu")
	)
	(gr_line
		(start 85.367368 -92.195396)
		(end 85.367368 -91.306396)
		(stroke
			(width 0.2)
			(type default)
		)
		(layer "In3.Cu")
	)
	(gr_arc
		(start 85.367368 -91.306396)
		(mid 84.983828 -90.922856)
		(end 84.600288 -91.306396)
		(stroke
			(width 0.2)
			(type default)
		)
		(layer "In3.Cu")
	)
	(gr_line
		(start 85.367368 -85.793834)
		(end 85.367368 -84.904834)
		(stroke
			(width 0.2)
			(type default)
		)
		(layer "In3.Cu")
	)
	(gr_arc
		(start 85.367368 -84.904834)
		(mid 84.983828 -84.521294)
		(end 84.600288 -84.904834)
		(stroke
			(width 0.2)
			(type default)
		)
		(layer "In3.Cu")
	)
	(gr_line
		(start 85.367368 -79.393796)
		(end 85.367368 -78.504796)
		(stroke
			(width 0.2)
			(type default)
		)
		(layer "In3.Cu")
	)
	(gr_arc
		(start 85.367368 -78.504796)
		(mid 84.983828 -78.121256)
		(end 84.600288 -78.504796)
		(stroke
			(width 0.2)
			(type default)
		)
		(layer "In3.Cu")
	)
	(gr_line
		(start 85.367368 -72.970136)
		(end 85.367368 -72.08139)
		(stroke
			(width 0.2)
			(type default)
		)
		(layer "In3.Cu")
	)
	(gr_arc
		(start 85.367368 -72.08139)
		(mid 84.983955 -71.697596)
		(end 84.600288 -72.081136)
		(stroke
			(width 0.2)
			(type default)
		)
		(layer "In3.Cu")
	)
	(gr_line
		(start 85.4202 -193.2432)
		(end 85.4202 -187.452)
		(stroke
			(width 0.381)
			(type default)
		)
		(layer "In3.Cu")
	)
	(gr_line
		(start 85.4202 -187.452)
		(end 89.8652 -183.007)
		(stroke
			(width 0.381)
			(type default)
		)
		(layer "In3.Cu")
	)
	(gr_line
		(start 85.471 -192.5828)
		(end 85.09 -192.9638)
		(stroke
			(width 0.381)
			(type default)
		)
		(layer "In3.Cu")
	)
	(gr_line
		(start 85.471 -192.5828)
		(end 85.7758 -192.8876)
		(stroke
			(width 0.381)
			(type default)
		)
		(layer "In3.Cu")
	)
	(gr_line
		(start 88.5444 -106.5276)
		(end 88.5444 -101.519736)
		(stroke
			(width 0.381)
			(type default)
		)
		(layer "In3.Cu")
	)
	(gr_line
		(start 88.5444 -101.519736)
		(end 84.0486 -97.023936)
		(stroke
			(width 0.381)
			(type default)
		)
		(layer "In3.Cu")
	)
	(gr_line
		(start 89.8652 -183.007)
		(end 96.7994 -183.007)
		(stroke
			(width 0.381)
			(type default)
		)
		(layer "In3.Cu")
	)
	(gr_line
		(start 92.899992 -52.007008)
		(end 93.345 -51.562)
		(stroke
			(width 0.381)
			(type default)
		)
		(layer "In3.Cu")
	)
	(gr_line
		(start 93.16212 -164.338)
		(end 96.1771 -161.32302)
		(stroke
			(width 0.381)
			(type default)
		)
		(layer "In3.Cu")
	)
	(gr_line
		(start 93.345 -51.562)
		(end 93.345 -48.387)
		(stroke
			(width 0.381)
			(type default)
		)
		(layer "In3.Cu")
	)
	(gr_line
		(start 93.345 -48.387)
		(end 94.742 -46.99)
		(stroke
			(width 0.381)
			(type default)
		)
		(layer "In3.Cu")
	)
	(gr_line
		(start 94.742 -46.99)
		(end 97.665286 -46.99)
		(stroke
			(width 0.381)
			(type default)
		)
		(layer "In3.Cu")
	)
	(gr_line
		(start 96.1771 -161.32302)
		(end 96.1771 -157.21838)
		(stroke
			(width 0.381)
			(type default)
		)
		(layer "In3.Cu")
	)
	(gr_line
		(start 96.1771 -157.21838)
		(end 97.10928 -156.2862)
		(stroke
			(width 0.381)
			(type default)
		)
		(layer "In3.Cu")
	)
	(gr_line
		(start 96.7994 -183.007)
		(end 101.2698 -178.5366)
		(stroke
			(width 0.381)
			(type default)
		)
		(layer "In3.Cu")
	)
	(gr_line
		(start 97.028 -144.78)
		(end 97.028 -135.763)
		(stroke
			(width 0.381)
			(type default)
		)
		(layer "In3.Cu")
	)
	(gr_line
		(start 97.028 -135.763)
		(end 97.663 -135.128)
		(stroke
			(width 0.381)
			(type default)
		)
		(layer "In3.Cu")
	)
	(gr_line
		(start 97.10928 -156.2862)
		(end 98.02622 -156.2862)
		(stroke
			(width 0.381)
			(type default)
		)
		(layer "In3.Cu")
	)
	(gr_line
		(start 97.663 -135.128)
		(end 97.663 -47.01286)
		(stroke
			(width 0.381)
			(type default)
		)
		(layer "In3.Cu")
	)
	(gr_line
		(start 97.663 -47.5488)
		(end 97.155 -47.0408)
		(stroke
			(width 0.381)
			(type default)
		)
		(layer "In3.Cu")
	)
	(gr_line
		(start 97.665286 -46.99)
		(end 97.670366 -46.99508)
		(stroke
			(width 0.381)
			(type default)
		)
		(layer "In3.Cu")
	)
	(gr_arc
		(start 97.670366 -46.99508)
		(mid 97.664883 -47.003227)
		(end 97.663 -47.01286)
		(stroke
			(width 0.381)
			(type default)
		)
		(layer "In3.Cu")
	)
	(gr_line
		(start 97.670366 -46.99508)
		(end 99.314 -45.351446)
		(stroke
			(width 0.381)
			(type default)
		)
		(layer "In3.Cu")
	)
	(gr_line
		(start 98.02622 -156.2862)
		(end 98.425 -155.88742)
		(stroke
			(width 0.381)
			(type default)
		)
		(layer "In3.Cu")
	)
	(gr_line
		(start 98.081846 -194.00012)
		(end 5.617972 -194.00012)
		(stroke
			(width 2.54)
			(type default)
		)
		(layer "In3.Cu")
	)
	(gr_arc
		(start 98.081846 -194.00012)
		(mid 98.607706 -193.850755)
		(end 98.976434 -193.447162)
		(stroke
			(width 2.54)
			(type default)
		)
		(layer "In3.Cu")
	)
	(gr_line
		(start 98.425 -155.88742)
		(end 98.425 -146.177)
		(stroke
			(width 0.381)
			(type default)
		)
		(layer "In3.Cu")
	)
	(gr_line
		(start 98.425 -146.177)
		(end 97.028 -144.78)
		(stroke
			(width 0.381)
			(type default)
		)
		(layer "In3.Cu")
	)
	(gr_line
		(start 99.314 -45.351446)
		(end 99.314 -20.4724)
		(stroke
			(width 0.381)
			(type default)
		)
		(layer "In3.Cu")
	)
	(gr_line
		(start 99.314 -20.4724)
		(end 109.4994 -10.287)
		(stroke
			(width 0.381)
			(type default)
		)
		(layer "In3.Cu")
	)
	(gr_line
		(start 101.2698 -178.5366)
		(end 104.3432 -178.5366)
		(stroke
			(width 0.381)
			(type default)
		)
		(layer "In3.Cu")
	)
	(gr_line
		(start 102.2604 -178.5366)
		(end 102.5652 -178.2318)
		(stroke
			(width 0.381)
			(type default)
		)
		(layer "In3.Cu")
	)
	(gr_line
		(start 102.2604 -178.5366)
		(end 102.6414 -178.9176)
		(stroke
			(width 0.381)
			(type default)
		)
		(layer "In3.Cu")
	)
	(gr_line
		(start 103.594408 -184.211214)
		(end 98.976434 -193.447162)
		(stroke
			(width 2.54)
			(type default)
		)
		(layer "In3.Cu")
	)
	(gr_arc
		(start 103.594408 -184.211214)
		(mid 103.673311 -183.993725)
		(end 103.700072 -183.76392)
		(stroke
			(width 2.54)
			(type default)
		)
		(layer "In3.Cu")
	)
	(gr_line
		(start 103.700072 -47.999904)
		(end 103.700072 -183.76392)
		(stroke
			(width 2.54)
			(type default)
		)
		(layer "In3.Cu")
	)
	(gr_line
		(start 104.3432 -45.8978)
		(end 104.3432 -169.8498)
		(stroke
			(width 0.381)
			(type default)
		)
		(layer "In3.Cu")
	)
	(gr_arc
		(start 104.70007 -47.999904)
		(mid 104.200198 -47.500032)
		(end 103.700072 -47.999904)
		(stroke
			(width 2.54)
			(type default)
		)
		(layer "In3.Cu")
	)
	(gr_line
		(start 104.775 -45.466)
		(end 104.3432 -45.8978)
		(stroke
			(width 0.381)
			(type default)
		)
		(layer "In3.Cu")
	)
	(gr_line
		(start 104.775 -25.654)
		(end 104.775 -45.466)
		(stroke
			(width 0.381)
			(type default)
		)
		(layer "In3.Cu")
	)
	(gr_arc
		(start 106.614722 -38.200076)
		(mid 107.099862 -38.685216)
		(end 107.585002 -38.200076)
		(stroke
			(width 0.2)
			(type default)
		)
		(layer "In3.Cu")
	)
	(gr_line
		(start 106.614722 -36.800028)
		(end 106.614722 -38.200076)
		(stroke
			(width 0.2)
			(type default)
		)
		(layer "In3.Cu")
	)
	(gr_arc
		(start 106.614722 -34.600134)
		(mid 107.099862 -35.085274)
		(end 107.585002 -34.600134)
		(stroke
			(width 0.2)
			(type default)
		)
		(layer "In3.Cu")
	)
	(gr_line
		(start 106.614722 -33.200086)
		(end 106.614722 -34.600134)
		(stroke
			(width 0.2)
			(type default)
		)
		(layer "In3.Cu")
	)
	(gr_line
		(start 107.585002 -38.200076)
		(end 107.585002 -36.800282)
		(stroke
			(width 0.2)
			(type default)
		)
		(layer "In3.Cu")
	)
	(gr_arc
		(start 107.585002 -36.800282)
		(mid 107.099989 -36.314888)
		(end 106.614722 -36.800028)
		(stroke
			(width 0.2)
			(type default)
		)
		(layer "In3.Cu")
	)
	(gr_line
		(start 107.585002 -34.600134)
		(end 107.585002 -33.20034)
		(stroke
			(width 0.2)
			(type default)
		)
		(layer "In3.Cu")
	)
	(gr_arc
		(start 107.585002 -33.20034)
		(mid 107.099989 -32.714946)
		(end 106.614722 -33.200086)
		(stroke
			(width 0.2)
			(type default)
		)
		(layer "In3.Cu")
	)
	(gr_arc
		(start 108.41482 -37.00018)
		(mid 108.89996 -37.48532)
		(end 109.3851 -37.00018)
		(stroke
			(width 0.2)
			(type default)
		)
		(layer "In3.Cu")
	)
	(gr_line
		(start 108.41482 -35.600132)
		(end 108.41482 -37.00018)
		(stroke
			(width 0.2)
			(type default)
		)
		(layer "In3.Cu")
	)
	(gr_arc
		(start 108.41482 -33.399984)
		(mid 108.89996 -33.885124)
		(end 109.3851 -33.399984)
		(stroke
			(width 0.2)
			(type default)
		)
		(layer "In3.Cu")
	)
	(gr_line
		(start 108.41482 -32.00019)
		(end 108.41482 -33.399984)
		(stroke
			(width 0.2)
			(type default)
		)
		(layer "In3.Cu")
	)
	(gr_line
		(start 109.3851 -37.00018)
		(end 109.3851 -35.600386)
		(stroke
			(width 0.2)
			(type default)
		)
		(layer "In3.Cu")
	)
	(gr_arc
		(start 109.3851 -35.600386)
		(mid 108.900087 -35.114992)
		(end 108.41482 -35.600132)
		(stroke
			(width 0.2)
			(type default)
		)
		(layer "In3.Cu")
	)
	(gr_line
		(start 109.3851 -33.399984)
		(end 109.3851 -32.000444)
		(stroke
			(width 0.2)
			(type default)
		)
		(layer "In3.Cu")
	)
	(gr_arc
		(start 109.3851 -32.000444)
		(mid 108.900087 -31.51505)
		(end 108.41482 -32.00019)
		(stroke
			(width 0.2)
			(type default)
		)
		(layer "In3.Cu")
	)
	(gr_line
		(start 109.4994 -10.287)
		(end 117.83568 -10.287)
		(stroke
			(width 0.381)
			(type default)
		)
		(layer "In3.Cu")
	)
	(gr_arc
		(start 110.214918 -38.200076)
		(mid 110.700058 -38.685216)
		(end 111.185198 -38.200076)
		(stroke
			(width 0.2)
			(type default)
		)
		(layer "In3.Cu")
	)
	(gr_line
		(start 110.214918 -36.800028)
		(end 110.214918 -38.200076)
		(stroke
			(width 0.2)
			(type default)
		)
		(layer "In3.Cu")
	)
	(gr_arc
		(start 110.214918 -34.600134)
		(mid 110.700058 -35.085274)
		(end 111.185198 -34.600134)
		(stroke
			(width 0.2)
			(type default)
		)
		(layer "In3.Cu")
	)
	(gr_line
		(start 110.214918 -33.200086)
		(end 110.214918 -34.600134)
		(stroke
			(width 0.2)
			(type default)
		)
		(layer "In3.Cu")
	)
	(gr_line
		(start 111.185198 -38.200076)
		(end 111.185198 -36.800282)
		(stroke
			(width 0.2)
			(type default)
		)
		(layer "In3.Cu")
	)
	(gr_arc
		(start 111.185198 -36.800282)
		(mid 110.700185 -36.314888)
		(end 110.214918 -36.800028)
		(stroke
			(width 0.2)
			(type default)
		)
		(layer "In3.Cu")
	)
	(gr_line
		(start 111.185198 -34.600134)
		(end 111.185198 -33.20034)
		(stroke
			(width 0.2)
			(type default)
		)
		(layer "In3.Cu")
	)
	(gr_arc
		(start 111.185198 -33.20034)
		(mid 110.700185 -32.714946)
		(end 110.214918 -33.200086)
		(stroke
			(width 0.2)
			(type default)
		)
		(layer "In3.Cu")
	)
	(gr_arc
		(start 112.014762 -37.00018)
		(mid 112.499902 -37.48532)
		(end 112.985042 -37.00018)
		(stroke
			(width 0.2)
			(type default)
		)
		(layer "In3.Cu")
	)
	(gr_line
		(start 112.014762 -35.600132)
		(end 112.014762 -37.00018)
		(stroke
			(width 0.2)
			(type default)
		)
		(layer "In3.Cu")
	)
	(gr_arc
		(start 112.014762 -33.399984)
		(mid 112.499902 -33.885124)
		(end 112.985042 -33.399984)
		(stroke
			(width 0.2)
			(type default)
		)
		(layer "In3.Cu")
	)
	(gr_line
		(start 112.014762 -32.00019)
		(end 112.014762 -33.399984)
		(stroke
			(width 0.2)
			(type default)
		)
		(layer "In3.Cu")
	)
	(gr_line
		(start 112.985042 -37.00018)
		(end 112.985042 -35.600386)
		(stroke
			(width 0.2)
			(type default)
		)
		(layer "In3.Cu")
	)
	(gr_arc
		(start 112.985042 -35.600386)
		(mid 112.500029 -35.114992)
		(end 112.014762 -35.600132)
		(stroke
			(width 0.2)
			(type default)
		)
		(layer "In3.Cu")
	)
	(gr_line
		(start 112.985042 -33.399984)
		(end 112.985042 -32.000444)
		(stroke
			(width 0.2)
			(type default)
		)
		(layer "In3.Cu")
	)
	(gr_arc
		(start 112.985042 -32.000444)
		(mid 112.500029 -31.51505)
		(end 112.014762 -32.00019)
		(stroke
			(width 0.2)
			(type default)
		)
		(layer "In3.Cu")
	)
	(gr_line
		(start 113.4618 -16.9672)
		(end 104.775 -25.654)
		(stroke
			(width 0.381)
			(type default)
		)
		(layer "In3.Cu")
	)
	(gr_arc
		(start 113.81486 -38.200076)
		(mid 114.3 -38.685216)
		(end 114.78514 -38.200076)
		(stroke
			(width 0.2)
			(type default)
		)
		(layer "In3.Cu")
	)
	(gr_line
		(start 113.81486 -36.800028)
		(end 113.81486 -38.200076)
		(stroke
			(width 0.2)
			(type default)
		)
		(layer "In3.Cu")
	)
	(gr_arc
		(start 113.81486 -34.600134)
		(mid 114.3 -35.085274)
		(end 114.78514 -34.600134)
		(stroke
			(width 0.2)
			(type default)
		)
		(layer "In3.Cu")
	)
	(gr_line
		(start 113.81486 -33.200086)
		(end 113.81486 -34.600134)
		(stroke
			(width 0.2)
			(type default)
		)
		(layer "In3.Cu")
	)
	(gr_line
		(start 114.78514 -38.200076)
		(end 114.78514 -36.800282)
		(stroke
			(width 0.2)
			(type default)
		)
		(layer "In3.Cu")
	)
	(gr_arc
		(start 114.78514 -36.800282)
		(mid 114.300127 -36.314888)
		(end 113.81486 -36.800028)
		(stroke
			(width 0.2)
			(type default)
		)
		(layer "In3.Cu")
	)
	(gr_line
		(start 114.78514 -34.600134)
		(end 114.78514 -33.20034)
		(stroke
			(width 0.2)
			(type default)
		)
		(layer "In3.Cu")
	)
	(gr_arc
		(start 114.78514 -33.20034)
		(mid 114.300127 -32.714946)
		(end 113.81486 -33.200086)
		(stroke
			(width 0.2)
			(type default)
		)
		(layer "In3.Cu")
	)
	(gr_arc
		(start 115.614704 -37.00018)
		(mid 116.099844 -37.48532)
		(end 116.584984 -37.00018)
		(stroke
			(width 0.2)
			(type default)
		)
		(layer "In3.Cu")
	)
	(gr_line
		(start 115.614704 -35.600132)
		(end 115.614704 -37.00018)
		(stroke
			(width 0.2)
			(type default)
		)
		(layer "In3.Cu")
	)
	(gr_arc
		(start 115.614704 -33.399984)
		(mid 116.099844 -33.885124)
		(end 116.584984 -33.399984)
		(stroke
			(width 0.2)
			(type default)
		)
		(layer "In3.Cu")
	)
	(gr_line
		(start 115.614704 -32.00019)
		(end 115.614704 -33.399984)
		(stroke
			(width 0.2)
			(type default)
		)
		(layer "In3.Cu")
	)
	(gr_line
		(start 116.584984 -37.00018)
		(end 116.584984 -35.600386)
		(stroke
			(width 0.2)
			(type default)
		)
		(layer "In3.Cu")
	)
	(gr_arc
		(start 116.584984 -35.600386)
		(mid 116.099971 -35.114992)
		(end 115.614704 -35.600132)
		(stroke
			(width 0.2)
			(type default)
		)
		(layer "In3.Cu")
	)
	(gr_line
		(start 116.584984 -33.399984)
		(end 116.584984 -32.000444)
		(stroke
			(width 0.2)
			(type default)
		)
		(layer "In3.Cu")
	)
	(gr_arc
		(start 116.584984 -32.000444)
		(mid 116.099971 -31.51505)
		(end 115.614704 -32.00019)
		(stroke
			(width 0.2)
			(type default)
		)
		(layer "In3.Cu")
	)
	(gr_arc
		(start 117.414802 -38.200076)
		(mid 117.899942 -38.685216)
		(end 118.385082 -38.200076)
		(stroke
			(width 0.2)
			(type default)
		)
		(layer "In3.Cu")
	)
	(gr_line
		(start 117.414802 -36.800028)
		(end 117.414802 -38.200076)
		(stroke
			(width 0.2)
			(type default)
		)
		(layer "In3.Cu")
	)
	(gr_arc
		(start 117.414802 -34.600134)
		(mid 117.899942 -35.085274)
		(end 118.385082 -34.600134)
		(stroke
			(width 0.2)
			(type default)
		)
		(layer "In3.Cu")
	)
	(gr_line
		(start 117.414802 -33.200086)
		(end 117.414802 -34.600134)
		(stroke
			(width 0.2)
			(type default)
		)
		(layer "In3.Cu")
	)
	(gr_line
		(start 117.83568 -10.287)
		(end 118.55958 -11.0109)
		(stroke
			(width 0.381)
			(type default)
		)
		(layer "In3.Cu")
	)
	(gr_line
		(start 118.385082 -38.200076)
		(end 118.385082 -36.800282)
		(stroke
			(width 0.2)
			(type default)
		)
		(layer "In3.Cu")
	)
	(gr_arc
		(start 118.385082 -36.800282)
		(mid 117.900069 -36.314888)
		(end 117.414802 -36.800028)
		(stroke
			(width 0.2)
			(type default)
		)
		(layer "In3.Cu")
	)
	(gr_line
		(start 118.385082 -34.600134)
		(end 118.385082 -33.20034)
		(stroke
			(width 0.2)
			(type default)
		)
		(layer "In3.Cu")
	)
	(gr_arc
		(start 118.385082 -33.20034)
		(mid 117.900069 -32.714946)
		(end 117.414802 -33.200086)
		(stroke
			(width 0.2)
			(type default)
		)
		(layer "In3.Cu")
	)
	(gr_line
		(start 118.55958 -11.0109)
		(end 119.28602 -11.0109)
		(stroke
			(width 0.381)
			(type default)
		)
		(layer "In3.Cu")
	)
	(gr_arc
		(start 119.2149 -37.00018)
		(mid 119.70004 -37.48532)
		(end 120.18518 -37.00018)
		(stroke
			(width 0.2)
			(type default)
		)
		(layer "In3.Cu")
	)
	(gr_line
		(start 119.2149 -35.600132)
		(end 119.2149 -37.00018)
		(stroke
			(width 0.2)
			(type default)
		)
		(layer "In3.Cu")
	)
	(gr_arc
		(start 119.2149 -33.399984)
		(mid 119.70004 -33.885124)
		(end 120.18518 -33.399984)
		(stroke
			(width 0.2)
			(type default)
		)
		(layer "In3.Cu")
	)
	(gr_line
		(start 119.2149 -32.00019)
		(end 119.2149 -33.399984)
		(stroke
			(width 0.2)
			(type default)
		)
		(layer "In3.Cu")
	)
	(gr_line
		(start 119.28602 -11.0109)
		(end 120.00992 -10.287)
		(stroke
			(width 0.381)
			(type default)
		)
		(layer "In3.Cu")
	)
	(gr_line
		(start 120.00992 -10.287)
		(end 128.335024 -10.287)
		(stroke
			(width 0.381)
			(type default)
		)
		(layer "In3.Cu")
	)
	(gr_line
		(start 120.18518 -37.00018)
		(end 120.18518 -35.600386)
		(stroke
			(width 0.2)
			(type default)
		)
		(layer "In3.Cu")
	)
	(gr_arc
		(start 120.18518 -35.600386)
		(mid 119.700167 -35.114992)
		(end 119.2149 -35.600132)
		(stroke
			(width 0.2)
			(type default)
		)
		(layer "In3.Cu")
	)
	(gr_line
		(start 120.18518 -33.399984)
		(end 120.18518 -32.000444)
		(stroke
			(width 0.2)
			(type default)
		)
		(layer "In3.Cu")
	)
	(gr_arc
		(start 120.18518 -32.000444)
		(mid 119.700167 -31.51505)
		(end 119.2149 -32.00019)
		(stroke
			(width 0.2)
			(type default)
		)
		(layer "In3.Cu")
	)
	(gr_line
		(start 121.307352 -46.825154)
		(end 121.307352 -17.28978)
		(stroke
			(width 0.381)
			(type default)
		)
		(layer "In3.Cu")
	)
	(gr_line
		(start 121.307352 -17.28978)
		(end 120.98401 -16.966438)
		(stroke
			(width 0.381)
			(type default)
		)
		(layer "In3.Cu")
	)
	(gr_line
		(start 121.307352 -17.28978)
		(end 121.317512 -17.28978)
		(stroke
			(width 0.381)
			(type default)
		)
		(layer "In3.Cu")
	)
	(gr_line
		(start 121.317512 -17.28978)
		(end 121.621296 -16.985996)
		(stroke
			(width 0.381)
			(type default)
		)
		(layer "In3.Cu")
	)
	(gr_arc
		(start 128.214882 -38.200076)
		(mid 128.700022 -38.685216)
		(end 129.185162 -38.200076)
		(stroke
			(width 0.2)
			(type default)
		)
		(layer "In3.Cu")
	)
	(gr_line
		(start 128.214882 -36.800028)
		(end 128.214882 -38.200076)
		(stroke
			(width 0.2)
			(type default)
		)
		(layer "In3.Cu")
	)
	(gr_arc
		(start 128.214882 -34.600134)
		(mid 128.700022 -35.085274)
		(end 129.185162 -34.600134)
		(stroke
			(width 0.2)
			(type default)
		)
		(layer "In3.Cu")
	)
	(gr_line
		(start 128.214882 -33.200086)
		(end 128.214882 -34.600134)
		(stroke
			(width 0.2)
			(type default)
		)
		(layer "In3.Cu")
	)
	(gr_line
		(start 128.335024 -10.287)
		(end 129.646172 -11.598148)
		(stroke
			(width 0.381)
			(type default)
		)
		(layer "In3.Cu")
	)
	(gr_line
		(start 129.185162 -38.200076)
		(end 129.185162 -36.800282)
		(stroke
			(width 0.2)
			(type default)
		)
		(layer "In3.Cu")
	)
	(gr_arc
		(start 129.185162 -36.800282)
		(mid 128.700149 -36.314888)
		(end 128.214882 -36.800028)
		(stroke
			(width 0.2)
			(type default)
		)
		(layer "In3.Cu")
	)
	(gr_line
		(start 129.185162 -34.600134)
		(end 129.185162 -33.20034)
		(stroke
			(width 0.2)
			(type default)
		)
		(layer "In3.Cu")
	)
	(gr_arc
		(start 129.185162 -33.20034)
		(mid 128.700149 -32.714946)
		(end 128.214882 -33.200086)
		(stroke
			(width 0.2)
			(type default)
		)
		(layer "In3.Cu")
	)
	(gr_line
		(start 129.2606 -16.9672)
		(end 113.4618 -16.9672)
		(stroke
			(width 0.381)
			(type default)
		)
		(layer "In3.Cu")
	)
	(gr_line
		(start 129.646172 -11.598148)
		(end 132.171948 -11.598148)
		(stroke
			(width 0.381)
			(type default)
		)
		(layer "In3.Cu")
	)
	(gr_arc
		(start 130.014726 -37.00018)
		(mid 130.499866 -37.48532)
		(end 130.985006 -37.00018)
		(stroke
			(width 0.2)
			(type default)
		)
		(layer "In3.Cu")
	)
	(gr_line
		(start 130.014726 -35.600132)
		(end 130.014726 -37.00018)
		(stroke
			(width 0.2)
			(type default)
		)
		(layer "In3.Cu")
	)
	(gr_arc
		(start 130.014726 -33.399984)
		(mid 130.499866 -33.885124)
		(end 130.985006 -33.399984)
		(stroke
			(width 0.2)
			(type default)
		)
		(layer "In3.Cu")
	)
	(gr_line
		(start 130.014726 -32.00019)
		(end 130.014726 -33.399984)
		(stroke
			(width 0.2)
			(type default)
		)
		(layer "In3.Cu")
	)
	(gr_line
		(start 130.2512 -15.9766)
		(end 129.2606 -16.9672)
		(stroke
			(width 0.381)
			(type default)
		)
		(layer "In3.Cu")
	)
	(gr_line
		(start 130.985006 -37.00018)
		(end 130.985006 -35.600386)
		(stroke
			(width 0.2)
			(type default)
		)
		(layer "In3.Cu")
	)
	(gr_arc
		(start 130.985006 -35.600386)
		(mid 130.499993 -35.114992)
		(end 130.014726 -35.600132)
		(stroke
			(width 0.2)
			(type default)
		)
		(layer "In3.Cu")
	)
	(gr_line
		(start 130.985006 -33.399984)
		(end 130.985006 -32.000444)
		(stroke
			(width 0.2)
			(type default)
		)
		(layer "In3.Cu")
	)
	(gr_arc
		(start 130.985006 -32.000444)
		(mid 130.499993 -31.51505)
		(end 130.014726 -32.00019)
		(stroke
			(width 0.2)
			(type default)
		)
		(layer "In3.Cu")
	)
	(gr_arc
		(start 131.814824 -38.200076)
		(mid 132.299964 -38.685216)
		(end 132.785104 -38.200076)
		(stroke
			(width 0.2)
			(type default)
		)
		(layer "In3.Cu")
	)
	(gr_line
		(start 131.814824 -36.800028)
		(end 131.814824 -38.200076)
		(stroke
			(width 0.2)
			(type default)
		)
		(layer "In3.Cu")
	)
	(gr_arc
		(start 131.814824 -34.600134)
		(mid 132.299964 -35.085274)
		(end 132.785104 -34.600134)
		(stroke
			(width 0.2)
			(type default)
		)
		(layer "In3.Cu")
	)
	(gr_line
		(start 131.814824 -33.200086)
		(end 131.814824 -34.600134)
		(stroke
			(width 0.2)
			(type default)
		)
		(layer "In3.Cu")
	)
	(gr_line
		(start 132.171948 -11.598148)
		(end 134.372096 -9.398)
		(stroke
			(width 0.381)
			(type default)
		)
		(layer "In3.Cu")
	)
	(gr_line
		(start 132.3086 -15.9766)
		(end 130.2512 -15.9766)
		(stroke
			(width 0.381)
			(type default)
		)
		(layer "In3.Cu")
	)
	(gr_line
		(start 132.785104 -38.200076)
		(end 132.785104 -36.800282)
		(stroke
			(width 0.2)
			(type default)
		)
		(layer "In3.Cu")
	)
	(gr_arc
		(start 132.785104 -36.800282)
		(mid 132.300091 -36.314888)
		(end 131.814824 -36.800028)
		(stroke
			(width 0.2)
			(type default)
		)
		(layer "In3.Cu")
	)
	(gr_line
		(start 132.785104 -34.600134)
		(end 132.785104 -33.20034)
		(stroke
			(width 0.2)
			(type default)
		)
		(layer "In3.Cu")
	)
	(gr_arc
		(start 132.785104 -33.20034)
		(mid 132.300091 -32.714946)
		(end 131.814824 -33.200086)
		(stroke
			(width 0.2)
			(type default)
		)
		(layer "In3.Cu")
	)
	(gr_line
		(start 133.5913 -14.6939)
		(end 132.3086 -15.9766)
		(stroke
			(width 0.381)
			(type default)
		)
		(layer "In3.Cu")
	)
	(gr_arc
		(start 133.614922 -37.00018)
		(mid 134.100062 -37.48532)
		(end 134.585202 -37.00018)
		(stroke
			(width 0.2)
			(type default)
		)
		(layer "In3.Cu")
	)
	(gr_line
		(start 133.614922 -35.600132)
		(end 133.614922 -37.00018)
		(stroke
			(width 0.2)
			(type default)
		)
		(layer "In3.Cu")
	)
	(gr_arc
		(start 133.614922 -33.399984)
		(mid 134.100062 -33.885124)
		(end 134.585202 -33.399984)
		(stroke
			(width 0.2)
			(type default)
		)
		(layer "In3.Cu")
	)
	(gr_line
		(start 133.614922 -32.00019)
		(end 133.614922 -33.399984)
		(stroke
			(width 0.2)
			(type default)
		)
		(layer "In3.Cu")
	)
	(gr_line
		(start 134.372096 -9.398)
		(end 148.971 -9.398)
		(stroke
			(width 0.381)
			(type default)
		)
		(layer "In3.Cu")
	)
	(gr_line
		(start 134.585202 -37.00018)
		(end 134.585202 -35.600386)
		(stroke
			(width 0.2)
			(type default)
		)
		(layer "In3.Cu")
	)
	(gr_arc
		(start 134.585202 -35.600386)
		(mid 134.100189 -35.114992)
		(end 133.614922 -35.600132)
		(stroke
			(width 0.2)
			(type default)
		)
		(layer "In3.Cu")
	)
	(gr_line
		(start 134.585202 -33.399984)
		(end 134.585202 -32.000444)
		(stroke
			(width 0.2)
			(type default)
		)
		(layer "In3.Cu")
	)
	(gr_arc
		(start 134.585202 -32.000444)
		(mid 134.100189 -31.51505)
		(end 133.614922 -32.00019)
		(stroke
			(width 0.2)
			(type default)
		)
		(layer "In3.Cu")
	)
	(gr_line
		(start 135.057642 -46.77029)
		(end 135.057642 -30.571186)
		(stroke
			(width 0.381)
			(type default)
		)
		(layer "In3.Cu")
	)
	(gr_line
		(start 135.057642 -30.571186)
		(end 135.804656 -29.824172)
		(stroke
			(width 0.381)
			(type default)
		)
		(layer "In3.Cu")
	)
	(gr_arc
		(start 135.414766 -38.200076)
		(mid 135.899906 -38.685216)
		(end 136.385046 -38.200076)
		(stroke
			(width 0.2)
			(type default)
		)
		(layer "In3.Cu")
	)
	(gr_line
		(start 135.414766 -36.800028)
		(end 135.414766 -38.200076)
		(stroke
			(width 0.2)
			(type default)
		)
		(layer "In3.Cu")
	)
	(gr_arc
		(start 135.414766 -34.600134)
		(mid 135.899906 -35.085274)
		(end 136.385046 -34.600134)
		(stroke
			(width 0.2)
			(type default)
		)
		(layer "In3.Cu")
	)
	(gr_line
		(start 135.414766 -33.200086)
		(end 135.414766 -34.600134)
		(stroke
			(width 0.2)
			(type default)
		)
		(layer "In3.Cu")
	)
	(gr_line
		(start 135.804656 -29.824172)
		(end 144.538192 -29.824172)
		(stroke
			(width 0.381)
			(type default)
		)
		(layer "In3.Cu")
	)
	(gr_line
		(start 136.385046 -38.200076)
		(end 136.385046 -36.800282)
		(stroke
			(width 0.2)
			(type default)
		)
		(layer "In3.Cu")
	)
	(gr_arc
		(start 136.385046 -36.800282)
		(mid 135.900033 -36.314888)
		(end 135.414766 -36.800028)
		(stroke
			(width 0.2)
			(type default)
		)
		(layer "In3.Cu")
	)
	(gr_line
		(start 136.385046 -34.600134)
		(end 136.385046 -33.20034)
		(stroke
			(width 0.2)
			(type default)
		)
		(layer "In3.Cu")
	)
	(gr_arc
		(start 136.385046 -33.20034)
		(mid 135.900033 -32.714946)
		(end 135.414766 -33.200086)
		(stroke
			(width 0.2)
			(type default)
		)
		(layer "In3.Cu")
	)
	(gr_arc
		(start 137.214864 -37.00018)
		(mid 137.700004 -37.48532)
		(end 138.185144 -37.00018)
		(stroke
			(width 0.2)
			(type default)
		)
		(layer "In3.Cu")
	)
	(gr_line
		(start 137.214864 -35.600132)
		(end 137.214864 -37.00018)
		(stroke
			(width 0.2)
			(type default)
		)
		(layer "In3.Cu")
	)
	(gr_arc
		(start 137.214864 -33.399984)
		(mid 137.700004 -33.885124)
		(end 138.185144 -33.399984)
		(stroke
			(width 0.2)
			(type default)
		)
		(layer "In3.Cu")
	)
	(gr_line
		(start 137.214864 -32.00019)
		(end 137.214864 -33.399984)
		(stroke
			(width 0.2)
			(type default)
		)
		(layer "In3.Cu")
	)
	(gr_line
		(start 138.185144 -37.00018)
		(end 138.185144 -35.600386)
		(stroke
			(width 0.2)
			(type default)
		)
		(layer "In3.Cu")
	)
	(gr_arc
		(start 138.185144 -35.600386)
		(mid 137.700131 -35.114992)
		(end 137.214864 -35.600132)
		(stroke
			(width 0.2)
			(type default)
		)
		(layer "In3.Cu")
	)
	(gr_line
		(start 138.185144 -33.399984)
		(end 138.185144 -32.000444)
		(stroke
			(width 0.2)
			(type default)
		)
		(layer "In3.Cu")
	)
	(gr_arc
		(start 138.185144 -32.000444)
		(mid 137.700131 -31.51505)
		(end 137.214864 -32.00019)
		(stroke
			(width 0.2)
			(type default)
		)
		(layer "In3.Cu")
	)
	(gr_arc
		(start 139.014708 -38.200076)
		(mid 139.499848 -38.685216)
		(end 139.984988 -38.200076)
		(stroke
			(width 0.2)
			(type default)
		)
		(layer "In3.Cu")
	)
	(gr_line
		(start 139.014708 -36.800028)
		(end 139.014708 -38.200076)
		(stroke
			(width 0.2)
			(type default)
		)
		(layer "In3.Cu")
	)
	(gr_arc
		(start 139.014708 -34.600134)
		(mid 139.499848 -35.085274)
		(end 139.984988 -34.600134)
		(stroke
			(width 0.2)
			(type default)
		)
		(layer "In3.Cu")
	)
	(gr_line
		(start 139.014708 -33.200086)
		(end 139.014708 -34.600134)
		(stroke
			(width 0.2)
			(type default)
		)
		(layer "In3.Cu")
	)
	(gr_line
		(start 139.984988 -38.200076)
		(end 139.984988 -36.800282)
		(stroke
			(width 0.2)
			(type default)
		)
		(layer "In3.Cu")
	)
	(gr_arc
		(start 139.984988 -36.800282)
		(mid 139.499975 -36.314888)
		(end 139.014708 -36.800028)
		(stroke
			(width 0.2)
			(type default)
		)
		(layer "In3.Cu")
	)
	(gr_line
		(start 139.984988 -34.600134)
		(end 139.984988 -33.20034)
		(stroke
			(width 0.2)
			(type default)
		)
		(layer "In3.Cu")
	)
	(gr_arc
		(start 139.984988 -33.20034)
		(mid 139.499975 -32.714946)
		(end 139.014708 -33.200086)
		(stroke
			(width 0.2)
			(type default)
		)
		(layer "In3.Cu")
	)
	(gr_arc
		(start 140.814806 -37.00018)
		(mid 141.299946 -37.48532)
		(end 141.785086 -37.00018)
		(stroke
			(width 0.2)
			(type default)
		)
		(layer "In3.Cu")
	)
	(gr_line
		(start 140.814806 -35.600132)
		(end 140.814806 -37.00018)
		(stroke
			(width 0.2)
			(type default)
		)
		(layer "In3.Cu")
	)
	(gr_arc
		(start 140.814806 -33.399984)
		(mid 141.299946 -33.885124)
		(end 141.785086 -33.399984)
		(stroke
			(width 0.2)
			(type default)
		)
		(layer "In3.Cu")
	)
	(gr_line
		(start 140.814806 -32.00019)
		(end 140.814806 -33.399984)
		(stroke
			(width 0.2)
			(type default)
		)
		(layer "In3.Cu")
	)
	(gr_line
		(start 140.9319 -14.6939)
		(end 133.5913 -14.6939)
		(stroke
			(width 0.381)
			(type default)
		)
		(layer "In3.Cu")
	)
	(gr_line
		(start 141.785086 -37.00018)
		(end 141.785086 -35.600386)
		(stroke
			(width 0.2)
			(type default)
		)
		(layer "In3.Cu")
	)
	(gr_arc
		(start 141.785086 -35.600386)
		(mid 141.300073 -35.114992)
		(end 140.814806 -35.600132)
		(stroke
			(width 0.2)
			(type default)
		)
		(layer "In3.Cu")
	)
	(gr_line
		(start 141.785086 -33.399984)
		(end 141.785086 -32.000444)
		(stroke
			(width 0.2)
			(type default)
		)
		(layer "In3.Cu")
	)
	(gr_arc
		(start 141.785086 -32.000444)
		(mid 141.300073 -31.51505)
		(end 140.814806 -32.00019)
		(stroke
			(width 0.2)
			(type default)
		)
		(layer "In3.Cu")
	)
	(gr_line
		(start 141.99997 -47.999904)
		(end 143.999966 -47.999904)
		(stroke
			(width 0.381)
			(type default)
		)
		(layer "In3.Cu")
	)
	(gr_line
		(start 143.299942 -47.999904)
		(end 104.70007 -47.999904)
		(stroke
			(width 2.54)
			(type default)
		)
		(layer "In3.Cu")
	)
	(gr_line
		(start 143.4338 -125.349)
		(end 143.2306 -125.1458)
		(stroke
			(width 0.381)
			(type default)
		)
		(layer "In3.Cu")
	)
	(gr_line
		(start 143.4592 -104.775)
		(end 143.4338 -104.7496)
		(stroke
			(width 0.381)
			(type default)
		)
		(layer "In3.Cu")
	)
	(gr_line
		(start 143.999966 -47.999904)
		(end 144.78 -47.21987)
		(stroke
			(width 0.381)
			(type default)
		)
		(layer "In3.Cu")
	)
	(gr_line
		(start 144.29994 -183.76392)
		(end 144.29994 -47.999904)
		(stroke
			(width 2.54)
			(type default)
		)
		(layer "In3.Cu")
	)
	(gr_arc
		(start 144.29994 -183.76392)
		(mid 144.326755 -183.993712)
		(end 144.405604 -184.211214)
		(stroke
			(width 2.54)
			(type default)
		)
		(layer "In3.Cu")
	)
	(gr_arc
		(start 144.29994 -47.999904)
		(mid 143.800068 -47.500032)
		(end 143.299942 -47.999904)
		(stroke
			(width 2.54)
			(type default)
		)
		(layer "In3.Cu")
	)
	(gr_line
		(start 144.538192 -29.830776)
		(end 144.787366 -30.07995)
		(stroke
			(width 0.381)
			(type default)
		)
		(layer "In3.Cu")
	)
	(gr_line
		(start 144.538192 -29.824172)
		(end 144.538192 -29.830776)
		(stroke
			(width 0.381)
			(type default)
		)
		(layer "In3.Cu")
	)
	(gr_line
		(start 144.538192 -29.824172)
		(end 144.740376 -29.621988)
		(stroke
			(width 0.381)
			(type default)
		)
		(layer "In3.Cu")
	)
	(gr_line
		(start 144.78 -47.21987)
		(end 144.78 -18.542)
		(stroke
			(width 0.381)
			(type default)
		)
		(layer "In3.Cu")
	)
	(gr_line
		(start 144.78 -18.542)
		(end 140.9319 -14.6939)
		(stroke
			(width 0.381)
			(type default)
		)
		(layer "In3.Cu")
	)
	(gr_line
		(start 145.8214 -125.349)
		(end 145.1864 -124.714)
		(stroke
			(width 0.381)
			(type default)
		)
		(layer "In3.Cu")
	)
	(gr_line
		(start 145.8468 -125.5268)
		(end 145.0086 -126.365)
		(stroke
			(width 0.381)
			(type default)
		)
		(layer "In3.Cu")
	)
	(gr_line
		(start 148.971 -9.398)
		(end 150.622 -11.049)
		(stroke
			(width 0.381)
			(type default)
		)
		(layer "In3.Cu")
	)
	(gr_line
		(start 149.023578 -193.447162)
		(end 144.405604 -184.211214)
		(stroke
			(width 2.54)
			(type default)
		)
		(layer "In3.Cu")
	)
	(gr_arc
		(start 149.023578 -193.447162)
		(mid 149.392225 -193.85063)
		(end 149.917912 -194.00012)
		(stroke
			(width 2.54)
			(type default)
		)
		(layer "In3.Cu")
	)
	(gr_circle
		(center 149.9362 -145.8976)
		(end 150.82774 -145.8976)
		(stroke
			(width 0.2)
			(type default)
		)
		(fill no)
		(layer "In3.Cu")
	)
	(gr_line
		(start 150.622 -75.184)
		(end 165.608 -90.17)
		(stroke
			(width 0.381)
			(type default)
		)
		(layer "In3.Cu")
	)
	(gr_line
		(start 150.622 -11.557)
		(end 151.0792 -11.0998)
		(stroke
			(width 0.381)
			(type default)
		)
		(layer "In3.Cu")
	)
	(gr_line
		(start 150.622 -11.049)
		(end 150.622 -75.184)
		(stroke
			(width 0.381)
			(type default)
		)
		(layer "In3.Cu")
	)
	(gr_line
		(start 150.622 -11.049)
		(end 188.1124 -11.049)
		(stroke
			(width 0.381)
			(type default)
		)
		(layer "In3.Cu")
	)
	(gr_line
		(start 150.7236 -40.6146)
		(end 150.749 -40.6146)
		(stroke
			(width 0.381)
			(type default)
		)
		(layer "In3.Cu")
	)
	(gr_line
		(start 150.749 -40.6146)
		(end 151.2316 -40.132)
		(stroke
			(width 0.381)
			(type default)
		)
		(layer "In3.Cu")
	)
	(gr_line
		(start 151.2316 -40.132)
		(end 150.7236 -39.624)
		(stroke
			(width 0.381)
			(type default)
		)
		(layer "In3.Cu")
	)
	(gr_arc
		(start 158.833566 -30.277054)
		(mid 159.027114 -30.916626)
		(end 159.666686 -30.723078)
		(stroke
			(width 0.2)
			(type default)
		)
		(layer "In3.Cu")
	)
	(gr_arc
		(start 158.833566 -26.47696)
		(mid 159.027114 -27.116532)
		(end 159.666686 -26.922984)
		(stroke
			(width 0.2)
			(type default)
		)
		(layer "In3.Cu")
	)
	(gr_arc
		(start 158.833566 -18.877026)
		(mid 159.027114 -19.516598)
		(end 159.666686 -19.32305)
		(stroke
			(width 0.2)
			(type default)
		)
		(layer "In3.Cu")
	)
	(gr_arc
		(start 158.836614 -22.671278)
		(mid 159.024316 -23.31492)
		(end 159.666686 -23.12289)
		(stroke
			(width 0.2)
			(type default)
		)
		(layer "In3.Cu")
	)
	(gr_line
		(start 159.583374 -28.877006)
		(end 158.833566 -30.277054)
		(stroke
			(width 0.2)
			(type default)
		)
		(layer "In3.Cu")
	)
	(gr_line
		(start 159.583374 -25.076912)
		(end 158.833566 -26.47696)
		(stroke
			(width 0.2)
			(type default)
		)
		(layer "In3.Cu")
	)
	(gr_line
		(start 159.583374 -21.277072)
		(end 158.836614 -22.671278)
		(stroke
			(width 0.2)
			(type default)
		)
		(layer "In3.Cu")
	)
	(gr_line
		(start 159.583374 -17.476978)
		(end 158.833566 -18.877026)
		(stroke
			(width 0.2)
			(type default)
		)
		(layer "In3.Cu")
	)
	(gr_line
		(start 159.666686 -30.723078)
		(end 160.413446 -29.328618)
		(stroke
			(width 0.2)
			(type default)
		)
		(layer "In3.Cu")
	)
	(gr_line
		(start 159.666686 -26.922984)
		(end 160.413446 -25.528524)
		(stroke
			(width 0.2)
			(type default)
		)
		(layer "In3.Cu")
	)
	(gr_line
		(start 159.666686 -23.12289)
		(end 160.416494 -21.723096)
		(stroke
			(width 0.2)
			(type default)
		)
		(layer "In3.Cu")
	)
	(gr_line
		(start 159.666686 -19.32305)
		(end 160.413446 -17.92859)
		(stroke
			(width 0.2)
			(type default)
		)
		(layer "In3.Cu")
	)
	(gr_arc
		(start 160.413446 -29.328618)
		(mid 160.225744 -28.684976)
		(end 159.583374 -28.877006)
		(stroke
			(width 0.2)
			(type default)
		)
		(layer "In3.Cu")
	)
	(gr_arc
		(start 160.413446 -25.528524)
		(mid 160.225744 -24.884882)
		(end 159.583374 -25.076912)
		(stroke
			(width 0.2)
			(type default)
		)
		(layer "In3.Cu")
	)
	(gr_arc
		(start 160.413446 -17.92859)
		(mid 160.225744 -17.284948)
		(end 159.583374 -17.476978)
		(stroke
			(width 0.2)
			(type default)
		)
		(layer "In3.Cu")
	)
	(gr_arc
		(start 160.416494 -21.723096)
		(mid 160.222946 -21.083524)
		(end 159.583374 -21.277072)
		(stroke
			(width 0.2)
			(type default)
		)
		(layer "In3.Cu")
	)
	(gr_line
		(start 161.081466 -22.675596)
		(end 161.083752 -22.676866)
		(stroke
			(width 0.2)
			(type default)
		)
		(layer "In3.Cu")
	)
	(gr_arc
		(start 161.083498 -30.277054)
		(mid 161.277046 -30.916626)
		(end 161.916618 -30.723078)
		(stroke
			(width 0.2)
			(type default)
		)
		(layer "In3.Cu")
	)
	(gr_arc
		(start 161.083498 -26.47696)
		(mid 161.277046 -27.116532)
		(end 161.916618 -26.922984)
		(stroke
			(width 0.2)
			(type default)
		)
		(layer "In3.Cu")
	)
	(gr_arc
		(start 161.083498 -18.877026)
		(mid 161.277046 -19.516598)
		(end 161.916618 -19.32305)
		(stroke
			(width 0.2)
			(type default)
		)
		(layer "In3.Cu")
	)
	(gr_arc
		(start 161.083752 -22.676866)
		(mid 161.277046 -23.316184)
		(end 161.916364 -23.12289)
		(stroke
			(width 0.2)
			(type default)
		)
		(layer "In3.Cu")
	)
	(gr_line
		(start 161.831528 -21.275802)
		(end 161.081466 -22.675596)
		(stroke
			(width 0.2)
			(type default)
		)
		(layer "In3.Cu")
	)
	(gr_line
		(start 161.83356 -28.877006)
		(end 161.083498 -30.277054)
		(stroke
			(width 0.2)
			(type default)
		)
		(layer "In3.Cu")
	)
	(gr_line
		(start 161.83356 -25.076912)
		(end 161.083498 -26.47696)
		(stroke
			(width 0.2)
			(type default)
		)
		(layer "In3.Cu")
	)
	(gr_line
		(start 161.83356 -17.476978)
		(end 161.083498 -18.877026)
		(stroke
			(width 0.2)
			(type default)
		)
		(layer "In3.Cu")
	)
	(gr_line
		(start 161.833814 -21.277072)
		(end 161.831528 -21.275802)
		(stroke
			(width 0.2)
			(type default)
		)
		(layer "In3.Cu")
	)
	(gr_line
		(start 161.916364 -23.12289)
		(end 161.91865 -23.12416)
		(stroke
			(width 0.2)
			(type default)
		)
		(layer "In3.Cu")
	)
	(gr_line
		(start 161.916618 -30.723078)
		(end 162.663632 -29.328618)
		(stroke
			(width 0.2)
			(type default)
		)
		(layer "In3.Cu")
	)
	(gr_line
		(start 161.916618 -26.922984)
		(end 162.663632 -25.528524)
		(stroke
			(width 0.2)
			(type default)
		)
		(layer "In3.Cu")
	)
	(gr_line
		(start 161.916618 -19.32305)
		(end 162.663632 -17.92859)
		(stroke
			(width 0.2)
			(type default)
		)
		(layer "In3.Cu")
	)
	(gr_line
		(start 161.91865 -23.12416)
		(end 162.668712 -21.72462)
		(stroke
			(width 0.2)
			(type default)
		)
		(layer "In3.Cu")
	)
	(gr_arc
		(start 162.663632 -29.328618)
		(mid 162.47593 -28.684976)
		(end 161.83356 -28.877006)
		(stroke
			(width 0.2)
			(type default)
		)
		(layer "In3.Cu")
	)
	(gr_arc
		(start 162.663632 -25.528524)
		(mid 162.47593 -24.884882)
		(end 161.83356 -25.076912)
		(stroke
			(width 0.2)
			(type default)
		)
		(layer "In3.Cu")
	)
	(gr_arc
		(start 162.663632 -17.92859)
		(mid 162.47593 -17.284948)
		(end 161.83356 -17.476978)
		(stroke
			(width 0.2)
			(type default)
		)
		(layer "In3.Cu")
	)
	(gr_arc
		(start 162.666426 -21.72335)
		(mid 162.473287 -21.083725)
		(end 161.833814 -21.277072)
		(stroke
			(width 0.2)
			(type default)
		)
		(layer "In3.Cu")
	)
	(gr_line
		(start 162.668458 -21.724366)
		(end 162.666426 -21.72335)
		(stroke
			(width 0.2)
			(type default)
		)
		(layer "In3.Cu")
	)
	(gr_line
		(start 162.668712 -21.72462)
		(end 162.668458 -21.724366)
		(stroke
			(width 0.2)
			(type default)
		)
		(layer "In3.Cu")
	)
	(gr_line
		(start 164.192204 -125.349)
		(end 143.4338 -125.349)
		(stroke
			(width 0.381)
			(type default)
		)
		(layer "In3.Cu")
	)
	(gr_line
		(start 164.2872 -146.631406)
		(end 164.2872 -125.443996)
		(stroke
			(width 0.381)
			(type default)
		)
		(layer "In3.Cu")
	)
	(gr_line
		(start 164.2872 -125.9078)
		(end 163.8046 -125.4252)
		(stroke
			(width 0.381)
			(type default)
		)
		(layer "In3.Cu")
	)
	(gr_line
		(start 164.2872 -125.443996)
		(end 164.192204 -125.349)
		(stroke
			(width 0.381)
			(type default)
		)
		(layer "In3.Cu")
	)
	(gr_line
		(start 164.2872 -125.443996)
		(end 165.608 -124.123196)
		(stroke
			(width 0.381)
			(type default)
		)
		(layer "In3.Cu")
	)
	(gr_line
		(start 165.608 -124.123196)
		(end 165.608 -114.0968)
		(stroke
			(width 0.381)
			(type default)
		)
		(layer "In3.Cu")
	)
	(gr_line
		(start 165.608 -114.0968)
		(end 175.9712 -114.0968)
		(stroke
			(width 0.381)
			(type default)
		)
		(layer "In3.Cu")
	)
	(gr_line
		(start 165.608 -90.17)
		(end 165.608 -114.0968)
		(stroke
			(width 0.381)
			(type default)
		)
		(layer "In3.Cu")
	)
	(gr_line
		(start 165.68166 -114.62512)
		(end 166.18966 -114.11712)
		(stroke
			(width 0.381)
			(type default)
		)
		(layer "In3.Cu")
	)
	(gr_line
		(start 166.18966 -114.11712)
		(end 165.68166 -113.60912)
		(stroke
			(width 0.381)
			(type default)
		)
		(layer "In3.Cu")
	)
	(gr_line
		(start 175.6283 -157.972506)
		(end 164.2872 -146.631406)
		(stroke
			(width 0.381)
			(type default)
		)
		(layer "In3.Cu")
	)
	(gr_line
		(start 175.9712 -114.0968)
		(end 176.657 -113.411)
		(stroke
			(width 0.381)
			(type default)
		)
		(layer "In3.Cu")
	)
	(gr_line
		(start 176.657 -113.411)
		(end 176.657 -105.664)
		(stroke
			(width 0.381)
			(type default)
		)
		(layer "In3.Cu")
	)
	(gr_line
		(start 176.657 -105.664)
		(end 180.973222 -101.347778)
		(stroke
			(width 0.381)
			(type default)
		)
		(layer "In3.Cu")
	)
	(gr_arc
		(start 178.811174 -26.465022)
		(mid 179.015136 -27.138884)
		(end 179.688998 -26.934922)
		(stroke
			(width 0.2)
			(type default)
		)
		(layer "In3.Cu")
	)
	(gr_arc
		(start 178.833526 -30.277054)
		(mid 179.027074 -30.916626)
		(end 179.666646 -30.723078)
		(stroke
			(width 0.2)
			(type default)
		)
		(layer "In3.Cu")
	)
	(gr_arc
		(start 178.833526 -18.877026)
		(mid 179.027074 -19.516598)
		(end 179.666646 -19.32305)
		(stroke
			(width 0.2)
			(type default)
		)
		(layer "In3.Cu")
	)
	(gr_arc
		(start 178.836574 -22.671278)
		(mid 179.024276 -23.31492)
		(end 179.666646 -23.12289)
		(stroke
			(width 0.2)
			(type default)
		)
		(layer "In3.Cu")
	)
	(gr_line
		(start 179.560982 -25.064974)
		(end 178.811174 -26.465022)
		(stroke
			(width 0.2)
			(type default)
		)
		(layer "In3.Cu")
	)
	(gr_line
		(start 179.583334 -28.877006)
		(end 178.833526 -30.277054)
		(stroke
			(width 0.2)
			(type default)
		)
		(layer "In3.Cu")
	)
	(gr_line
		(start 179.583334 -21.277072)
		(end 178.836574 -22.671278)
		(stroke
			(width 0.2)
			(type default)
		)
		(layer "In3.Cu")
	)
	(gr_line
		(start 179.583334 -17.476978)
		(end 178.833526 -18.877026)
		(stroke
			(width 0.2)
			(type default)
		)
		(layer "In3.Cu")
	)
	(gr_line
		(start 179.666646 -30.723078)
		(end 180.413406 -29.328618)
		(stroke
			(width 0.2)
			(type default)
		)
		(layer "In3.Cu")
	)
	(gr_line
		(start 179.666646 -23.12289)
		(end 180.416454 -21.723096)
		(stroke
			(width 0.2)
			(type default)
		)
		(layer "In3.Cu")
	)
	(gr_line
		(start 179.666646 -19.32305)
		(end 180.413406 -17.92859)
		(stroke
			(width 0.2)
			(type default)
		)
		(layer "In3.Cu")
	)
	(gr_line
		(start 179.688998 -26.934922)
		(end 180.43398 -25.543764)
		(stroke
			(width 0.2)
			(type default)
		)
		(layer "In3.Cu")
	)
	(gr_arc
		(start 180.413406 -29.328618)
		(mid 180.225704 -28.684976)
		(end 179.583334 -28.877006)
		(stroke
			(width 0.2)
			(type default)
		)
		(layer "In3.Cu")
	)
	(gr_arc
		(start 180.413406 -17.92859)
		(mid 180.225704 -17.284948)
		(end 179.583334 -17.476978)
		(stroke
			(width 0.2)
			(type default)
		)
		(layer "In3.Cu")
	)
	(gr_arc
		(start 180.416454 -21.723096)
		(mid 180.222906 -21.083524)
		(end 179.583334 -21.277072)
		(stroke
			(width 0.2)
			(type default)
		)
		(layer "In3.Cu")
	)
	(gr_arc
		(start 180.43398 -25.543764)
		(mid 180.239312 -24.863383)
		(end 179.560982 -25.064974)
		(stroke
			(width 0.2)
			(type default)
		)
		(layer "In3.Cu")
	)
	(gr_line
		(start 180.973222 -101.347778)
		(end 191.643 -101.347778)
		(stroke
			(width 0.381)
			(type default)
		)
		(layer "In3.Cu")
	)
	(gr_arc
		(start 181.061106 -26.464768)
		(mid 181.264814 -27.138884)
		(end 181.93893 -26.935176)
		(stroke
			(width 0.2)
			(type default)
		)
		(layer "In3.Cu")
	)
	(gr_line
		(start 181.081426 -22.675596)
		(end 181.083712 -22.676866)
		(stroke
			(width 0.2)
			(type default)
		)
		(layer "In3.Cu")
	)
	(gr_arc
		(start 181.083458 -30.277054)
		(mid 181.277006 -30.916626)
		(end 181.916578 -30.723078)
		(stroke
			(width 0.2)
			(type default)
		)
		(layer "In3.Cu")
	)
	(gr_arc
		(start 181.083458 -18.877026)
		(mid 181.277006 -19.516598)
		(end 181.916578 -19.32305)
		(stroke
			(width 0.2)
			(type default)
		)
		(layer "In3.Cu")
	)
	(gr_arc
		(start 181.083712 -22.676866)
		(mid 181.277006 -23.316184)
		(end 181.916324 -23.12289)
		(stroke
			(width 0.2)
			(type default)
		)
		(layer "In3.Cu")
	)
	(gr_line
		(start 181.811168 -25.06472)
		(end 181.061106 -26.464768)
		(stroke
			(width 0.2)
			(type default)
		)
		(layer "In3.Cu")
	)
	(gr_line
		(start 181.831488 -21.275802)
		(end 181.081426 -22.675596)
		(stroke
			(width 0.2)
			(type default)
		)
		(layer "In3.Cu")
	)
	(gr_line
		(start 181.83352 -28.877006)
		(end 181.083458 -30.277054)
		(stroke
			(width 0.2)
			(type default)
		)
		(layer "In3.Cu")
	)
	(gr_line
		(start 181.83352 -17.476978)
		(end 181.083458 -18.877026)
		(stroke
			(width 0.2)
			(type default)
		)
		(layer "In3.Cu")
	)
	(gr_line
		(start 181.833774 -21.277072)
		(end 181.831488 -21.275802)
		(stroke
			(width 0.2)
			(type default)
		)
		(layer "In3.Cu")
	)
	(gr_line
		(start 181.864 -82.5881)
		(end 181.864 -81.5086)
		(stroke
			(width 0.381)
			(type default)
		)
		(layer "In3.Cu")
	)
	(gr_line
		(start 181.864 -81.5086)
		(end 182.2704 -81.1022)
		(stroke
			(width 0.381)
			(type default)
		)
		(layer "In3.Cu")
	)
	(gr_line
		(start 181.916324 -23.12289)
		(end 181.91861 -23.12416)
		(stroke
			(width 0.2)
			(type default)
		)
		(layer "In3.Cu")
	)
	(gr_line
		(start 181.916578 -30.723078)
		(end 182.663592 -29.328618)
		(stroke
			(width 0.2)
			(type default)
		)
		(layer "In3.Cu")
	)
	(gr_line
		(start 181.916578 -19.32305)
		(end 182.663592 -17.92859)
		(stroke
			(width 0.2)
			(type default)
		)
		(layer "In3.Cu")
	)
	(gr_line
		(start 181.91861 -23.12416)
		(end 182.668672 -21.72462)
		(stroke
			(width 0.2)
			(type default)
		)
		(layer "In3.Cu")
	)
	(gr_line
		(start 181.93893 -26.935176)
		(end 182.684166 -25.543764)
		(stroke
			(width 0.2)
			(type default)
		)
		(layer "In3.Cu")
	)
	(gr_line
		(start 182.2704 -81.1022)
		(end 186.0042 -81.1022)
		(stroke
			(width 0.381)
			(type default)
		)
		(layer "In3.Cu")
	)
	(gr_arc
		(start 182.663592 -29.328618)
		(mid 182.47589 -28.684976)
		(end 181.83352 -28.877006)
		(stroke
			(width 0.2)
			(type default)
		)
		(layer "In3.Cu")
	)
	(gr_arc
		(start 182.663592 -17.92859)
		(mid 182.47589 -17.284948)
		(end 181.83352 -17.476978)
		(stroke
			(width 0.2)
			(type default)
		)
		(layer "In3.Cu")
	)
	(gr_arc
		(start 182.666386 -21.72335)
		(mid 182.473247 -21.083725)
		(end 181.833774 -21.277072)
		(stroke
			(width 0.2)
			(type default)
		)
		(layer "In3.Cu")
	)
	(gr_line
		(start 182.668418 -21.724366)
		(end 182.666386 -21.72335)
		(stroke
			(width 0.2)
			(type default)
		)
		(layer "In3.Cu")
	)
	(gr_line
		(start 182.668672 -21.72462)
		(end 182.668418 -21.724366)
		(stroke
			(width 0.2)
			(type default)
		)
		(layer "In3.Cu")
	)
	(gr_arc
		(start 182.684166 -25.543764)
		(mid 182.489596 -24.863437)
		(end 181.811168 -25.06472)
		(stroke
			(width 0.2)
			(type default)
		)
		(layer "In3.Cu")
	)
	(gr_line
		(start 185.1406 -72.0344)
		(end 185.1406 -57.5056)
		(stroke
			(width 0.381)
			(type default)
		)
		(layer "In3.Cu")
	)
	(gr_line
		(start 185.1406 -57.5056)
		(end 185.674 -56.9722)
		(stroke
			(width 0.381)
			(type default)
		)
		(layer "In3.Cu")
	)
	(gr_line
		(start 185.674 -56.9722)
		(end 190.754 -56.9722)
		(stroke
			(width 0.381)
			(type default)
		)
		(layer "In3.Cu")
	)
	(gr_line
		(start 185.7502 -72.644)
		(end 185.1406 -72.0344)
		(stroke
			(width 0.381)
			(type default)
		)
		(layer "In3.Cu")
	)
	(gr_line
		(start 186.0042 -81.1022)
		(end 190.9826 -76.1238)
		(stroke
			(width 0.381)
			(type default)
		)
		(layer "In3.Cu")
	)
	(gr_line
		(start 188.1124 -11.049)
		(end 193.4972 -16.4338)
		(stroke
			(width 0.381)
			(type default)
		)
		(layer "In3.Cu")
	)
	(gr_line
		(start 189.103 -101.346)
		(end 189.611 -101.854)
		(stroke
			(width 0.381)
			(type default)
		)
		(layer "In3.Cu")
	)
	(gr_arc
		(start 189.286134 -84.241132)
		(mid 189.279055 -84.782246)
		(end 189.820296 -84.784692)
		(stroke
			(width 0.2)
			(type default)
		)
		(layer "In3.Cu")
	)
	(gr_line
		(start 189.611 -111.379)
		(end 189.611 -101.34981)
		(stroke
			(width 0.381)
			(type default)
		)
		(layer "In3.Cu")
	)
	(gr_line
		(start 189.611 -101.854)
		(end 190.119 -101.346)
		(stroke
			(width 0.381)
			(type default)
		)
		(layer "In3.Cu")
	)
	(gr_line
		(start 189.611 -101.34981)
		(end 189.613032 -101.347778)
		(stroke
			(width 0.381)
			(type default)
		)
		(layer "In3.Cu")
	)
	(gr_line
		(start 189.820296 -84.784692)
		(end 190.448692 -84.156296)
		(stroke
			(width 0.2)
			(type default)
		)
		(layer "In3.Cu")
	)
	(gr_line
		(start 189.909704 -83.617308)
		(end 189.286134 -84.241132)
		(stroke
			(width 0.2)
			(type default)
		)
		(layer "In3.Cu")
	)
	(gr_arc
		(start 190.448692 -84.156296)
		(mid 190.448692 -83.617308)
		(end 189.909704 -83.617308)
		(stroke
			(width 0.2)
			(type default)
		)
		(layer "In3.Cu")
	)
	(gr_line
		(start 190.5 -72.644)
		(end 185.7502 -72.644)
		(stroke
			(width 0.381)
			(type default)
		)
		(layer "In3.Cu")
	)
	(gr_line
		(start 190.754 -56.9722)
		(end 191.262 -57.4802)
		(stroke
			(width 0.381)
			(type default)
		)
		(layer "In3.Cu")
	)
	(gr_arc
		(start 190.835534 -87.035132)
		(mid 190.828455 -87.576246)
		(end 191.369696 -87.578692)
		(stroke
			(width 0.2)
			(type default)
		)
		(layer "In3.Cu")
	)
	(gr_line
		(start 190.9826 -76.1238)
		(end 190.9826 -73.1266)
		(stroke
			(width 0.381)
			(type default)
		)
		(layer "In3.Cu")
	)
	(gr_line
		(start 190.9826 -73.1266)
		(end 190.5 -72.644)
		(stroke
			(width 0.381)
			(type default)
		)
		(layer "In3.Cu")
	)
	(gr_line
		(start 191.262 -57.4802)
		(end 196.3928 -57.4802)
		(stroke
			(width 0.381)
			(type default)
		)
		(layer "In3.Cu")
	)
	(gr_line
		(start 191.369696 -87.578692)
		(end 191.998092 -86.950296)
		(stroke
			(width 0.2)
			(type default)
		)
		(layer "In3.Cu")
	)
	(gr_line
		(start 191.459104 -86.411308)
		(end 190.835534 -87.035132)
		(stroke
			(width 0.2)
			(type default)
		)
		(layer "In3.Cu")
	)
	(gr_arc
		(start 191.64173 -74.699622)
		(mid 191.99987 -75.057762)
		(end 192.35801 -74.699622)
		(stroke
			(width 0.2)
			(type default)
		)
		(layer "In3.Cu")
	)
	(gr_line
		(start 191.64173 -73.899776)
		(end 191.64173 -74.699622)
		(stroke
			(width 0.2)
			(type default)
		)
		(layer "In3.Cu")
	)
	(gr_line
		(start 191.643 -101.347778)
		(end 192.532 -100.458778)
		(stroke
			(width 0.381)
			(type default)
		)
		(layer "In3.Cu")
	)
	(gr_arc
		(start 191.998092 -86.950296)
		(mid 191.998092 -86.411308)
		(end 191.459104 -86.411308)
		(stroke
			(width 0.2)
			(type default)
		)
		(layer "In3.Cu")
	)
	(gr_line
		(start 192.151 -113.919)
		(end 189.611 -111.379)
		(stroke
			(width 0.381)
			(type default)
		)
		(layer "In3.Cu")
	)
	(gr_line
		(start 192.35801 -74.699622)
		(end 192.35801 -73.90003)
		(stroke
			(width 0.2)
			(type default)
		)
		(layer "In3.Cu")
	)
	(gr_arc
		(start 192.35801 -73.90003)
		(mid 191.999997 -73.541636)
		(end 191.64173 -73.899776)
		(stroke
			(width 0.2)
			(type default)
		)
		(layer "In3.Cu")
	)
	(gr_line
		(start 192.441576 -73.90003)
		(end 192.44183 -74.699876)
		(stroke
			(width 0.2)
			(type default)
		)
		(layer "In3.Cu")
	)
	(gr_arc
		(start 192.44183 -74.699876)
		(mid 192.800097 -75.058016)
		(end 193.15811 -74.699622)
		(stroke
			(width 0.2)
			(type default)
		)
		(layer "In3.Cu")
	)
	(gr_line
		(start 192.532 -100.458778)
		(end 192.532 -93.2561)
		(stroke
			(width 0.381)
			(type default)
		)
		(layer "In3.Cu")
	)
	(gr_line
		(start 192.532 -93.2561)
		(end 181.864 -82.5881)
		(stroke
			(width 0.381)
			(type default)
		)
		(layer "In3.Cu")
	)
	(gr_arc
		(start 193.157856 -73.90003)
		(mid 192.799716 -73.541636)
		(end 192.441576 -73.90003)
		(stroke
			(width 0.2)
			(type default)
		)
		(layer "In3.Cu")
	)
	(gr_line
		(start 193.15811 -74.699622)
		(end 193.157856 -73.90003)
		(stroke
			(width 0.2)
			(type default)
		)
		(layer "In3.Cu")
	)
	(gr_line
		(start 193.4972 -16.4338)
		(end 197.5358 -16.4338)
		(stroke
			(width 0.381)
			(type default)
		)
		(layer "In3.Cu")
	)
	(gr_arc
		(start 193.557906 -88.736932)
		(mid 193.550827 -89.278046)
		(end 194.092068 -89.280492)
		(stroke
			(width 0.2)
			(type default)
		)
		(layer "In3.Cu")
	)
	(gr_arc
		(start 193.781934 -84.012532)
		(mid 193.774855 -84.553646)
		(end 194.316096 -84.556092)
		(stroke
			(width 0.2)
			(type default)
		)
		(layer "In3.Cu")
	)
	(gr_arc
		(start 194.03441 -74.698606)
		(mid 194.389248 -75.060048)
		(end 194.75069 -74.70521)
		(stroke
			(width 0.2)
			(type default)
		)
		(layer "In3.Cu")
	)
	(gr_line
		(start 194.041522 -73.896474)
		(end 194.03441 -74.698606)
		(stroke
			(width 0.2)
			(type default)
		)
		(layer "In3.Cu")
	)
	(gr_line
		(start 194.092068 -89.280492)
		(end 194.720464 -88.652096)
		(stroke
			(width 0.2)
			(type default)
		)
		(layer "In3.Cu")
	)
	(gr_line
		(start 194.181476 -88.113108)
		(end 193.557906 -88.736932)
		(stroke
			(width 0.2)
			(type default)
		)
		(layer "In3.Cu")
	)
	(gr_line
		(start 194.316096 -84.556092)
		(end 194.944492 -83.927696)
		(stroke
			(width 0.2)
			(type default)
		)
		(layer "In3.Cu")
	)
	(gr_line
		(start 194.405504 -83.388708)
		(end 193.781934 -84.012532)
		(stroke
			(width 0.2)
			(type default)
		)
		(layer "In3.Cu")
	)
	(gr_arc
		(start 194.720464 -88.652096)
		(mid 194.720464 -88.113108)
		(end 194.181476 -88.113108)
		(stroke
			(width 0.2)
			(type default)
		)
		(layer "In3.Cu")
	)
	(gr_line
		(start 194.75069 -74.70521)
		(end 194.757802 -73.903332)
		(stroke
			(width 0.2)
			(type default)
		)
		(layer "In3.Cu")
	)
	(gr_arc
		(start 194.757802 -73.903332)
		(mid 194.403091 -73.541891)
		(end 194.041522 -73.896474)
		(stroke
			(width 0.2)
			(type default)
		)
		(layer "In3.Cu")
	)
	(gr_arc
		(start 194.840352 -74.706988)
		(mid 195.197984 -75.065636)
		(end 195.556632 -74.708004)
		(stroke
			(width 0.2)
			(type default)
		)
		(layer "In3.Cu")
	)
	(gr_line
		(start 194.841622 -73.899268)
		(end 194.840352 -74.706988)
		(stroke
			(width 0.2)
			(type default)
		)
		(layer "In3.Cu")
	)
	(gr_arc
		(start 194.944492 -83.927696)
		(mid 194.944492 -83.388708)
		(end 194.405504 -83.388708)
		(stroke
			(width 0.2)
			(type default)
		)
		(layer "In3.Cu")
	)
	(gr_line
		(start 195.556632 -74.708004)
		(end 195.557902 -73.900538)
		(stroke
			(width 0.2)
			(type default)
		)
		(layer "In3.Cu")
	)
	(gr_arc
		(start 195.557902 -73.900538)
		(mid 195.200397 -73.54189)
		(end 194.841622 -73.899268)
		(stroke
			(width 0.2)
			(type default)
		)
		(layer "In3.Cu")
	)
	(gr_line
		(start 196.3928 -57.4802)
		(end 196.977 -56.896)
		(stroke
			(width 0.381)
			(type default)
		)
		(layer "In3.Cu")
	)
	(gr_line
		(start 196.441568 -73.903586)
		(end 196.44995 -74.702162)
		(stroke
			(width 0.2)
			(type default)
		)
		(layer "In3.Cu")
	)
	(gr_arc
		(start 196.44995 -74.702162)
		(mid 196.8119 -75.056492)
		(end 197.16623 -74.694542)
		(stroke
			(width 0.2)
			(type default)
		)
		(layer "In3.Cu")
	)
	(gr_arc
		(start 196.631306 -85.688932)
		(mid 196.624227 -86.230046)
		(end 197.165468 -86.232492)
		(stroke
			(width 0.2)
			(type default)
		)
		(layer "In3.Cu")
	)
	(gr_line
		(start 196.977 -56.896)
		(end 209.423 -56.896)
		(stroke
			(width 0.381)
			(type default)
		)
		(layer "In3.Cu")
	)
	(gr_arc
		(start 197.157848 -73.89622)
		(mid 196.796025 -73.541889)
		(end 196.441568 -73.903586)
		(stroke
			(width 0.2)
			(type default)
		)
		(layer "In3.Cu")
	)
	(gr_line
		(start 197.165468 -86.232492)
		(end 197.793864 -85.604096)
		(stroke
			(width 0.2)
			(type default)
		)
		(layer "In3.Cu")
	)
	(gr_line
		(start 197.16623 -74.694542)
		(end 197.157848 -73.89622)
		(stroke
			(width 0.2)
			(type default)
		)
		(layer "In3.Cu")
	)
	(gr_line
		(start 197.241668 -73.904094)
		(end 197.251066 -74.70394)
		(stroke
			(width 0.2)
			(type default)
		)
		(layer "In3.Cu")
	)
	(gr_arc
		(start 197.251066 -74.70394)
		(mid 197.613524 -75.057762)
		(end 197.967346 -74.695304)
		(stroke
			(width 0.2)
			(type default)
		)
		(layer "In3.Cu")
	)
	(gr_line
		(start 197.254876 -85.065108)
		(end 196.631306 -85.688932)
		(stroke
			(width 0.2)
			(type default)
		)
		(layer "In3.Cu")
	)
	(gr_line
		(start 197.5358 -16.4338)
		(end 210.947 -29.845)
		(stroke
			(width 0.381)
			(type default)
		)
		(layer "In3.Cu")
	)
	(gr_arc
		(start 197.793864 -85.604096)
		(mid 197.793864 -85.065108)
		(end 197.254876 -85.065108)
		(stroke
			(width 0.2)
			(type default)
		)
		(layer "In3.Cu")
	)
	(gr_arc
		(start 197.922134 -88.813132)
		(mid 197.915055 -89.354246)
		(end 198.456296 -89.356692)
		(stroke
			(width 0.2)
			(type default)
		)
		(layer "In3.Cu")
	)
	(gr_arc
		(start 197.957948 -73.895712)
		(mid 197.595617 -73.541888)
		(end 197.241668 -73.904094)
		(stroke
			(width 0.2)
			(type default)
		)
		(layer "In3.Cu")
	)
	(gr_line
		(start 197.967346 -74.695304)
		(end 197.957948 -73.895712)
		(stroke
			(width 0.2)
			(type default)
		)
		(layer "In3.Cu")
	)
	(gr_line
		(start 198.456296 -89.356692)
		(end 199.084692 -88.728296)
		(stroke
			(width 0.2)
			(type default)
		)
		(layer "In3.Cu")
	)
	(gr_line
		(start 198.545704 -88.189308)
		(end 197.922134 -88.813132)
		(stroke
			(width 0.2)
			(type default)
		)
		(layer "In3.Cu")
	)
	(gr_line
		(start 198.841614 -73.900538)
		(end 198.843392 -74.693018)
		(stroke
			(width 0.2)
			(type default)
		)
		(layer "In3.Cu")
	)
	(gr_arc
		(start 198.843392 -74.693018)
		(mid 199.202294 -75.050396)
		(end 199.559672 -74.691494)
		(stroke
			(width 0.2)
			(type default)
		)
		(layer "In3.Cu")
	)
	(gr_arc
		(start 199.084692 -88.728296)
		(mid 199.084692 -88.189308)
		(end 198.545704 -88.189308)
		(stroke
			(width 0.2)
			(type default)
		)
		(layer "In3.Cu")
	)
	(gr_arc
		(start 199.557894 -73.899268)
		(mid 199.199119 -73.54189)
		(end 198.841614 -73.900538)
		(stroke
			(width 0.2)
			(type default)
		)
		(layer "In3.Cu")
	)
	(gr_line
		(start 199.559672 -74.691494)
		(end 199.557894 -73.899268)
		(stroke
			(width 0.2)
			(type default)
		)
		(layer "In3.Cu")
	)
	(gr_line
		(start 199.641714 -73.900538)
		(end 199.643492 -74.695558)
		(stroke
			(width 0.2)
			(type default)
		)
		(layer "In3.Cu")
	)
	(gr_arc
		(start 199.643492 -74.695558)
		(mid 200.002394 -75.052936)
		(end 200.359772 -74.694034)
		(stroke
			(width 0.2)
			(type default)
		)
		(layer "In3.Cu")
	)
	(gr_arc
		(start 200.357994 -73.899268)
		(mid 199.999219 -73.54189)
		(end 199.641714 -73.900538)
		(stroke
			(width 0.2)
			(type default)
		)
		(layer "In3.Cu")
	)
	(gr_line
		(start 200.359772 -74.694034)
		(end 200.357994 -73.899268)
		(stroke
			(width 0.2)
			(type default)
		)
		(layer "In3.Cu")
	)
	(gr_line
		(start 200.79843 -74.287126)
		(end 201.598276 -74.287126)
		(stroke
			(width 0.2)
			(type default)
		)
		(layer "In3.Cu")
	)
	(gr_arc
		(start 200.798684 -73.520046)
		(mid 200.41489 -73.903459)
		(end 200.79843 -74.287126)
		(stroke
			(width 0.2)
			(type default)
		)
		(layer "In3.Cu")
	)
	(gr_arc
		(start 200.944734 -85.815932)
		(mid 200.937655 -86.357046)
		(end 201.478896 -86.359492)
		(stroke
			(width 0.2)
			(type default)
		)
		(layer "In3.Cu")
	)
	(gr_arc
		(start 201.209656 -67.49923)
		(mid 201.590021 -67.886073)
		(end 201.976736 -67.50558)
		(stroke
			(width 0.2)
			(type default)
		)
		(layer "In3.Cu")
	)
	(gr_arc
		(start 201.20991 -72.297036)
		(mid 201.592815 -72.681338)
		(end 201.97699 -72.298306)
		(stroke
			(width 0.2)
			(type default)
		)
		(layer "In3.Cu")
	)
	(gr_line
		(start 201.210926 -71.502524)
		(end 201.20991 -72.297036)
		(stroke
			(width 0.2)
			(type default)
		)
		(layer "In3.Cu")
	)
	(gr_line
		(start 201.211688 -69.111114)
		(end 201.225658 -69.906388)
		(stroke
			(width 0.2)
			(type default)
		)
		(layer "In3.Cu")
	)
	(gr_line
		(start 201.216006 -66.705988)
		(end 201.209656 -67.49923)
		(stroke
			(width 0.2)
			(type default)
		)
		(layer "In3.Cu")
	)
	(gr_arc
		(start 201.225658 -69.906388)
		(mid 201.615929 -70.283322)
		(end 201.992738 -69.892926)
		(stroke
			(width 0.2)
			(type default)
		)
		(layer "In3.Cu")
	)
	(gr_line
		(start 201.478896 -86.359492)
		(end 202.107292 -85.731096)
		(stroke
			(width 0.2)
			(type default)
		)
		(layer "In3.Cu")
	)
	(gr_line
		(start 201.568304 -85.192108)
		(end 200.944734 -85.815932)
		(stroke
			(width 0.2)
			(type default)
		)
		(layer "In3.Cu")
	)
	(gr_line
		(start 201.591672 -68.678806)
		(end 202.39609 -68.68668)
		(stroke
			(width 0.2)
			(type default)
		)
		(layer "In3.Cu")
	)
	(gr_line
		(start 201.592688 -71.086218)
		(end 202.40371 -71.087996)
		(stroke
			(width 0.2)
			(type default)
		)
		(layer "In3.Cu")
	)
	(gr_arc
		(start 201.594466 -70.319138)
		(mid 201.210164 -70.701789)
		(end 201.592688 -71.086218)
		(stroke
			(width 0.2)
			(type default)
		)
		(layer "In3.Cu")
	)
	(gr_arc
		(start 201.598276 -74.287126)
		(mid 201.981816 -73.903586)
		(end 201.598276 -73.520046)
		(stroke
			(width 0.2)
			(type default)
		)
		(layer "In3.Cu")
	)
	(gr_line
		(start 201.598276 -73.520046)
		(end 200.798684 -73.520046)
		(stroke
			(width 0.2)
			(type default)
		)
		(layer "In3.Cu")
	)
	(gr_arc
		(start 201.599292 -72.716898)
		(mid 201.217276 -73.101835)
		(end 201.602086 -73.483978)
		(stroke
			(width 0.2)
			(type default)
		)
		(layer "In3.Cu")
	)
	(gr_arc
		(start 201.599546 -67.911726)
		(mid 201.212197 -68.291329)
		(end 201.591672 -68.678806)
		(stroke
			(width 0.2)
			(type default)
		)
		(layer "In3.Cu")
	)
	(gr_line
		(start 201.5998 -75.883262)
		(end 202.399646 -75.883262)
		(stroke
			(width 0.2)
			(type default)
		)
		(layer "In3.Cu")
	)
	(gr_arc
		(start 201.600054 -75.116182)
		(mid 201.21626 -75.499595)
		(end 201.5998 -75.883262)
		(stroke
			(width 0.2)
			(type default)
		)
		(layer "In3.Cu")
	)
	(gr_line
		(start 201.602086 -73.483978)
		(end 202.39863 -73.480676)
		(stroke
			(width 0.2)
			(type default)
		)
		(layer "In3.Cu")
	)
	(gr_line
		(start 201.976736 -67.50558)
		(end 201.983086 -66.712084)
		(stroke
			(width 0.2)
			(type default)
		)
		(layer "In3.Cu")
	)
	(gr_line
		(start 201.97699 -72.298306)
		(end 201.978006 -71.50354)
		(stroke
			(width 0.2)
			(type default)
		)
		(layer "In3.Cu")
	)
	(gr_arc
		(start 201.978006 -71.50354)
		(mid 201.594974 -71.119492)
		(end 201.210926 -71.502524)
		(stroke
			(width 0.2)
			(type default)
		)
		(layer "In3.Cu")
	)
	(gr_arc
		(start 201.978768 -69.097398)
		(mid 201.58837 -68.720716)
		(end 201.211688 -69.111114)
		(stroke
			(width 0.2)
			(type default)
		)
		(layer "In3.Cu")
	)
	(gr_arc
		(start 201.983086 -66.712084)
		(mid 201.602594 -66.325496)
		(end 201.216006 -66.705988)
		(stroke
			(width 0.2)
			(type default)
		)
		(layer "In3.Cu")
	)
	(gr_line
		(start 201.992738 -69.892926)
		(end 201.978768 -69.097398)
		(stroke
			(width 0.2)
			(type default)
		)
		(layer "In3.Cu")
	)
	(gr_arc
		(start 202.107292 -85.731096)
		(mid 202.107292 -85.192108)
		(end 201.568304 -85.192108)
		(stroke
			(width 0.2)
			(type default)
		)
		(layer "In3.Cu")
	)
	(gr_line
		(start 202.395582 -72.713596)
		(end 201.599292 -72.716898)
		(stroke
			(width 0.2)
			(type default)
		)
		(layer "In3.Cu")
	)
	(gr_arc
		(start 202.39609 -68.68668)
		(mid 202.78344 -68.30695)
		(end 202.40371 -67.9196)
		(stroke
			(width 0.2)
			(type default)
		)
		(layer "In3.Cu")
	)
	(gr_arc
		(start 202.39863 -73.480676)
		(mid 202.780646 -73.095612)
		(end 202.395582 -72.713596)
		(stroke
			(width 0.2)
			(type default)
		)
		(layer "In3.Cu")
	)
	(gr_arc
		(start 202.399646 -75.883262)
		(mid 202.783186 -75.499722)
		(end 202.399646 -75.116182)
		(stroke
			(width 0.2)
			(type default)
		)
		(layer "In3.Cu")
	)
	(gr_line
		(start 202.399646 -75.116182)
		(end 201.600054 -75.116182)
		(stroke
			(width 0.2)
			(type default)
		)
		(layer "In3.Cu")
	)
	(gr_arc
		(start 202.40371 -71.087996)
		(mid 202.788012 -70.705218)
		(end 202.405234 -70.320916)
		(stroke
			(width 0.2)
			(type default)
		)
		(layer "In3.Cu")
	)
	(gr_line
		(start 202.40371 -67.9196)
		(end 201.599546 -67.911726)
		(stroke
			(width 0.2)
			(type default)
		)
		(layer "In3.Cu")
	)
	(gr_line
		(start 202.405234 -70.320916)
		(end 201.594466 -70.319138)
		(stroke
			(width 0.2)
			(type default)
		)
		(layer "In3.Cu")
	)
	(gr_arc
		(start 203.535534 -85.231732)
		(mid 203.528455 -85.772846)
		(end 204.069696 -85.775292)
		(stroke
			(width 0.2)
			(type default)
		)
		(layer "In3.Cu")
	)
	(gr_line
		(start 204.069696 -85.775292)
		(end 204.698092 -85.146896)
		(stroke
			(width 0.2)
			(type default)
		)
		(layer "In3.Cu")
	)
	(gr_line
		(start 204.159104 -84.607908)
		(end 203.535534 -85.231732)
		(stroke
			(width 0.2)
			(type default)
		)
		(layer "In3.Cu")
	)
	(gr_arc
		(start 204.698092 -85.146896)
		(mid 204.698092 -84.607908)
		(end 204.159104 -84.607908)
		(stroke
			(width 0.2)
			(type default)
		)
		(layer "In3.Cu")
	)
	(gr_line
		(start 207.264 -113.919)
		(end 192.151 -113.919)
		(stroke
			(width 0.381)
			(type default)
		)
		(layer "In3.Cu")
	)
	(gr_line
		(start 208.28 -112.903)
		(end 207.264 -113.919)
		(stroke
			(width 0.381)
			(type default)
		)
		(layer "In3.Cu")
	)
	(gr_line
		(start 208.28 -105.537)
		(end 208.28 -112.903)
		(stroke
			(width 0.381)
			(type default)
		)
		(layer "In3.Cu")
	)
	(gr_line
		(start 209.423 -67.31)
		(end 209.75574 -67.63766)
		(stroke
			(width 0.381)
			(type default)
		)
		(layer "In3.Cu")
	)
	(gr_line
		(start 209.423 -56.9722)
		(end 209.423 -67.31)
		(stroke
			(width 0.381)
			(type default)
		)
		(layer "In3.Cu")
	)
	(gr_line
		(start 209.75574 -67.63766)
		(end 210.947 -68.82892)
		(stroke
			(width 0.381)
			(type default)
		)
		(layer "In3.Cu")
	)
	(gr_line
		(start 210.3628 -40.1701)
		(end 210.8708 -40.6781)
		(stroke
			(width 0.381)
			(type default)
		)
		(layer "In3.Cu")
	)
	(gr_line
		(start 210.790536 -63.655194)
		(end 210.79079 -63.655448)
		(stroke
			(width 0.2)
			(type default)
		)
		(layer "In3.Cu")
	)
	(gr_arc
		(start 210.79079 -63.655448)
		(mid 210.79079 -64.193928)
		(end 211.32927 -64.193928)
		(stroke
			(width 0.2)
			(type default)
		)
		(layer "In3.Cu")
	)
	(gr_line
		(start 210.8454 -39.6875)
		(end 210.3628 -40.1701)
		(stroke
			(width 0.381)
			(type default)
		)
		(layer "In3.Cu")
	)
	(gr_line
		(start 210.8708 -40.132)
		(end 150.749 -40.132)
		(stroke
			(width 0.381)
			(type default)
		)
		(layer "In3.Cu")
	)
	(gr_line
		(start 210.8708 -39.6875)
		(end 210.8454 -39.6875)
		(stroke
			(width 0.381)
			(type default)
		)
		(layer "In3.Cu")
	)
	(gr_line
		(start 210.947 -102.87)
		(end 208.28 -105.537)
		(stroke
			(width 0.381)
			(type default)
		)
		(layer "In3.Cu")
	)
	(gr_line
		(start 210.947 -68.82892)
		(end 210.947 -102.87)
		(stroke
			(width 0.381)
			(type default)
		)
		(layer "In3.Cu")
	)
	(gr_line
		(start 210.947 -55.4482)
		(end 209.423 -56.9722)
		(stroke
			(width 0.381)
			(type default)
		)
		(layer "In3.Cu")
	)
	(gr_line
		(start 210.947 -29.845)
		(end 210.947 -55.4482)
		(stroke
			(width 0.381)
			(type default)
		)
		(layer "In3.Cu")
	)
	(gr_line
		(start 210.959192 -66.09842)
		(end 210.959446 -66.098674)
		(stroke
			(width 0.2)
			(type default)
		)
		(layer "In3.Cu")
	)
	(gr_arc
		(start 210.959446 -66.098674)
		(mid 210.959446 -66.637154)
		(end 211.497926 -66.637154)
		(stroke
			(width 0.2)
			(type default)
		)
		(layer "In3.Cu")
	)
	(gr_line
		(start 211.32927 -64.193928)
		(end 211.329524 -64.194182)
		(stroke
			(width 0.2)
			(type default)
		)
		(layer "In3.Cu")
	)
	(gr_line
		(start 211.329524 -64.194182)
		(end 212.137498 -63.385954)
		(stroke
			(width 0.2)
			(type default)
		)
		(layer "In3.Cu")
	)
	(gr_line
		(start 211.497926 -66.637154)
		(end 211.49818 -66.637408)
		(stroke
			(width 0.2)
			(type default)
		)
		(layer "In3.Cu")
	)
	(gr_line
		(start 211.49818 -66.637408)
		(end 212.306154 -65.82918)
		(stroke
			(width 0.2)
			(type default)
		)
		(layer "In3.Cu")
	)
	(gr_line
		(start 211.598764 -62.846966)
		(end 210.790536 -63.655194)
		(stroke
			(width 0.2)
			(type default)
		)
		(layer "In3.Cu")
	)
	(gr_line
		(start 211.599018 -62.84722)
		(end 211.598764 -62.846966)
		(stroke
			(width 0.2)
			(type default)
		)
		(layer "In3.Cu")
	)
	(gr_line
		(start 211.76742 -65.290192)
		(end 210.959192 -66.09842)
		(stroke
			(width 0.2)
			(type default)
		)
		(layer "In3.Cu")
	)
	(gr_line
		(start 211.767674 -65.290446)
		(end 211.76742 -65.290192)
		(stroke
			(width 0.2)
			(type default)
		)
		(layer "In3.Cu")
	)
	(gr_line
		(start 212.137498 -63.385954)
		(end 212.137498 -63.3857)
		(stroke
			(width 0.2)
			(type default)
		)
		(layer "In3.Cu")
	)
	(gr_arc
		(start 212.137498 -63.3857)
		(mid 212.137498 -62.84722)
		(end 211.599018 -62.84722)
		(stroke
			(width 0.2)
			(type default)
		)
		(layer "In3.Cu")
	)
	(gr_line
		(start 212.306154 -65.82918)
		(end 212.306154 -65.828926)
		(stroke
			(width 0.2)
			(type default)
		)
		(layer "In3.Cu")
	)
	(gr_arc
		(start 212.306154 -65.828926)
		(mid 212.306154 -65.290446)
		(end 211.767674 -65.290446)
		(stroke
			(width 0.2)
			(type default)
		)
		(layer "In3.Cu")
	)
	(gr_line
		(start 212.432392 -67.74942)
		(end 212.432646 -67.749674)
		(stroke
			(width 0.2)
			(type default)
		)
		(layer "In3.Cu")
	)
	(gr_arc
		(start 212.432646 -67.749674)
		(mid 212.432646 -68.288154)
		(end 212.971126 -68.288154)
		(stroke
			(width 0.2)
			(type default)
		)
		(layer "In3.Cu")
	)
	(gr_line
		(start 212.971126 -68.288154)
		(end 212.97138 -68.288408)
		(stroke
			(width 0.2)
			(type default)
		)
		(layer "In3.Cu")
	)
	(gr_line
		(start 212.97138 -68.288408)
		(end 213.779354 -67.48018)
		(stroke
			(width 0.2)
			(type default)
		)
		(layer "In3.Cu")
	)
	(gr_line
		(start 213.24062 -66.941192)
		(end 212.432392 -67.74942)
		(stroke
			(width 0.2)
			(type default)
		)
		(layer "In3.Cu")
	)
	(gr_line
		(start 213.240874 -66.941446)
		(end 213.24062 -66.941192)
		(stroke
			(width 0.2)
			(type default)
		)
		(layer "In3.Cu")
	)
	(gr_line
		(start 213.448392 -72.52462)
		(end 213.448646 -72.524874)
		(stroke
			(width 0.2)
			(type default)
		)
		(layer "In3.Cu")
	)
	(gr_arc
		(start 213.448646 -72.524874)
		(mid 213.448646 -73.063354)
		(end 213.987126 -73.063354)
		(stroke
			(width 0.2)
			(type default)
		)
		(layer "In3.Cu")
	)
	(gr_line
		(start 213.779354 -67.48018)
		(end 213.779354 -67.479926)
		(stroke
			(width 0.2)
			(type default)
		)
		(layer "In3.Cu")
	)
	(gr_arc
		(start 213.779354 -67.479926)
		(mid 213.779354 -66.941446)
		(end 213.240874 -66.941446)
		(stroke
			(width 0.2)
			(type default)
		)
		(layer "In3.Cu")
	)
	(gr_line
		(start 213.956392 -69.22262)
		(end 213.956646 -69.222874)
		(stroke
			(width 0.2)
			(type default)
		)
		(layer "In3.Cu")
	)
	(gr_arc
		(start 213.956646 -69.222874)
		(mid 213.956646 -69.761354)
		(end 214.495126 -69.761354)
		(stroke
			(width 0.2)
			(type default)
		)
		(layer "In3.Cu")
	)
	(gr_line
		(start 213.987126 -73.063354)
		(end 213.98738 -73.063608)
		(stroke
			(width 0.2)
			(type default)
		)
		(layer "In3.Cu")
	)
	(gr_line
		(start 213.98738 -73.063608)
		(end 214.795354 -72.25538)
		(stroke
			(width 0.2)
			(type default)
		)
		(layer "In3.Cu")
	)
	(gr_line
		(start 214.25662 -71.716392)
		(end 213.448392 -72.52462)
		(stroke
			(width 0.2)
			(type default)
		)
		(layer "In3.Cu")
	)
	(gr_line
		(start 214.256874 -71.716646)
		(end 214.25662 -71.716392)
		(stroke
			(width 0.2)
			(type default)
		)
		(layer "In3.Cu")
	)
	(gr_line
		(start 214.495126 -69.761354)
		(end 214.49538 -69.761608)
		(stroke
			(width 0.2)
			(type default)
		)
		(layer "In3.Cu")
	)
	(gr_line
		(start 214.49538 -69.761608)
		(end 215.303354 -68.95338)
		(stroke
			(width 0.2)
			(type default)
		)
		(layer "In3.Cu")
	)
	(gr_line
		(start 214.76462 -68.414392)
		(end 213.956392 -69.22262)
		(stroke
			(width 0.2)
			(type default)
		)
		(layer "In3.Cu")
	)
	(gr_line
		(start 214.764874 -68.414646)
		(end 214.76462 -68.414392)
		(stroke
			(width 0.2)
			(type default)
		)
		(layer "In3.Cu")
	)
	(gr_line
		(start 214.795354 -72.25538)
		(end 214.795354 -72.255126)
		(stroke
			(width 0.2)
			(type default)
		)
		(layer "In3.Cu")
	)
	(gr_arc
		(start 214.795354 -72.255126)
		(mid 214.795354 -71.716646)
		(end 214.256874 -71.716646)
		(stroke
			(width 0.2)
			(type default)
		)
		(layer "In3.Cu")
	)
	(gr_line
		(start 214.845392 -73.92162)
		(end 214.845646 -73.921874)
		(stroke
			(width 0.2)
			(type default)
		)
		(layer "In3.Cu")
	)
	(gr_arc
		(start 214.845646 -73.921874)
		(mid 214.845646 -74.460354)
		(end 215.384126 -74.460354)
		(stroke
			(width 0.2)
			(type default)
		)
		(layer "In3.Cu")
	)
	(gr_line
		(start 215.226392 -79.38262)
		(end 215.226646 -79.382874)
		(stroke
			(width 0.2)
			(type default)
		)
		(layer "In3.Cu")
	)
	(gr_arc
		(start 215.226646 -79.382874)
		(mid 215.226646 -79.921354)
		(end 215.765126 -79.921354)
		(stroke
			(width 0.2)
			(type default)
		)
		(layer "In3.Cu")
	)
	(gr_line
		(start 215.303354 -68.95338)
		(end 215.303354 -68.953126)
		(stroke
			(width 0.2)
			(type default)
		)
		(layer "In3.Cu")
	)
	(gr_arc
		(start 215.303354 -68.953126)
		(mid 215.303354 -68.414646)
		(end 214.764874 -68.414646)
		(stroke
			(width 0.2)
			(type default)
		)
		(layer "In3.Cu")
	)
	(gr_line
		(start 215.384126 -74.460354)
		(end 215.38438 -74.460608)
		(stroke
			(width 0.2)
			(type default)
		)
		(layer "In3.Cu")
	)
	(gr_line
		(start 215.38438 -74.460608)
		(end 216.192354 -73.65238)
		(stroke
			(width 0.2)
			(type default)
		)
		(layer "In3.Cu")
	)
	(gr_line
		(start 215.65362 -73.113392)
		(end 214.845392 -73.92162)
		(stroke
			(width 0.2)
			(type default)
		)
		(layer "In3.Cu")
	)
	(gr_line
		(start 215.653874 -73.113646)
		(end 215.65362 -73.113392)
		(stroke
			(width 0.2)
			(type default)
		)
		(layer "In3.Cu")
	)
	(gr_line
		(start 215.765126 -79.921354)
		(end 215.76538 -79.921608)
		(stroke
			(width 0.2)
			(type default)
		)
		(layer "In3.Cu")
	)
	(gr_line
		(start 215.76538 -79.921608)
		(end 216.573354 -79.11338)
		(stroke
			(width 0.2)
			(type default)
		)
		(layer "In3.Cu")
	)
	(gr_line
		(start 216.03462 -78.574392)
		(end 215.226392 -79.38262)
		(stroke
			(width 0.2)
			(type default)
		)
		(layer "In3.Cu")
	)
	(gr_line
		(start 216.034874 -78.574646)
		(end 216.03462 -78.574392)
		(stroke
			(width 0.2)
			(type default)
		)
		(layer "In3.Cu")
	)
	(gr_line
		(start 216.192354 -73.65238)
		(end 216.192354 -73.652126)
		(stroke
			(width 0.2)
			(type default)
		)
		(layer "In3.Cu")
	)
	(gr_arc
		(start 216.192354 -73.652126)
		(mid 216.192354 -73.113646)
		(end 215.653874 -73.113646)
		(stroke
			(width 0.2)
			(type default)
		)
		(layer "In3.Cu")
	)
	(gr_line
		(start 216.369392 -75.44562)
		(end 216.369646 -75.445874)
		(stroke
			(width 0.2)
			(type default)
		)
		(layer "In3.Cu")
	)
	(gr_arc
		(start 216.369646 -75.445874)
		(mid 216.369646 -75.984354)
		(end 216.908126 -75.984354)
		(stroke
			(width 0.2)
			(type default)
		)
		(layer "In3.Cu")
	)
	(gr_line
		(start 216.573354 -79.11338)
		(end 216.573354 -79.113126)
		(stroke
			(width 0.2)
			(type default)
		)
		(layer "In3.Cu")
	)
	(gr_arc
		(start 216.573354 -79.113126)
		(mid 216.573354 -78.574646)
		(end 216.034874 -78.574646)
		(stroke
			(width 0.2)
			(type default)
		)
		(layer "In3.Cu")
	)
	(gr_line
		(start 216.908126 -75.984354)
		(end 216.90838 -75.984608)
		(stroke
			(width 0.2)
			(type default)
		)
		(layer "In3.Cu")
	)
	(gr_line
		(start 216.90838 -75.984608)
		(end 217.716354 -75.17638)
		(stroke
			(width 0.2)
			(type default)
		)
		(layer "In3.Cu")
	)
	(gr_line
		(start 217.17762 -74.637392)
		(end 216.369392 -75.44562)
		(stroke
			(width 0.2)
			(type default)
		)
		(layer "In3.Cu")
	)
	(gr_line
		(start 217.177874 -74.637646)
		(end 217.17762 -74.637392)
		(stroke
			(width 0.2)
			(type default)
		)
		(layer "In3.Cu")
	)
	(gr_line
		(start 217.716354 -75.17638)
		(end 217.716354 -75.176126)
		(stroke
			(width 0.2)
			(type default)
		)
		(layer "In3.Cu")
	)
	(gr_arc
		(start 217.716354 -75.176126)
		(mid 217.716354 -74.637646)
		(end 217.177874 -74.637646)
		(stroke
			(width 0.2)
			(type default)
		)
		(layer "In3.Cu")
	)
	(gr_line
		(start 229.382066 -194.00012)
		(end 149.917912 -194.00012)
		(stroke
			(width 2.54)
			(type default)
		)
		(layer "In3.Cu")
	)
	(gr_arc
		(start 229.382066 -194.00012)
		(mid 229.907793 -193.850701)
		(end 230.2764 -193.447162)
		(stroke
			(width 2.54)
			(type default)
		)
		(layer "In3.Cu")
	)
	(gr_line
		(start 233.6038 -157.9626)
		(end 233.9086 -157.6578)
		(stroke
			(width 0.381)
			(type default)
		)
		(layer "In3.Cu")
	)
	(gr_line
		(start 233.6038 -157.9626)
		(end 233.9848 -158.3436)
		(stroke
			(width 0.381)
			(type default)
		)
		(layer "In3.Cu")
	)
	(gr_line
		(start 233.844592 -157.972506)
		(end 175.6283 -157.972506)
		(stroke
			(width 0.381)
			(type default)
		)
		(layer "In3.Cu")
	)
	(gr_line
		(start 234.894374 -184.211214)
		(end 230.2764 -193.447162)
		(stroke
			(width 2.54)
			(type default)
		)
		(layer "In3.Cu")
	)
	(gr_arc
		(start 234.894374 -184.211214)
		(mid 234.97328 -183.993726)
		(end 235.000038 -183.76392)
		(stroke
			(width 2.54)
			(type default)
		)
		(layer "In3.Cu")
	)
	(gr_arc
		(start 235.000038 -0.999998)
		(mid 234.707147 -0.29288)
		(end 234.00004 0)
		(stroke
			(width 2.54)
			(type default)
		)
		(layer "In3.Cu")
	)
	(gr_line
		(start 235.000038 -0.999998)
		(end 235.000038 -183.76392)
		(stroke
			(width 2.54)
			(type default)
		)
		(layer "In3.Cu")
	)
	(gr_line
		(start -2.068576 -182.65267)
		(end -2.012188 -182.709058)
		(stroke
			(width 0.381)
			(type default)
		)
		(layer "In4.Cu")
	)
	(gr_line
		(start -2.012188 -182.709058)
		(end 5.170932 -182.709058)
		(stroke
			(width 0.381)
			(type default)
		)
		(layer "In4.Cu")
	)
	(gr_line
		(start -0.79629 -108.741718)
		(end 30.13837 -108.741718)
		(stroke
			(width 0.381)
			(type default)
		)
		(layer "In4.Cu")
	)
	(gr_line
		(start 0 -183.76392)
		(end 0 -0.999998)
		(stroke
			(width 2.54)
			(type default)
		)
		(layer "In4.Cu")
	)
	(gr_arc
		(start 0 -183.76392)
		(mid 0.026807 -183.993715)
		(end 0.105664 -184.211214)
		(stroke
			(width 2.54)
			(type default)
		)
		(layer "In4.Cu")
	)
	(gr_arc
		(start 0.999998 0)
		(mid 0.292893 -0.292893)
		(end 0 -0.999998)
		(stroke
			(width 2.54)
			(type default)
		)
		(layer "In4.Cu")
	)
	(gr_line
		(start 0.999998 0)
		(end 29.53004 0)
		(stroke
			(width 2.54)
			(type default)
		)
		(layer "In4.Cu")
	)
	(gr_line
		(start 1.108202 -183.23687)
		(end 1.625092 -182.71998)
		(stroke
			(width 0.381)
			(type default)
		)
		(layer "In4.Cu")
	)
	(gr_line
		(start 1.110742 -109.27715)
		(end 1.627632 -108.76026)
		(stroke
			(width 0.381)
			(type default)
		)
		(layer "In4.Cu")
	)
	(gr_line
		(start 1.625092 -182.71998)
		(end 1.108202 -182.20309)
		(stroke
			(width 0.381)
			(type default)
		)
		(layer "In4.Cu")
	)
	(gr_line
		(start 1.627632 -108.76026)
		(end 1.110742 -108.24337)
		(stroke
			(width 0.381)
			(type default)
		)
		(layer "In4.Cu")
	)
	(gr_line
		(start 4.723638 -193.447162)
		(end 0.105664 -184.211214)
		(stroke
			(width 2.54)
			(type default)
		)
		(layer "In4.Cu")
	)
	(gr_arc
		(start 4.723638 -193.447162)
		(mid 5.092281 -193.850645)
		(end 5.617972 -194.00012)
		(stroke
			(width 2.54)
			(type default)
		)
		(layer "In4.Cu")
	)
	(gr_line
		(start 5.170932 -182.709058)
		(end 5.171186 -182.708804)
		(stroke
			(width 0.381)
			(type default)
		)
		(layer "In4.Cu")
	)
	(gr_line
		(start 5.171186 -182.708804)
		(end 13.463778 -182.708804)
		(stroke
			(width 0.381)
			(type default)
		)
		(layer "In4.Cu")
	)
	(gr_line
		(start 13.463778 -182.708804)
		(end 16.152876 -185.397902)
		(stroke
			(width 0.381)
			(type default)
		)
		(layer "In4.Cu")
	)
	(gr_line
		(start 14.165834 -173.032166)
		(end 14.165834 -166.08679)
		(stroke
			(width 0.381)
			(type default)
		)
		(layer "In4.Cu")
	)
	(gr_line
		(start 14.165834 -166.08679)
		(end 34.00679 -166.08679)
		(stroke
			(width 0.381)
			(type default)
		)
		(layer "In4.Cu")
	)
	(gr_line
		(start 14.165834 -132.51561)
		(end 14.165834 -166.08679)
		(stroke
			(width 0.381)
			(type default)
		)
		(layer "In4.Cu")
	)
	(gr_line
		(start 14.224 -166.624)
		(end 14.74089 -166.10711)
		(stroke
			(width 0.381)
			(type default)
		)
		(layer "In4.Cu")
	)
	(gr_circle
		(center 14.249908 -6.249924)
		(end 15.141448 -6.249924)
		(stroke
			(width 0.2)
			(type default)
		)
		(fill no)
		(layer "In4.Cu")
	)
	(gr_line
		(start 14.74089 -166.10711)
		(end 14.224 -165.59022)
		(stroke
			(width 0.381)
			(type default)
		)
		(layer "In4.Cu")
	)
	(gr_line
		(start 15.21206 -139.884912)
		(end 15.53972 -140.212572)
		(stroke
			(width 0.381)
			(type default)
		)
		(layer "In4.Cu")
	)
	(gr_line
		(start 15.21206 -136.077452)
		(end 15.21206 -139.884912)
		(stroke
			(width 0.381)
			(type default)
		)
		(layer "In4.Cu")
	)
	(gr_line
		(start 15.53972 -140.212572)
		(end 16.543528 -140.212572)
		(stroke
			(width 0.381)
			(type default)
		)
		(layer "In4.Cu")
	)
	(gr_line
		(start 16.152876 -185.397902)
		(end 28.898088 -185.397902)
		(stroke
			(width 0.381)
			(type default)
		)
		(layer "In4.Cu")
	)
	(gr_line
		(start 16.543528 -140.212572)
		(end 16.8783 -139.8778)
		(stroke
			(width 0.381)
			(type default)
		)
		(layer "In4.Cu")
	)
	(gr_line
		(start 16.8783 -139.8778)
		(end 16.8783 -135.520176)
		(stroke
			(width 0.381)
			(type default)
		)
		(layer "In4.Cu")
	)
	(gr_line
		(start 16.8783 -135.520176)
		(end 17.935194 -134.463282)
		(stroke
			(width 0.381)
			(type default)
		)
		(layer "In4.Cu")
	)
	(gr_line
		(start 17.609566 -133.679946)
		(end 15.21206 -136.077452)
		(stroke
			(width 0.381)
			(type default)
		)
		(layer "In4.Cu")
	)
	(gr_line
		(start 17.825466 -176.691798)
		(end 14.165834 -173.032166)
		(stroke
			(width 0.381)
			(type default)
		)
		(layer "In4.Cu")
	)
	(gr_line
		(start 17.935194 -134.463282)
		(end 26.659586 -134.463282)
		(stroke
			(width 0.381)
			(type default)
		)
		(layer "In4.Cu")
	)
	(gr_line
		(start 23.448772 -176.691798)
		(end 17.825466 -176.691798)
		(stroke
			(width 0.381)
			(type default)
		)
		(layer "In4.Cu")
	)
	(gr_line
		(start 24.8158 -184.9882)
		(end 24.4094 -185.3946)
		(stroke
			(width 0.381)
			(type default)
		)
		(layer "In4.Cu")
	)
	(gr_line
		(start 24.8412 -184.9882)
		(end 24.8158 -184.9882)
		(stroke
			(width 0.381)
			(type default)
		)
		(layer "In4.Cu")
	)
	(gr_line
		(start 24.896318 -184.739788)
		(end 24.896318 -185.386218)
		(stroke
			(width 0.381)
			(type default)
		)
		(layer "In4.Cu")
	)
	(gr_line
		(start 24.896318 -184.739788)
		(end 24.896318 -178.139344)
		(stroke
			(width 0.381)
			(type default)
		)
		(layer "In4.Cu")
	)
	(gr_line
		(start 24.896318 -178.139344)
		(end 23.448772 -176.691798)
		(stroke
			(width 0.381)
			(type default)
		)
		(layer "In4.Cu")
	)
	(gr_line
		(start 25.327102 -185.397902)
		(end 24.896318 -184.967118)
		(stroke
			(width 0.381)
			(type default)
		)
		(layer "In4.Cu")
	)
	(gr_circle
		(center 26.249884 -8.750046)
		(end 27.141424 -8.750046)
		(stroke
			(width 0.2)
			(type default)
		)
		(fill no)
		(layer "In4.Cu")
	)
	(gr_line
		(start 26.43886 -120.242584)
		(end 14.165834 -132.51561)
		(stroke
			(width 0.381)
			(type default)
		)
		(layer "In4.Cu")
	)
	(gr_line
		(start 26.659586 -134.463282)
		(end 38.331648 -146.135344)
		(stroke
			(width 0.381)
			(type default)
		)
		(layer "In4.Cu")
	)
	(gr_line
		(start 27.002994 -133.679946)
		(end 17.609566 -133.679946)
		(stroke
			(width 0.381)
			(type default)
		)
		(layer "In4.Cu")
	)
	(gr_line
		(start 28.2448 -165.5699)
		(end 28.2448 -165.9636)
		(stroke
			(width 0.381)
			(type default)
		)
		(layer "In4.Cu")
	)
	(gr_line
		(start 28.253436 -165.565836)
		(end 28.253436 -165.561264)
		(stroke
			(width 0.381)
			(type default)
		)
		(layer "In4.Cu")
	)
	(gr_line
		(start 28.253436 -165.561264)
		(end 27.7241 -166.0906)
		(stroke
			(width 0.381)
			(type default)
		)
		(layer "In4.Cu")
	)
	(gr_line
		(start 28.253436 -165.561264)
		(end 28.2448 -165.5699)
		(stroke
			(width 0.381)
			(type default)
		)
		(layer "In4.Cu")
	)
	(gr_line
		(start 28.253436 -153.901902)
		(end 28.253436 -165.561264)
		(stroke
			(width 0.381)
			(type default)
		)
		(layer "In4.Cu")
	)
	(gr_line
		(start 28.7528 -166.0652)
		(end 28.253436 -165.565836)
		(stroke
			(width 0.381)
			(type default)
		)
		(layer "In4.Cu")
	)
	(gr_arc
		(start 28.915868 -185.405268)
		(mid 28.907718 -185.399801)
		(end 28.898088 -185.397902)
		(stroke
			(width 0.381)
			(type default)
		)
		(layer "In4.Cu")
	)
	(gr_line
		(start 28.915868 -185.405268)
		(end 36.5252 -193.0146)
		(stroke
			(width 0.381)
			(type default)
		)
		(layer "In4.Cu")
	)
	(gr_line
		(start 29.7942 -108.7628)
		(end 32.0294 -108.7628)
		(stroke
			(width 0.381)
			(type default)
		)
		(layer "In4.Cu")
	)
	(gr_line
		(start 30.13837 -108.741718)
		(end 31.83001 -107.050078)
		(stroke
			(width 0.381)
			(type default)
		)
		(layer "In4.Cu")
	)
	(gr_line
		(start 30.3276 -108.6866)
		(end 30.5816 -108.6866)
		(stroke
			(width 0.381)
			(type default)
		)
		(layer "In4.Cu")
	)
	(gr_arc
		(start 30.530038 -109.050074)
		(mid 30.822931 -109.757179)
		(end 31.530036 -110.050072)
		(stroke
			(width 2.54)
			(type default)
		)
		(layer "In4.Cu")
	)
	(gr_arc
		(start 30.530038 -0.999998)
		(mid 30.237147 -0.29288)
		(end 29.53004 0)
		(stroke
			(width 2.54)
			(type default)
		)
		(layer "In4.Cu")
	)
	(gr_line
		(start 30.530038 -0.999998)
		(end 30.530038 -109.050074)
		(stroke
			(width 2.54)
			(type default)
		)
		(layer "In4.Cu")
	)
	(gr_line
		(start 30.5816 -108.6866)
		(end 30.9118 -108.6866)
		(stroke
			(width 0.381)
			(type default)
		)
		(layer "In4.Cu")
	)
	(gr_line
		(start 30.5816 -108.6866)
		(end 31.115 -108.1532)
		(stroke
			(width 0.381)
			(type default)
		)
		(layer "In4.Cu")
	)
	(gr_line
		(start 30.9118 -108.6866)
		(end 31.2928 -108.3056)
		(stroke
			(width 0.381)
			(type default)
		)
		(layer "In4.Cu")
	)
	(gr_line
		(start 31.530036 -110.050072)
		(end 72.030082 -110.050072)
		(stroke
			(width 2.54)
			(type default)
		)
		(layer "In4.Cu")
	)
	(gr_line
		(start 32.02813 -150.127208)
		(end 28.253436 -153.901902)
		(stroke
			(width 0.381)
			(type default)
		)
		(layer "In4.Cu")
	)
	(gr_line
		(start 34.00679 -166.08679)
		(end 34.355532 -165.738048)
		(stroke
			(width 0.381)
			(type default)
		)
		(layer "In4.Cu")
	)
	(gr_line
		(start 34.00679 -166.08679)
		(end 34.456624 -166.536624)
		(stroke
			(width 0.381)
			(type default)
		)
		(layer "In4.Cu")
	)
	(gr_line
		(start 34.355532 -165.738048)
		(end 65.2272 -165.738048)
		(stroke
			(width 0.381)
			(type default)
		)
		(layer "In4.Cu")
	)
	(gr_line
		(start 34.456624 -169.737024)
		(end 53.6194 -188.8998)
		(stroke
			(width 0.381)
			(type default)
		)
		(layer "In4.Cu")
	)
	(gr_line
		(start 34.456624 -166.536624)
		(end 34.456624 -169.737024)
		(stroke
			(width 0.381)
			(type default)
		)
		(layer "In4.Cu")
	)
	(gr_line
		(start 36.5252 -193.0146)
		(end 79.1972 -193.0146)
		(stroke
			(width 0.381)
			(type default)
		)
		(layer "In4.Cu")
	)
	(gr_line
		(start 36.836096 -140.66901)
		(end 37.56279 -141.395704)
		(stroke
			(width 0.381)
			(type default)
		)
		(layer "In4.Cu")
	)
	(gr_line
		(start 36.836096 -135.833104)
		(end 36.836096 -140.66901)
		(stroke
			(width 0.381)
			(type default)
		)
		(layer "In4.Cu")
	)
	(gr_line
		(start 37.56279 -141.395704)
		(end 43.870118 -141.395704)
		(stroke
			(width 0.381)
			(type default)
		)
		(layer "In4.Cu")
	)
	(gr_line
		(start 38.120574 -144.797526)
		(end 27.002994 -133.679946)
		(stroke
			(width 0.381)
			(type default)
		)
		(layer "In4.Cu")
	)
	(gr_line
		(start 38.331648 -146.135344)
		(end 39.109904 -146.9136)
		(stroke
			(width 0.3048)
			(type default)
		)
		(layer "In4.Cu")
	)
	(gr_line
		(start 38.641274 -144.797526)
		(end 38.120574 -144.797526)
		(stroke
			(width 0.3048)
			(type default)
		)
		(layer "In4.Cu")
	)
	(gr_line
		(start 38.862 -144.5768)
		(end 38.641274 -144.797526)
		(stroke
			(width 0.3048)
			(type default)
		)
		(layer "In4.Cu")
	)
	(gr_line
		(start 39.109904 -146.9136)
		(end 42.926 -146.9136)
		(stroke
			(width 0.3048)
			(type default)
		)
		(layer "In4.Cu")
	)
	(gr_line
		(start 40.527478 -132.141722)
		(end 36.836096 -135.833104)
		(stroke
			(width 0.381)
			(type default)
		)
		(layer "In4.Cu")
	)
	(gr_arc
		(start 40.529256 -132.14096)
		(mid 40.528284 -132.141153)
		(end 40.527478 -132.141722)
		(stroke
			(width 0.381)
			(type default)
		)
		(layer "In4.Cu")
	)
	(gr_line
		(start 42.926 -146.9136)
		(end 43.688 -147.6756)
		(stroke
			(width 0.3048)
			(type default)
		)
		(layer "In4.Cu")
	)
	(gr_line
		(start 43.613832 -150.127208)
		(end 32.02813 -150.127208)
		(stroke
			(width 0.381)
			(type default)
		)
		(layer "In4.Cu")
	)
	(gr_line
		(start 43.688 -147.6756)
		(end 44.3611 -147.6756)
		(stroke
			(width 0.3048)
			(type default)
		)
		(layer "In4.Cu")
	)
	(gr_line
		(start 43.870118 -141.395704)
		(end 44.66082 -142.186406)
		(stroke
			(width 0.381)
			(type default)
		)
		(layer "In4.Cu")
	)
	(gr_line
		(start 44.3611 -147.6756)
		(end 44.3738 -147.6756)
		(stroke
			(width 0.3048)
			(type default)
		)
		(layer "In4.Cu")
	)
	(gr_line
		(start 44.3611 -147.6756)
		(end 44.6024 -147.9169)
		(stroke
			(width 0.3048)
			(type default)
		)
		(layer "In4.Cu")
	)
	(gr_line
		(start 44.3738 -147.6756)
		(end 44.6786 -147.3708)
		(stroke
			(width 0.3048)
			(type default)
		)
		(layer "In4.Cu")
	)
	(gr_line
		(start 44.45 -144.5768)
		(end 38.862 -144.5768)
		(stroke
			(width 0.3048)
			(type default)
		)
		(layer "In4.Cu")
	)
	(gr_line
		(start 44.45 -144.5768)
		(end 44.6532 -144.3736)
		(stroke
			(width 0.3048)
			(type default)
		)
		(layer "In4.Cu")
	)
	(gr_line
		(start 44.6024 -144.7292)
		(end 44.45 -144.5768)
		(stroke
			(width 0.3048)
			(type default)
		)
		(layer "In4.Cu")
	)
	(gr_line
		(start 44.66082 -149.08022)
		(end 43.613832 -150.127208)
		(stroke
			(width 0.381)
			(type default)
		)
		(layer "In4.Cu")
	)
	(gr_line
		(start 44.66082 -142.186406)
		(end 44.66082 -149.08022)
		(stroke
			(width 0.381)
			(type default)
		)
		(layer "In4.Cu")
	)
	(gr_line
		(start 53.6194 -188.8998)
		(end 68.5038 -188.8998)
		(stroke
			(width 0.381)
			(type default)
		)
		(layer "In4.Cu")
	)
	(gr_line
		(start 65.2272 -165.738048)
		(end 76.431648 -154.5336)
		(stroke
			(width 0.381)
			(type default)
		)
		(layer "In4.Cu")
	)
	(gr_line
		(start 68.5038 -188.8998)
		(end 72.4662 -184.9374)
		(stroke
			(width 0.381)
			(type default)
		)
		(layer "In4.Cu")
	)
	(gr_arc
		(start 72.030082 -110.050072)
		(mid 72.737187 -109.757179)
		(end 73.03008 -109.050074)
		(stroke
			(width 2.54)
			(type default)
		)
		(layer "In4.Cu")
	)
	(gr_line
		(start 72.056498 -120.242584)
		(end 26.43886 -120.242584)
		(stroke
			(width 0.381)
			(type default)
		)
		(layer "In4.Cu")
	)
	(gr_line
		(start 72.145144 -132.14096)
		(end 40.529256 -132.14096)
		(stroke
			(width 0.381)
			(type default)
		)
		(layer "In4.Cu")
	)
	(gr_arc
		(start 72.146922 -132.141722)
		(mid 72.146106 -132.141177)
		(end 72.145144 -132.14096)
		(stroke
			(width 0.381)
			(type default)
		)
		(layer "In4.Cu")
	)
	(gr_line
		(start 72.4662 -184.9374)
		(end 72.4662 -168.91)
		(stroke
			(width 0.381)
			(type default)
		)
		(layer "In4.Cu")
	)
	(gr_line
		(start 72.4662 -168.91)
		(end 76.6572 -164.719)
		(stroke
			(width 0.381)
			(type default)
		)
		(layer "In4.Cu")
	)
	(gr_line
		(start 73.03008 -109.050074)
		(end 73.03008 -0.999998)
		(stroke
			(width 2.54)
			(type default)
		)
		(layer "In4.Cu")
	)
	(gr_arc
		(start 74.030078 0)
		(mid 73.322986 -0.2929)
		(end 73.03008 -0.999998)
		(stroke
			(width 2.54)
			(type default)
		)
		(layer "In4.Cu")
	)
	(gr_line
		(start 74.030078 0)
		(end 234.00004 0)
		(stroke
			(width 2.54)
			(type default)
		)
		(layer "In4.Cu")
	)
	(gr_line
		(start 76.431648 -154.5336)
		(end 77.724 -154.5336)
		(stroke
			(width 0.381)
			(type default)
		)
		(layer "In4.Cu")
	)
	(gr_line
		(start 76.6572 -164.719)
		(end 83.5152 -164.719)
		(stroke
			(width 0.381)
			(type default)
		)
		(layer "In4.Cu")
	)
	(gr_arc
		(start 76.891134 -68.211192)
		(mid 77.274674 -68.594732)
		(end 77.658214 -68.211192)
		(stroke
			(width 0.2)
			(type default)
		)
		(layer "In4.Cu")
	)
	(gr_line
		(start 76.891134 -67.322192)
		(end 76.891134 -68.211192)
		(stroke
			(width 0.2)
			(type default)
		)
		(layer "In4.Cu")
	)
	(gr_arc
		(start 76.900278 -93.799914)
		(mid 77.283691 -94.183708)
		(end 77.667358 -93.800168)
		(stroke
			(width 0.2)
			(type default)
		)
		(layer "In4.Cu")
	)
	(gr_line
		(start 76.900278 -92.911168)
		(end 76.900278 -93.799914)
		(stroke
			(width 0.2)
			(type default)
		)
		(layer "In4.Cu")
	)
	(gr_arc
		(start 76.900278 -87.399114)
		(mid 77.283691 -87.782908)
		(end 77.667358 -87.399368)
		(stroke
			(width 0.2)
			(type default)
		)
		(layer "In4.Cu")
	)
	(gr_line
		(start 76.900278 -86.510368)
		(end 76.900278 -87.399114)
		(stroke
			(width 0.2)
			(type default)
		)
		(layer "In4.Cu")
	)
	(gr_arc
		(start 76.900278 -80.998314)
		(mid 77.283691 -81.382108)
		(end 77.667358 -80.998568)
		(stroke
			(width 0.2)
			(type default)
		)
		(layer "In4.Cu")
	)
	(gr_line
		(start 76.900278 -80.109568)
		(end 76.900278 -80.998314)
		(stroke
			(width 0.2)
			(type default)
		)
		(layer "In4.Cu")
	)
	(gr_arc
		(start 76.900278 -74.597514)
		(mid 77.283691 -74.981308)
		(end 77.667358 -74.597768)
		(stroke
			(width 0.2)
			(type default)
		)
		(layer "In4.Cu")
	)
	(gr_line
		(start 76.900278 -73.708768)
		(end 76.900278 -74.597514)
		(stroke
			(width 0.2)
			(type default)
		)
		(layer "In4.Cu")
	)
	(gr_line
		(start 77.658214 -68.211192)
		(end 77.658214 -67.322446)
		(stroke
			(width 0.2)
			(type default)
		)
		(layer "In4.Cu")
	)
	(gr_arc
		(start 77.658214 -67.322446)
		(mid 77.274801 -66.938652)
		(end 76.891134 -67.322192)
		(stroke
			(width 0.2)
			(type default)
		)
		(layer "In4.Cu")
	)
	(gr_line
		(start 77.667358 -93.800168)
		(end 77.667358 -92.911168)
		(stroke
			(width 0.2)
			(type default)
		)
		(layer "In4.Cu")
	)
	(gr_arc
		(start 77.667358 -92.911168)
		(mid 77.283818 -92.527628)
		(end 76.900278 -92.911168)
		(stroke
			(width 0.2)
			(type default)
		)
		(layer "In4.Cu")
	)
	(gr_line
		(start 77.667358 -87.399368)
		(end 77.667358 -86.510368)
		(stroke
			(width 0.2)
			(type default)
		)
		(layer "In4.Cu")
	)
	(gr_arc
		(start 77.667358 -86.510368)
		(mid 77.283818 -86.126828)
		(end 76.900278 -86.510368)
		(stroke
			(width 0.2)
			(type default)
		)
		(layer "In4.Cu")
	)
	(gr_line
		(start 77.667358 -80.998568)
		(end 77.667358 -80.109568)
		(stroke
			(width 0.2)
			(type default)
		)
		(layer "In4.Cu")
	)
	(gr_arc
		(start 77.667358 -80.109568)
		(mid 77.283818 -79.726028)
		(end 76.900278 -80.109568)
		(stroke
			(width 0.2)
			(type default)
		)
		(layer "In4.Cu")
	)
	(gr_line
		(start 77.667358 -74.597768)
		(end 77.667358 -73.708768)
		(stroke
			(width 0.2)
			(type default)
		)
		(layer "In4.Cu")
	)
	(gr_arc
		(start 77.667358 -73.708768)
		(mid 77.283818 -73.325228)
		(end 76.900278 -73.708768)
		(stroke
			(width 0.2)
			(type default)
		)
		(layer "In4.Cu")
	)
	(gr_line
		(start 77.724 -154.5336)
		(end 78.8162 -153.4414)
		(stroke
			(width 0.381)
			(type default)
		)
		(layer "In4.Cu")
	)
	(gr_arc
		(start 77.738478 -90.599514)
		(mid 78.121891 -90.983308)
		(end 78.505558 -90.599768)
		(stroke
			(width 0.2)
			(type default)
		)
		(layer "In4.Cu")
	)
	(gr_line
		(start 77.738478 -89.710768)
		(end 77.738478 -90.599514)
		(stroke
			(width 0.2)
			(type default)
		)
		(layer "In4.Cu")
	)
	(gr_arc
		(start 77.738478 -84.224114)
		(mid 78.121891 -84.607908)
		(end 78.505558 -84.224368)
		(stroke
			(width 0.2)
			(type default)
		)
		(layer "In4.Cu")
	)
	(gr_line
		(start 77.738478 -83.335368)
		(end 77.738478 -84.224114)
		(stroke
			(width 0.2)
			(type default)
		)
		(layer "In4.Cu")
	)
	(gr_arc
		(start 77.738478 -77.797914)
		(mid 78.121891 -78.181708)
		(end 78.505558 -77.798168)
		(stroke
			(width 0.2)
			(type default)
		)
		(layer "In4.Cu")
	)
	(gr_line
		(start 77.738478 -76.909168)
		(end 77.738478 -77.797914)
		(stroke
			(width 0.2)
			(type default)
		)
		(layer "In4.Cu")
	)
	(gr_arc
		(start 77.738478 -71.397114)
		(mid 78.121891 -71.780908)
		(end 78.505558 -71.397368)
		(stroke
			(width 0.2)
			(type default)
		)
		(layer "In4.Cu")
	)
	(gr_line
		(start 77.738478 -70.508368)
		(end 77.738478 -71.397114)
		(stroke
			(width 0.2)
			(type default)
		)
		(layer "In4.Cu")
	)
	(gr_line
		(start 78.024482 -114.2746)
		(end 72.056498 -120.242584)
		(stroke
			(width 0.381)
			(type default)
		)
		(layer "In4.Cu")
	)
	(gr_line
		(start 78.505558 -90.599768)
		(end 78.505558 -89.710768)
		(stroke
			(width 0.2)
			(type default)
		)
		(layer "In4.Cu")
	)
	(gr_arc
		(start 78.505558 -89.710768)
		(mid 78.122018 -89.327228)
		(end 77.738478 -89.710768)
		(stroke
			(width 0.2)
			(type default)
		)
		(layer "In4.Cu")
	)
	(gr_line
		(start 78.505558 -84.224368)
		(end 78.505558 -83.335368)
		(stroke
			(width 0.2)
			(type default)
		)
		(layer "In4.Cu")
	)
	(gr_arc
		(start 78.505558 -83.335368)
		(mid 78.122018 -82.951828)
		(end 77.738478 -83.335368)
		(stroke
			(width 0.2)
			(type default)
		)
		(layer "In4.Cu")
	)
	(gr_line
		(start 78.505558 -77.798168)
		(end 78.505558 -76.909168)
		(stroke
			(width 0.2)
			(type default)
		)
		(layer "In4.Cu")
	)
	(gr_arc
		(start 78.505558 -76.909168)
		(mid 78.122018 -76.525628)
		(end 77.738478 -76.909168)
		(stroke
			(width 0.2)
			(type default)
		)
		(layer "In4.Cu")
	)
	(gr_line
		(start 78.505558 -71.397368)
		(end 78.505558 -70.508368)
		(stroke
			(width 0.2)
			(type default)
		)
		(layer "In4.Cu")
	)
	(gr_arc
		(start 78.505558 -70.508368)
		(mid 78.122018 -70.124828)
		(end 77.738478 -70.508368)
		(stroke
			(width 0.2)
			(type default)
		)
		(layer "In4.Cu")
	)
	(gr_line
		(start 78.8162 -153.4414)
		(end 78.8162 -138.811)
		(stroke
			(width 0.381)
			(type default)
		)
		(layer "In4.Cu")
	)
	(gr_line
		(start 78.8162 -138.811)
		(end 72.146922 -132.141722)
		(stroke
			(width 0.381)
			(type default)
		)
		(layer "In4.Cu")
	)
	(gr_line
		(start 80.772 -164.719)
		(end 80.772 -159.258)
		(stroke
			(width 0.381)
			(type default)
		)
		(layer "In4.Cu")
	)
	(gr_line
		(start 80.772 -164.18179)
		(end 80.23479 -164.719)
		(stroke
			(width 0.381)
			(type default)
		)
		(layer "In4.Cu")
	)
	(gr_line
		(start 80.772 -159.258)
		(end 81.28 -158.75)
		(stroke
			(width 0.381)
			(type default)
		)
		(layer "In4.Cu")
	)
	(gr_line
		(start 81.28 -158.75)
		(end 86.5378 -158.75)
		(stroke
			(width 0.381)
			(type default)
		)
		(layer "In4.Cu")
	)
	(gr_line
		(start 81.30921 -164.719)
		(end 80.772 -164.18179)
		(stroke
			(width 0.381)
			(type default)
		)
		(layer "In4.Cu")
	)
	(gr_arc
		(start 82.974688 -95.381318)
		(mid 83.358101 -95.765112)
		(end 83.741768 -95.381572)
		(stroke
			(width 0.2)
			(type default)
		)
		(layer "In4.Cu")
	)
	(gr_line
		(start 82.974688 -94.492572)
		(end 82.974688 -95.381318)
		(stroke
			(width 0.2)
			(type default)
		)
		(layer "In4.Cu")
	)
	(gr_arc
		(start 82.974688 -88.994234)
		(mid 83.358228 -89.377774)
		(end 83.741768 -88.994234)
		(stroke
			(width 0.2)
			(type default)
		)
		(layer "In4.Cu")
	)
	(gr_line
		(start 82.974688 -88.105234)
		(end 82.974688 -88.994234)
		(stroke
			(width 0.2)
			(type default)
		)
		(layer "In4.Cu")
	)
	(gr_arc
		(start 82.974688 -82.593942)
		(mid 83.358101 -82.977736)
		(end 83.741768 -82.594196)
		(stroke
			(width 0.2)
			(type default)
		)
		(layer "In4.Cu")
	)
	(gr_line
		(start 82.974688 -81.705196)
		(end 82.974688 -82.593942)
		(stroke
			(width 0.2)
			(type default)
		)
		(layer "In4.Cu")
	)
	(gr_arc
		(start 82.974688 -76.193904)
		(mid 83.358101 -76.577698)
		(end 83.741768 -76.194158)
		(stroke
			(width 0.2)
			(type default)
		)
		(layer "In4.Cu")
	)
	(gr_line
		(start 82.974688 -75.305158)
		(end 82.974688 -76.193904)
		(stroke
			(width 0.2)
			(type default)
		)
		(layer "In4.Cu")
	)
	(gr_line
		(start 83.5152 -164.719)
		(end 84.5312 -165.735)
		(stroke
			(width 0.381)
			(type default)
		)
		(layer "In4.Cu")
	)
	(gr_line
		(start 83.590384 -114.2746)
		(end 78.024482 -114.2746)
		(stroke
			(width 0.381)
			(type default)
		)
		(layer "In4.Cu")
	)
	(gr_line
		(start 83.741768 -95.381572)
		(end 83.741768 -94.492572)
		(stroke
			(width 0.2)
			(type default)
		)
		(layer "In4.Cu")
	)
	(gr_arc
		(start 83.741768 -94.492572)
		(mid 83.358228 -94.109032)
		(end 82.974688 -94.492572)
		(stroke
			(width 0.2)
			(type default)
		)
		(layer "In4.Cu")
	)
	(gr_line
		(start 83.741768 -88.994234)
		(end 83.741768 -88.105488)
		(stroke
			(width 0.2)
			(type default)
		)
		(layer "In4.Cu")
	)
	(gr_arc
		(start 83.741768 -88.105488)
		(mid 83.358355 -87.721694)
		(end 82.974688 -88.105234)
		(stroke
			(width 0.2)
			(type default)
		)
		(layer "In4.Cu")
	)
	(gr_line
		(start 83.741768 -82.594196)
		(end 83.741768 -81.705196)
		(stroke
			(width 0.2)
			(type default)
		)
		(layer "In4.Cu")
	)
	(gr_arc
		(start 83.741768 -81.705196)
		(mid 83.358228 -81.321656)
		(end 82.974688 -81.705196)
		(stroke
			(width 0.2)
			(type default)
		)
		(layer "In4.Cu")
	)
	(gr_line
		(start 83.741768 -76.194158)
		(end 83.741768 -75.305158)
		(stroke
			(width 0.2)
			(type default)
		)
		(layer "In4.Cu")
	)
	(gr_arc
		(start 83.741768 -75.305158)
		(mid 83.358228 -74.921618)
		(end 82.974688 -75.305158)
		(stroke
			(width 0.2)
			(type default)
		)
		(layer "In4.Cu")
	)
	(gr_line
		(start 83.977734 -192.958466)
		(end 84.4931 -192.4431)
		(stroke
			(width 0.381)
			(type default)
		)
		(layer "In4.Cu")
	)
	(gr_line
		(start 84.091018 -96.96323)
		(end 88.773 -101.645212)
		(stroke
			(width 0.381)
			(type default)
		)
		(layer "In4.Cu")
	)
	(gr_line
		(start 84.091018 -9.446514)
		(end 84.091018 -96.96323)
		(stroke
			(width 0.381)
			(type default)
		)
		(layer "In4.Cu")
	)
	(gr_line
		(start 84.5312 -193.49974)
		(end 84.59216 -193.5607)
		(stroke
			(width 0.381)
			(type default)
		)
		(layer "In4.Cu")
	)
	(gr_line
		(start 84.5312 -182.05069)
		(end 85.04809 -181.5338)
		(stroke
			(width 0.381)
			(type default)
		)
		(layer "In4.Cu")
	)
	(gr_line
		(start 84.5312 -165.735)
		(end 84.5312 -193.49974)
		(stroke
			(width 0.381)
			(type default)
		)
		(layer "In4.Cu")
	)
	(gr_arc
		(start 84.600288 -92.195142)
		(mid 84.983701 -92.578936)
		(end 85.367368 -92.195396)
		(stroke
			(width 0.2)
			(type default)
		)
		(layer "In4.Cu")
	)
	(gr_line
		(start 84.600288 -91.306396)
		(end 84.600288 -92.195142)
		(stroke
			(width 0.2)
			(type default)
		)
		(layer "In4.Cu")
	)
	(gr_arc
		(start 84.600288 -85.79358)
		(mid 84.983701 -86.177374)
		(end 85.367368 -85.793834)
		(stroke
			(width 0.2)
			(type default)
		)
		(layer "In4.Cu")
	)
	(gr_line
		(start 84.600288 -84.904834)
		(end 84.600288 -85.79358)
		(stroke
			(width 0.2)
			(type default)
		)
		(layer "In4.Cu")
	)
	(gr_arc
		(start 84.600288 -79.393542)
		(mid 84.983701 -79.777336)
		(end 85.367368 -79.393796)
		(stroke
			(width 0.2)
			(type default)
		)
		(layer "In4.Cu")
	)
	(gr_line
		(start 84.600288 -78.504796)
		(end 84.600288 -79.393542)
		(stroke
			(width 0.2)
			(type default)
		)
		(layer "In4.Cu")
	)
	(gr_arc
		(start 84.600288 -72.970136)
		(mid 84.983828 -73.353676)
		(end 85.367368 -72.970136)
		(stroke
			(width 0.2)
			(type default)
		)
		(layer "In4.Cu")
	)
	(gr_line
		(start 84.600288 -72.081136)
		(end 84.600288 -72.970136)
		(stroke
			(width 0.2)
			(type default)
		)
		(layer "In4.Cu")
	)
	(gr_line
		(start 85.04809 -181.5338)
		(end 84.5312 -181.01691)
		(stroke
			(width 0.381)
			(type default)
		)
		(layer "In4.Cu")
	)
	(gr_line
		(start 85.084666 -192.958466)
		(end 84.5439 -192.4177)
		(stroke
			(width 0.381)
			(type default)
		)
		(layer "In4.Cu")
	)
	(gr_line
		(start 85.367368 -92.195396)
		(end 85.367368 -91.306396)
		(stroke
			(width 0.2)
			(type default)
		)
		(layer "In4.Cu")
	)
	(gr_arc
		(start 85.367368 -91.306396)
		(mid 84.983828 -90.922856)
		(end 84.600288 -91.306396)
		(stroke
			(width 0.2)
			(type default)
		)
		(layer "In4.Cu")
	)
	(gr_line
		(start 85.367368 -85.793834)
		(end 85.367368 -84.904834)
		(stroke
			(width 0.2)
			(type default)
		)
		(layer "In4.Cu")
	)
	(gr_arc
		(start 85.367368 -84.904834)
		(mid 84.983828 -84.521294)
		(end 84.600288 -84.904834)
		(stroke
			(width 0.2)
			(type default)
		)
		(layer "In4.Cu")
	)
	(gr_line
		(start 85.367368 -79.393796)
		(end 85.367368 -78.504796)
		(stroke
			(width 0.2)
			(type default)
		)
		(layer "In4.Cu")
	)
	(gr_arc
		(start 85.367368 -78.504796)
		(mid 84.983828 -78.121256)
		(end 84.600288 -78.504796)
		(stroke
			(width 0.2)
			(type default)
		)
		(layer "In4.Cu")
	)
	(gr_line
		(start 85.367368 -72.970136)
		(end 85.367368 -72.08139)
		(stroke
			(width 0.2)
			(type default)
		)
		(layer "In4.Cu")
	)
	(gr_arc
		(start 85.367368 -72.08139)
		(mid 84.983955 -71.697596)
		(end 84.600288 -72.081136)
		(stroke
			(width 0.2)
			(type default)
		)
		(layer "In4.Cu")
	)
	(gr_line
		(start 86.5378 -158.75)
		(end 89.3318 -155.956)
		(stroke
			(width 0.381)
			(type default)
		)
		(layer "In4.Cu")
	)
	(gr_line
		(start 87.249 -181.5338)
		(end 84.554568 -181.5338)
		(stroke
			(width 0.381)
			(type default)
		)
		(layer "In4.Cu")
	)
	(gr_line
		(start 88.0872 -182.372)
		(end 87.249 -181.5338)
		(stroke
			(width 0.381)
			(type default)
		)
		(layer "In4.Cu")
	)
	(gr_line
		(start 88.143842 -5.39369)
		(end 84.091018 -9.446514)
		(stroke
			(width 0.381)
			(type default)
		)
		(layer "In4.Cu")
	)
	(gr_line
		(start 88.773 -109.091984)
		(end 83.590384 -114.2746)
		(stroke
			(width 0.381)
			(type default)
		)
		(layer "In4.Cu")
	)
	(gr_line
		(start 88.773 -101.645212)
		(end 88.773 -109.091984)
		(stroke
			(width 0.381)
			(type default)
		)
		(layer "In4.Cu")
	)
	(gr_line
		(start 88.9508 -182.372)
		(end 88.0872 -182.372)
		(stroke
			(width 0.381)
			(type default)
		)
		(layer "In4.Cu")
	)
	(gr_line
		(start 89.3318 -155.956)
		(end 89.3318 -154.6352)
		(stroke
			(width 0.381)
			(type default)
		)
		(layer "In4.Cu")
	)
	(gr_line
		(start 89.3318 -154.6352)
		(end 93.726 -150.241)
		(stroke
			(width 0.381)
			(type default)
		)
		(layer "In4.Cu")
	)
	(gr_line
		(start 89.789 -181.5338)
		(end 88.9508 -182.372)
		(stroke
			(width 0.381)
			(type default)
		)
		(layer "In4.Cu")
	)
	(gr_line
		(start 93.726 -150.241)
		(end 99.5934 -150.241)
		(stroke
			(width 0.381)
			(type default)
		)
		(layer "In4.Cu")
	)
	(gr_line
		(start 98.081846 -194.00012)
		(end 5.617972 -194.00012)
		(stroke
			(width 2.54)
			(type default)
		)
		(layer "In4.Cu")
	)
	(gr_arc
		(start 98.081846 -194.00012)
		(mid 98.607706 -193.850755)
		(end 98.976434 -193.447162)
		(stroke
			(width 2.54)
			(type default)
		)
		(layer "In4.Cu")
	)
	(gr_line
		(start 99.5934 -150.241)
		(end 100.6094 -151.257)
		(stroke
			(width 0.381)
			(type default)
		)
		(layer "In4.Cu")
	)
	(gr_line
		(start 100.1268 -181.5338)
		(end 89.789 -181.5338)
		(stroke
			(width 0.381)
			(type default)
		)
		(layer "In4.Cu")
	)
	(gr_line
		(start 100.6094 -181.0512)
		(end 100.1268 -181.5338)
		(stroke
			(width 0.381)
			(type default)
		)
		(layer "In4.Cu")
	)
	(gr_line
		(start 100.6094 -151.257)
		(end 100.6094 -181.0512)
		(stroke
			(width 0.381)
			(type default)
		)
		(layer "In4.Cu")
	)
	(gr_line
		(start 103.594408 -184.211214)
		(end 98.976434 -193.447162)
		(stroke
			(width 2.54)
			(type default)
		)
		(layer "In4.Cu")
	)
	(gr_arc
		(start 103.594408 -184.211214)
		(mid 103.673311 -183.993725)
		(end 103.700072 -183.76392)
		(stroke
			(width 2.54)
			(type default)
		)
		(layer "In4.Cu")
	)
	(gr_line
		(start 103.700072 -47.999904)
		(end 103.700072 -183.76392)
		(stroke
			(width 2.54)
			(type default)
		)
		(layer "In4.Cu")
	)
	(gr_arc
		(start 104.70007 -47.999904)
		(mid 104.200198 -47.500032)
		(end 103.700072 -47.999904)
		(stroke
			(width 2.54)
			(type default)
		)
		(layer "In4.Cu")
	)
	(gr_line
		(start 105.392982 -5.39369)
		(end 88.143842 -5.39369)
		(stroke
			(width 0.381)
			(type default)
		)
		(layer "In4.Cu")
	)
	(gr_arc
		(start 106.614722 -38.200076)
		(mid 107.099862 -38.685216)
		(end 107.585002 -38.200076)
		(stroke
			(width 0.2)
			(type default)
		)
		(layer "In4.Cu")
	)
	(gr_line
		(start 106.614722 -36.800028)
		(end 106.614722 -38.200076)
		(stroke
			(width 0.2)
			(type default)
		)
		(layer "In4.Cu")
	)
	(gr_arc
		(start 106.614722 -34.600134)
		(mid 107.099862 -35.085274)
		(end 107.585002 -34.600134)
		(stroke
			(width 0.2)
			(type default)
		)
		(layer "In4.Cu")
	)
	(gr_line
		(start 106.614722 -33.200086)
		(end 106.614722 -34.600134)
		(stroke
			(width 0.2)
			(type default)
		)
		(layer "In4.Cu")
	)
	(gr_line
		(start 107.585002 -38.200076)
		(end 107.585002 -36.800282)
		(stroke
			(width 0.2)
			(type default)
		)
		(layer "In4.Cu")
	)
	(gr_arc
		(start 107.585002 -36.800282)
		(mid 107.099989 -36.314888)
		(end 106.614722 -36.800028)
		(stroke
			(width 0.2)
			(type default)
		)
		(layer "In4.Cu")
	)
	(gr_line
		(start 107.585002 -34.600134)
		(end 107.585002 -33.20034)
		(stroke
			(width 0.2)
			(type default)
		)
		(layer "In4.Cu")
	)
	(gr_arc
		(start 107.585002 -33.20034)
		(mid 107.099989 -32.714946)
		(end 106.614722 -33.200086)
		(stroke
			(width 0.2)
			(type default)
		)
		(layer "In4.Cu")
	)
	(gr_arc
		(start 108.41482 -37.00018)
		(mid 108.89996 -37.48532)
		(end 109.3851 -37.00018)
		(stroke
			(width 0.2)
			(type default)
		)
		(layer "In4.Cu")
	)
	(gr_line
		(start 108.41482 -35.600132)
		(end 108.41482 -37.00018)
		(stroke
			(width 0.2)
			(type default)
		)
		(layer "In4.Cu")
	)
	(gr_arc
		(start 108.41482 -33.399984)
		(mid 108.89996 -33.885124)
		(end 109.3851 -33.399984)
		(stroke
			(width 0.2)
			(type default)
		)
		(layer "In4.Cu")
	)
	(gr_line
		(start 108.41482 -32.00019)
		(end 108.41482 -33.399984)
		(stroke
			(width 0.2)
			(type default)
		)
		(layer "In4.Cu")
	)
	(gr_line
		(start 109.3851 -37.00018)
		(end 109.3851 -35.600386)
		(stroke
			(width 0.2)
			(type default)
		)
		(layer "In4.Cu")
	)
	(gr_arc
		(start 109.3851 -35.600386)
		(mid 108.900087 -35.114992)
		(end 108.41482 -35.600132)
		(stroke
			(width 0.2)
			(type default)
		)
		(layer "In4.Cu")
	)
	(gr_line
		(start 109.3851 -33.399984)
		(end 109.3851 -32.000444)
		(stroke
			(width 0.2)
			(type default)
		)
		(layer "In4.Cu")
	)
	(gr_arc
		(start 109.3851 -32.000444)
		(mid 108.900087 -31.51505)
		(end 108.41482 -32.00019)
		(stroke
			(width 0.2)
			(type default)
		)
		(layer "In4.Cu")
	)
	(gr_arc
		(start 110.214918 -38.200076)
		(mid 110.700058 -38.685216)
		(end 111.185198 -38.200076)
		(stroke
			(width 0.2)
			(type default)
		)
		(layer "In4.Cu")
	)
	(gr_line
		(start 110.214918 -36.800028)
		(end 110.214918 -38.200076)
		(stroke
			(width 0.2)
			(type default)
		)
		(layer "In4.Cu")
	)
	(gr_arc
		(start 110.214918 -34.600134)
		(mid 110.700058 -35.085274)
		(end 111.185198 -34.600134)
		(stroke
			(width 0.2)
			(type default)
		)
		(layer "In4.Cu")
	)
	(gr_line
		(start 110.214918 -33.200086)
		(end 110.214918 -34.600134)
		(stroke
			(width 0.2)
			(type default)
		)
		(layer "In4.Cu")
	)
	(gr_line
		(start 111.185198 -38.200076)
		(end 111.185198 -36.800282)
		(stroke
			(width 0.2)
			(type default)
		)
		(layer "In4.Cu")
	)
	(gr_arc
		(start 111.185198 -36.800282)
		(mid 110.700185 -36.314888)
		(end 110.214918 -36.800028)
		(stroke
			(width 0.2)
			(type default)
		)
		(layer "In4.Cu")
	)
	(gr_line
		(start 111.185198 -34.600134)
		(end 111.185198 -33.20034)
		(stroke
			(width 0.2)
			(type default)
		)
		(layer "In4.Cu")
	)
	(gr_arc
		(start 111.185198 -33.20034)
		(mid 110.700185 -32.714946)
		(end 110.214918 -33.200086)
		(stroke
			(width 0.2)
			(type default)
		)
		(layer "In4.Cu")
	)
	(gr_line
		(start 111.251492 -11.2522)
		(end 105.392982 -5.39369)
		(stroke
			(width 0.381)
			(type default)
		)
		(layer "In4.Cu")
	)
	(gr_arc
		(start 112.014762 -37.00018)
		(mid 112.499902 -37.48532)
		(end 112.985042 -37.00018)
		(stroke
			(width 0.2)
			(type default)
		)
		(layer "In4.Cu")
	)
	(gr_line
		(start 112.014762 -35.600132)
		(end 112.014762 -37.00018)
		(stroke
			(width 0.2)
			(type default)
		)
		(layer "In4.Cu")
	)
	(gr_arc
		(start 112.014762 -33.399984)
		(mid 112.499902 -33.885124)
		(end 112.985042 -33.399984)
		(stroke
			(width 0.2)
			(type default)
		)
		(layer "In4.Cu")
	)
	(gr_line
		(start 112.014762 -32.00019)
		(end 112.014762 -33.399984)
		(stroke
			(width 0.2)
			(type default)
		)
		(layer "In4.Cu")
	)
	(gr_line
		(start 112.985042 -37.00018)
		(end 112.985042 -35.600386)
		(stroke
			(width 0.2)
			(type default)
		)
		(layer "In4.Cu")
	)
	(gr_arc
		(start 112.985042 -35.600386)
		(mid 112.500029 -35.114992)
		(end 112.014762 -35.600132)
		(stroke
			(width 0.2)
			(type default)
		)
		(layer "In4.Cu")
	)
	(gr_line
		(start 112.985042 -33.399984)
		(end 112.985042 -32.000444)
		(stroke
			(width 0.2)
			(type default)
		)
		(layer "In4.Cu")
	)
	(gr_arc
		(start 112.985042 -32.000444)
		(mid 112.500029 -31.51505)
		(end 112.014762 -32.00019)
		(stroke
			(width 0.2)
			(type default)
		)
		(layer "In4.Cu")
	)
	(gr_arc
		(start 113.81486 -38.200076)
		(mid 114.3 -38.685216)
		(end 114.78514 -38.200076)
		(stroke
			(width 0.2)
			(type default)
		)
		(layer "In4.Cu")
	)
	(gr_line
		(start 113.81486 -36.800028)
		(end 113.81486 -38.200076)
		(stroke
			(width 0.2)
			(type default)
		)
		(layer "In4.Cu")
	)
	(gr_arc
		(start 113.81486 -34.600134)
		(mid 114.3 -35.085274)
		(end 114.78514 -34.600134)
		(stroke
			(width 0.2)
			(type default)
		)
		(layer "In4.Cu")
	)
	(gr_line
		(start 113.81486 -33.200086)
		(end 113.81486 -34.600134)
		(stroke
			(width 0.2)
			(type default)
		)
		(layer "In4.Cu")
	)
	(gr_line
		(start 114.78514 -38.200076)
		(end 114.78514 -36.800282)
		(stroke
			(width 0.2)
			(type default)
		)
		(layer "In4.Cu")
	)
	(gr_arc
		(start 114.78514 -36.800282)
		(mid 114.300127 -36.314888)
		(end 113.81486 -36.800028)
		(stroke
			(width 0.2)
			(type default)
		)
		(layer "In4.Cu")
	)
	(gr_line
		(start 114.78514 -34.600134)
		(end 114.78514 -33.20034)
		(stroke
			(width 0.2)
			(type default)
		)
		(layer "In4.Cu")
	)
	(gr_arc
		(start 114.78514 -33.20034)
		(mid 114.300127 -32.714946)
		(end 113.81486 -33.200086)
		(stroke
			(width 0.2)
			(type default)
		)
		(layer "In4.Cu")
	)
	(gr_arc
		(start 115.614704 -37.00018)
		(mid 116.099844 -37.48532)
		(end 116.584984 -37.00018)
		(stroke
			(width 0.2)
			(type default)
		)
		(layer "In4.Cu")
	)
	(gr_line
		(start 115.614704 -35.600132)
		(end 115.614704 -37.00018)
		(stroke
			(width 0.2)
			(type default)
		)
		(layer "In4.Cu")
	)
	(gr_arc
		(start 115.614704 -33.399984)
		(mid 116.099844 -33.885124)
		(end 116.584984 -33.399984)
		(stroke
			(width 0.2)
			(type default)
		)
		(layer "In4.Cu")
	)
	(gr_line
		(start 115.614704 -32.00019)
		(end 115.614704 -33.399984)
		(stroke
			(width 0.2)
			(type default)
		)
		(layer "In4.Cu")
	)
	(gr_line
		(start 116.584984 -37.00018)
		(end 116.584984 -35.600386)
		(stroke
			(width 0.2)
			(type default)
		)
		(layer "In4.Cu")
	)
	(gr_arc
		(start 116.584984 -35.600386)
		(mid 116.099971 -35.114992)
		(end 115.614704 -35.600132)
		(stroke
			(width 0.2)
			(type default)
		)
		(layer "In4.Cu")
	)
	(gr_line
		(start 116.584984 -33.399984)
		(end 116.584984 -32.000444)
		(stroke
			(width 0.2)
			(type default)
		)
		(layer "In4.Cu")
	)
	(gr_arc
		(start 116.584984 -32.000444)
		(mid 116.099971 -31.51505)
		(end 115.614704 -32.00019)
		(stroke
			(width 0.2)
			(type default)
		)
		(layer "In4.Cu")
	)
	(gr_arc
		(start 117.414802 -38.200076)
		(mid 117.899942 -38.685216)
		(end 118.385082 -38.200076)
		(stroke
			(width 0.2)
			(type default)
		)
		(layer "In4.Cu")
	)
	(gr_line
		(start 117.414802 -36.800028)
		(end 117.414802 -38.200076)
		(stroke
			(width 0.2)
			(type default)
		)
		(layer "In4.Cu")
	)
	(gr_arc
		(start 117.414802 -34.600134)
		(mid 117.899942 -35.085274)
		(end 118.385082 -34.600134)
		(stroke
			(width 0.2)
			(type default)
		)
		(layer "In4.Cu")
	)
	(gr_line
		(start 117.414802 -33.200086)
		(end 117.414802 -34.600134)
		(stroke
			(width 0.2)
			(type default)
		)
		(layer "In4.Cu")
	)
	(gr_line
		(start 118.385082 -38.200076)
		(end 118.385082 -36.800282)
		(stroke
			(width 0.2)
			(type default)
		)
		(layer "In4.Cu")
	)
	(gr_arc
		(start 118.385082 -36.800282)
		(mid 117.900069 -36.314888)
		(end 117.414802 -36.800028)
		(stroke
			(width 0.2)
			(type default)
		)
		(layer "In4.Cu")
	)
	(gr_line
		(start 118.385082 -34.600134)
		(end 118.385082 -33.20034)
		(stroke
			(width 0.2)
			(type default)
		)
		(layer "In4.Cu")
	)
	(gr_arc
		(start 118.385082 -33.20034)
		(mid 117.900069 -32.714946)
		(end 117.414802 -33.200086)
		(stroke
			(width 0.2)
			(type default)
		)
		(layer "In4.Cu")
	)
	(gr_arc
		(start 119.2149 -37.00018)
		(mid 119.70004 -37.48532)
		(end 120.18518 -37.00018)
		(stroke
			(width 0.2)
			(type default)
		)
		(layer "In4.Cu")
	)
	(gr_line
		(start 119.2149 -35.600132)
		(end 119.2149 -37.00018)
		(stroke
			(width 0.2)
			(type default)
		)
		(layer "In4.Cu")
	)
	(gr_arc
		(start 119.2149 -33.399984)
		(mid 119.70004 -33.885124)
		(end 120.18518 -33.399984)
		(stroke
			(width 0.2)
			(type default)
		)
		(layer "In4.Cu")
	)
	(gr_line
		(start 119.2149 -32.00019)
		(end 119.2149 -33.399984)
		(stroke
			(width 0.2)
			(type default)
		)
		(layer "In4.Cu")
	)
	(gr_line
		(start 120.18518 -37.00018)
		(end 120.18518 -35.600386)
		(stroke
			(width 0.2)
			(type default)
		)
		(layer "In4.Cu")
	)
	(gr_arc
		(start 120.18518 -35.600386)
		(mid 119.700167 -35.114992)
		(end 119.2149 -35.600132)
		(stroke
			(width 0.2)
			(type default)
		)
		(layer "In4.Cu")
	)
	(gr_line
		(start 120.18518 -33.399984)
		(end 120.18518 -32.000444)
		(stroke
			(width 0.2)
			(type default)
		)
		(layer "In4.Cu")
	)
	(gr_arc
		(start 120.18518 -32.000444)
		(mid 119.700167 -31.51505)
		(end 119.2149 -32.00019)
		(stroke
			(width 0.2)
			(type default)
		)
		(layer "In4.Cu")
	)
	(gr_arc
		(start 128.214882 -38.200076)
		(mid 128.700022 -38.685216)
		(end 129.185162 -38.200076)
		(stroke
			(width 0.2)
			(type default)
		)
		(layer "In4.Cu")
	)
	(gr_line
		(start 128.214882 -36.800028)
		(end 128.214882 -38.200076)
		(stroke
			(width 0.2)
			(type default)
		)
		(layer "In4.Cu")
	)
	(gr_arc
		(start 128.214882 -34.600134)
		(mid 128.700022 -35.085274)
		(end 129.185162 -34.600134)
		(stroke
			(width 0.2)
			(type default)
		)
		(layer "In4.Cu")
	)
	(gr_line
		(start 128.214882 -33.200086)
		(end 128.214882 -34.600134)
		(stroke
			(width 0.2)
			(type default)
		)
		(layer "In4.Cu")
	)
	(gr_line
		(start 128.858518 -11.2522)
		(end 111.251492 -11.2522)
		(stroke
			(width 0.381)
			(type default)
		)
		(layer "In4.Cu")
	)
	(gr_line
		(start 129.185162 -38.200076)
		(end 129.185162 -36.800282)
		(stroke
			(width 0.2)
			(type default)
		)
		(layer "In4.Cu")
	)
	(gr_arc
		(start 129.185162 -36.800282)
		(mid 128.700149 -36.314888)
		(end 128.214882 -36.800028)
		(stroke
			(width 0.2)
			(type default)
		)
		(layer "In4.Cu")
	)
	(gr_line
		(start 129.185162 -34.600134)
		(end 129.185162 -33.20034)
		(stroke
			(width 0.2)
			(type default)
		)
		(layer "In4.Cu")
	)
	(gr_arc
		(start 129.185162 -33.20034)
		(mid 128.700149 -32.714946)
		(end 128.214882 -33.200086)
		(stroke
			(width 0.2)
			(type default)
		)
		(layer "In4.Cu")
	)
	(gr_line
		(start 129.495296 -11.888978)
		(end 128.858518 -11.2522)
		(stroke
			(width 0.381)
			(type default)
		)
		(layer "In4.Cu")
	)
	(gr_arc
		(start 130.014726 -37.00018)
		(mid 130.499866 -37.48532)
		(end 130.985006 -37.00018)
		(stroke
			(width 0.2)
			(type default)
		)
		(layer "In4.Cu")
	)
	(gr_line
		(start 130.014726 -35.600132)
		(end 130.014726 -37.00018)
		(stroke
			(width 0.2)
			(type default)
		)
		(layer "In4.Cu")
	)
	(gr_arc
		(start 130.014726 -33.399984)
		(mid 130.499866 -33.885124)
		(end 130.985006 -33.399984)
		(stroke
			(width 0.2)
			(type default)
		)
		(layer "In4.Cu")
	)
	(gr_line
		(start 130.014726 -32.00019)
		(end 130.014726 -33.399984)
		(stroke
			(width 0.2)
			(type default)
		)
		(layer "In4.Cu")
	)
	(gr_line
		(start 130.985006 -37.00018)
		(end 130.985006 -35.600386)
		(stroke
			(width 0.2)
			(type default)
		)
		(layer "In4.Cu")
	)
	(gr_arc
		(start 130.985006 -35.600386)
		(mid 130.499993 -35.114992)
		(end 130.014726 -35.600132)
		(stroke
			(width 0.2)
			(type default)
		)
		(layer "In4.Cu")
	)
	(gr_line
		(start 130.985006 -33.399984)
		(end 130.985006 -32.000444)
		(stroke
			(width 0.2)
			(type default)
		)
		(layer "In4.Cu")
	)
	(gr_arc
		(start 130.985006 -32.000444)
		(mid 130.499993 -31.51505)
		(end 130.014726 -32.00019)
		(stroke
			(width 0.2)
			(type default)
		)
		(layer "In4.Cu")
	)
	(gr_arc
		(start 131.814824 -38.200076)
		(mid 132.299964 -38.685216)
		(end 132.785104 -38.200076)
		(stroke
			(width 0.2)
			(type default)
		)
		(layer "In4.Cu")
	)
	(gr_line
		(start 131.814824 -36.800028)
		(end 131.814824 -38.200076)
		(stroke
			(width 0.2)
			(type default)
		)
		(layer "In4.Cu")
	)
	(gr_arc
		(start 131.814824 -34.600134)
		(mid 132.299964 -35.085274)
		(end 132.785104 -34.600134)
		(stroke
			(width 0.2)
			(type default)
		)
		(layer "In4.Cu")
	)
	(gr_line
		(start 131.814824 -33.200086)
		(end 131.814824 -34.600134)
		(stroke
			(width 0.2)
			(type default)
		)
		(layer "In4.Cu")
	)
	(gr_line
		(start 132.785104 -38.200076)
		(end 132.785104 -36.800282)
		(stroke
			(width 0.2)
			(type default)
		)
		(layer "In4.Cu")
	)
	(gr_arc
		(start 132.785104 -36.800282)
		(mid 132.300091 -36.314888)
		(end 131.814824 -36.800028)
		(stroke
			(width 0.2)
			(type default)
		)
		(layer "In4.Cu")
	)
	(gr_line
		(start 132.785104 -34.600134)
		(end 132.785104 -33.20034)
		(stroke
			(width 0.2)
			(type default)
		)
		(layer "In4.Cu")
	)
	(gr_arc
		(start 132.785104 -33.20034)
		(mid 132.300091 -32.714946)
		(end 131.814824 -33.200086)
		(stroke
			(width 0.2)
			(type default)
		)
		(layer "In4.Cu")
	)
	(gr_arc
		(start 133.614922 -37.00018)
		(mid 134.100062 -37.48532)
		(end 134.585202 -37.00018)
		(stroke
			(width 0.2)
			(type default)
		)
		(layer "In4.Cu")
	)
	(gr_line
		(start 133.614922 -35.600132)
		(end 133.614922 -37.00018)
		(stroke
			(width 0.2)
			(type default)
		)
		(layer "In4.Cu")
	)
	(gr_arc
		(start 133.614922 -33.399984)
		(mid 134.100062 -33.885124)
		(end 134.585202 -33.399984)
		(stroke
			(width 0.2)
			(type default)
		)
		(layer "In4.Cu")
	)
	(gr_line
		(start 133.614922 -32.00019)
		(end 133.614922 -33.399984)
		(stroke
			(width 0.2)
			(type default)
		)
		(layer "In4.Cu")
	)
	(gr_line
		(start 134.585202 -37.00018)
		(end 134.585202 -35.600386)
		(stroke
			(width 0.2)
			(type default)
		)
		(layer "In4.Cu")
	)
	(gr_arc
		(start 134.585202 -35.600386)
		(mid 134.100189 -35.114992)
		(end 133.614922 -35.600132)
		(stroke
			(width 0.2)
			(type default)
		)
		(layer "In4.Cu")
	)
	(gr_line
		(start 134.585202 -33.399984)
		(end 134.585202 -32.000444)
		(stroke
			(width 0.2)
			(type default)
		)
		(layer "In4.Cu")
	)
	(gr_arc
		(start 134.585202 -32.000444)
		(mid 134.100189 -31.51505)
		(end 133.614922 -32.00019)
		(stroke
			(width 0.2)
			(type default)
		)
		(layer "In4.Cu")
	)
	(gr_line
		(start 134.814818 -11.888978)
		(end 129.495296 -11.888978)
		(stroke
			(width 0.381)
			(type default)
		)
		(layer "In4.Cu")
	)
	(gr_arc
		(start 135.414766 -38.200076)
		(mid 135.899906 -38.685216)
		(end 136.385046 -38.200076)
		(stroke
			(width 0.2)
			(type default)
		)
		(layer "In4.Cu")
	)
	(gr_line
		(start 135.414766 -36.800028)
		(end 135.414766 -38.200076)
		(stroke
			(width 0.2)
			(type default)
		)
		(layer "In4.Cu")
	)
	(gr_arc
		(start 135.414766 -34.600134)
		(mid 135.899906 -35.085274)
		(end 136.385046 -34.600134)
		(stroke
			(width 0.2)
			(type default)
		)
		(layer "In4.Cu")
	)
	(gr_line
		(start 135.414766 -33.200086)
		(end 135.414766 -34.600134)
		(stroke
			(width 0.2)
			(type default)
		)
		(layer "In4.Cu")
	)
	(gr_line
		(start 136.385046 -38.200076)
		(end 136.385046 -36.800282)
		(stroke
			(width 0.2)
			(type default)
		)
		(layer "In4.Cu")
	)
	(gr_arc
		(start 136.385046 -36.800282)
		(mid 135.900033 -36.314888)
		(end 135.414766 -36.800028)
		(stroke
			(width 0.2)
			(type default)
		)
		(layer "In4.Cu")
	)
	(gr_line
		(start 136.385046 -34.600134)
		(end 136.385046 -33.20034)
		(stroke
			(width 0.2)
			(type default)
		)
		(layer "In4.Cu")
	)
	(gr_arc
		(start 136.385046 -33.20034)
		(mid 135.900033 -32.714946)
		(end 135.414766 -33.200086)
		(stroke
			(width 0.2)
			(type default)
		)
		(layer "In4.Cu")
	)
	(gr_line
		(start 136.97204 -14.0462)
		(end 134.814818 -11.888978)
		(stroke
			(width 0.381)
			(type default)
		)
		(layer "In4.Cu")
	)
	(gr_arc
		(start 137.214864 -37.00018)
		(mid 137.700004 -37.48532)
		(end 138.185144 -37.00018)
		(stroke
			(width 0.2)
			(type default)
		)
		(layer "In4.Cu")
	)
	(gr_line
		(start 137.214864 -35.600132)
		(end 137.214864 -37.00018)
		(stroke
			(width 0.2)
			(type default)
		)
		(layer "In4.Cu")
	)
	(gr_arc
		(start 137.214864 -33.399984)
		(mid 137.700004 -33.885124)
		(end 138.185144 -33.399984)
		(stroke
			(width 0.2)
			(type default)
		)
		(layer "In4.Cu")
	)
	(gr_line
		(start 137.214864 -32.00019)
		(end 137.214864 -33.399984)
		(stroke
			(width 0.2)
			(type default)
		)
		(layer "In4.Cu")
	)
	(gr_line
		(start 138.185144 -37.00018)
		(end 138.185144 -35.600386)
		(stroke
			(width 0.2)
			(type default)
		)
		(layer "In4.Cu")
	)
	(gr_arc
		(start 138.185144 -35.600386)
		(mid 137.700131 -35.114992)
		(end 137.214864 -35.600132)
		(stroke
			(width 0.2)
			(type default)
		)
		(layer "In4.Cu")
	)
	(gr_line
		(start 138.185144 -33.399984)
		(end 138.185144 -32.000444)
		(stroke
			(width 0.2)
			(type default)
		)
		(layer "In4.Cu")
	)
	(gr_arc
		(start 138.185144 -32.000444)
		(mid 137.700131 -31.51505)
		(end 137.214864 -32.00019)
		(stroke
			(width 0.2)
			(type default)
		)
		(layer "In4.Cu")
	)
	(gr_arc
		(start 139.014708 -38.200076)
		(mid 139.499848 -38.685216)
		(end 139.984988 -38.200076)
		(stroke
			(width 0.2)
			(type default)
		)
		(layer "In4.Cu")
	)
	(gr_line
		(start 139.014708 -36.800028)
		(end 139.014708 -38.200076)
		(stroke
			(width 0.2)
			(type default)
		)
		(layer "In4.Cu")
	)
	(gr_arc
		(start 139.014708 -34.600134)
		(mid 139.499848 -35.085274)
		(end 139.984988 -34.600134)
		(stroke
			(width 0.2)
			(type default)
		)
		(layer "In4.Cu")
	)
	(gr_line
		(start 139.014708 -33.200086)
		(end 139.014708 -34.600134)
		(stroke
			(width 0.2)
			(type default)
		)
		(layer "In4.Cu")
	)
	(gr_line
		(start 139.984988 -38.200076)
		(end 139.984988 -36.800282)
		(stroke
			(width 0.2)
			(type default)
		)
		(layer "In4.Cu")
	)
	(gr_arc
		(start 139.984988 -36.800282)
		(mid 139.499975 -36.314888)
		(end 139.014708 -36.800028)
		(stroke
			(width 0.2)
			(type default)
		)
		(layer "In4.Cu")
	)
	(gr_line
		(start 139.984988 -34.600134)
		(end 139.984988 -33.20034)
		(stroke
			(width 0.2)
			(type default)
		)
		(layer "In4.Cu")
	)
	(gr_arc
		(start 139.984988 -33.20034)
		(mid 139.499975 -32.714946)
		(end 139.014708 -33.200086)
		(stroke
			(width 0.2)
			(type default)
		)
		(layer "In4.Cu")
	)
	(gr_arc
		(start 140.814806 -37.00018)
		(mid 141.299946 -37.48532)
		(end 141.785086 -37.00018)
		(stroke
			(width 0.2)
			(type default)
		)
		(layer "In4.Cu")
	)
	(gr_line
		(start 140.814806 -35.600132)
		(end 140.814806 -37.00018)
		(stroke
			(width 0.2)
			(type default)
		)
		(layer "In4.Cu")
	)
	(gr_arc
		(start 140.814806 -33.399984)
		(mid 141.299946 -33.885124)
		(end 141.785086 -33.399984)
		(stroke
			(width 0.2)
			(type default)
		)
		(layer "In4.Cu")
	)
	(gr_line
		(start 140.814806 -32.00019)
		(end 140.814806 -33.399984)
		(stroke
			(width 0.2)
			(type default)
		)
		(layer "In4.Cu")
	)
	(gr_line
		(start 141.1224 -14.0462)
		(end 136.97204 -14.0462)
		(stroke
			(width 0.381)
			(type default)
		)
		(layer "In4.Cu")
	)
	(gr_line
		(start 141.785086 -37.00018)
		(end 141.785086 -35.600386)
		(stroke
			(width 0.2)
			(type default)
		)
		(layer "In4.Cu")
	)
	(gr_arc
		(start 141.785086 -35.600386)
		(mid 141.300073 -35.114992)
		(end 140.814806 -35.600132)
		(stroke
			(width 0.2)
			(type default)
		)
		(layer "In4.Cu")
	)
	(gr_line
		(start 141.785086 -33.399984)
		(end 141.785086 -32.000444)
		(stroke
			(width 0.2)
			(type default)
		)
		(layer "In4.Cu")
	)
	(gr_arc
		(start 141.785086 -32.000444)
		(mid 141.300073 -31.51505)
		(end 140.814806 -32.00019)
		(stroke
			(width 0.2)
			(type default)
		)
		(layer "In4.Cu")
	)
	(gr_line
		(start 142.1384 -15.0622)
		(end 141.1224 -14.0462)
		(stroke
			(width 0.381)
			(type default)
		)
		(layer "In4.Cu")
	)
	(gr_line
		(start 143.299942 -47.999904)
		(end 104.70007 -47.999904)
		(stroke
			(width 2.54)
			(type default)
		)
		(layer "In4.Cu")
	)
	(gr_line
		(start 143.4084 -90.3986)
		(end 143.383 -90.424)
		(stroke
			(width 0.381)
			(type default)
		)
		(layer "In4.Cu")
	)
	(gr_line
		(start 143.9672 -105.2322)
		(end 143.891 -105.156)
		(stroke
			(width 0.381)
			(type default)
		)
		(layer "In4.Cu")
	)
	(gr_line
		(start 144.29994 -183.76392)
		(end 144.29994 -47.999904)
		(stroke
			(width 2.54)
			(type default)
		)
		(layer "In4.Cu")
	)
	(gr_arc
		(start 144.29994 -183.76392)
		(mid 144.326755 -183.993712)
		(end 144.405604 -184.211214)
		(stroke
			(width 2.54)
			(type default)
		)
		(layer "In4.Cu")
	)
	(gr_arc
		(start 144.29994 -47.999904)
		(mid 143.800068 -47.500032)
		(end 143.299942 -47.999904)
		(stroke
			(width 2.54)
			(type default)
		)
		(layer "In4.Cu")
	)
	(gr_line
		(start 145.2372 -105.72369)
		(end 145.75409 -105.2068)
		(stroke
			(width 0.381)
			(type default)
		)
		(layer "In4.Cu")
	)
	(gr_line
		(start 145.2372 -90.99169)
		(end 145.75409 -90.4748)
		(stroke
			(width 0.381)
			(type default)
		)
		(layer "In4.Cu")
	)
	(gr_line
		(start 145.75409 -105.2068)
		(end 145.2372 -104.68991)
		(stroke
			(width 0.381)
			(type default)
		)
		(layer "In4.Cu")
	)
	(gr_line
		(start 145.75409 -90.4748)
		(end 145.2372 -89.95791)
		(stroke
			(width 0.381)
			(type default)
		)
		(layer "In4.Cu")
	)
	(gr_line
		(start 149.023578 -193.447162)
		(end 144.405604 -184.211214)
		(stroke
			(width 2.54)
			(type default)
		)
		(layer "In4.Cu")
	)
	(gr_arc
		(start 149.023578 -193.447162)
		(mid 149.392225 -193.85063)
		(end 149.917912 -194.00012)
		(stroke
			(width 2.54)
			(type default)
		)
		(layer "In4.Cu")
	)
	(gr_circle
		(center 149.9362 -145.8976)
		(end 150.82774 -145.8976)
		(stroke
			(width 0.2)
			(type default)
		)
		(fill no)
		(layer "In4.Cu")
	)
	(gr_line
		(start 150.2156 -90.3986)
		(end 143.4084 -90.3986)
		(stroke
			(width 0.381)
			(type default)
		)
		(layer "In4.Cu")
	)
	(gr_line
		(start 150.8252 -91.0082)
		(end 150.2156 -90.3986)
		(stroke
			(width 0.381)
			(type default)
		)
		(layer "In4.Cu")
	)
	(gr_line
		(start 155.882594 -15.0622)
		(end 142.1384 -15.0622)
		(stroke
			(width 0.381)
			(type default)
		)
		(layer "In4.Cu")
	)
	(gr_line
		(start 157.734 -105.2322)
		(end 143.9672 -105.2322)
		(stroke
			(width 0.381)
			(type default)
		)
		(layer "In4.Cu")
	)
	(gr_line
		(start 158.30931 -12.635484)
		(end 155.882594 -15.0622)
		(stroke
			(width 0.381)
			(type default)
		)
		(layer "In4.Cu")
	)
	(gr_arc
		(start 158.833566 -30.277054)
		(mid 159.027114 -30.916626)
		(end 159.666686 -30.723078)
		(stroke
			(width 0.2)
			(type default)
		)
		(layer "In4.Cu")
	)
	(gr_arc
		(start 158.833566 -26.47696)
		(mid 159.027114 -27.116532)
		(end 159.666686 -26.922984)
		(stroke
			(width 0.2)
			(type default)
		)
		(layer "In4.Cu")
	)
	(gr_arc
		(start 158.833566 -18.877026)
		(mid 159.027114 -19.516598)
		(end 159.666686 -19.32305)
		(stroke
			(width 0.2)
			(type default)
		)
		(layer "In4.Cu")
	)
	(gr_arc
		(start 158.836614 -22.671278)
		(mid 159.024316 -23.31492)
		(end 159.666686 -23.12289)
		(stroke
			(width 0.2)
			(type default)
		)
		(layer "In4.Cu")
	)
	(gr_line
		(start 159.583374 -28.877006)
		(end 158.833566 -30.277054)
		(stroke
			(width 0.2)
			(type default)
		)
		(layer "In4.Cu")
	)
	(gr_line
		(start 159.583374 -25.076912)
		(end 158.833566 -26.47696)
		(stroke
			(width 0.2)
			(type default)
		)
		(layer "In4.Cu")
	)
	(gr_line
		(start 159.583374 -21.277072)
		(end 158.836614 -22.671278)
		(stroke
			(width 0.2)
			(type default)
		)
		(layer "In4.Cu")
	)
	(gr_line
		(start 159.583374 -17.476978)
		(end 158.833566 -18.877026)
		(stroke
			(width 0.2)
			(type default)
		)
		(layer "In4.Cu")
	)
	(gr_line
		(start 159.666686 -30.723078)
		(end 160.413446 -29.328618)
		(stroke
			(width 0.2)
			(type default)
		)
		(layer "In4.Cu")
	)
	(gr_line
		(start 159.666686 -26.922984)
		(end 160.413446 -25.528524)
		(stroke
			(width 0.2)
			(type default)
		)
		(layer "In4.Cu")
	)
	(gr_line
		(start 159.666686 -23.12289)
		(end 160.416494 -21.723096)
		(stroke
			(width 0.2)
			(type default)
		)
		(layer "In4.Cu")
	)
	(gr_line
		(start 159.666686 -19.32305)
		(end 160.413446 -17.92859)
		(stroke
			(width 0.2)
			(type default)
		)
		(layer "In4.Cu")
	)
	(gr_arc
		(start 160.413446 -29.328618)
		(mid 160.225744 -28.684976)
		(end 159.583374 -28.877006)
		(stroke
			(width 0.2)
			(type default)
		)
		(layer "In4.Cu")
	)
	(gr_arc
		(start 160.413446 -25.528524)
		(mid 160.225744 -24.884882)
		(end 159.583374 -25.076912)
		(stroke
			(width 0.2)
			(type default)
		)
		(layer "In4.Cu")
	)
	(gr_arc
		(start 160.413446 -17.92859)
		(mid 160.225744 -17.284948)
		(end 159.583374 -17.476978)
		(stroke
			(width 0.2)
			(type default)
		)
		(layer "In4.Cu")
	)
	(gr_arc
		(start 160.416494 -21.723096)
		(mid 160.222946 -21.083524)
		(end 159.583374 -21.277072)
		(stroke
			(width 0.2)
			(type default)
		)
		(layer "In4.Cu")
	)
	(gr_line
		(start 161.081466 -22.675596)
		(end 161.083752 -22.676866)
		(stroke
			(width 0.2)
			(type default)
		)
		(layer "In4.Cu")
	)
	(gr_arc
		(start 161.083498 -30.277054)
		(mid 161.277046 -30.916626)
		(end 161.916618 -30.723078)
		(stroke
			(width 0.2)
			(type default)
		)
		(layer "In4.Cu")
	)
	(gr_arc
		(start 161.083498 -26.47696)
		(mid 161.277046 -27.116532)
		(end 161.916618 -26.922984)
		(stroke
			(width 0.2)
			(type default)
		)
		(layer "In4.Cu")
	)
	(gr_arc
		(start 161.083498 -18.877026)
		(mid 161.277046 -19.516598)
		(end 161.916618 -19.32305)
		(stroke
			(width 0.2)
			(type default)
		)
		(layer "In4.Cu")
	)
	(gr_arc
		(start 161.083752 -22.676866)
		(mid 161.277046 -23.316184)
		(end 161.916364 -23.12289)
		(stroke
			(width 0.2)
			(type default)
		)
		(layer "In4.Cu")
	)
	(gr_line
		(start 161.831528 -21.275802)
		(end 161.081466 -22.675596)
		(stroke
			(width 0.2)
			(type default)
		)
		(layer "In4.Cu")
	)
	(gr_line
		(start 161.83356 -28.877006)
		(end 161.083498 -30.277054)
		(stroke
			(width 0.2)
			(type default)
		)
		(layer "In4.Cu")
	)
	(gr_line
		(start 161.83356 -25.076912)
		(end 161.083498 -26.47696)
		(stroke
			(width 0.2)
			(type default)
		)
		(layer "In4.Cu")
	)
	(gr_line
		(start 161.83356 -17.476978)
		(end 161.083498 -18.877026)
		(stroke
			(width 0.2)
			(type default)
		)
		(layer "In4.Cu")
	)
	(gr_line
		(start 161.833814 -21.277072)
		(end 161.831528 -21.275802)
		(stroke
			(width 0.2)
			(type default)
		)
		(layer "In4.Cu")
	)
	(gr_line
		(start 161.916364 -23.12289)
		(end 161.91865 -23.12416)
		(stroke
			(width 0.2)
			(type default)
		)
		(layer "In4.Cu")
	)
	(gr_line
		(start 161.916618 -30.723078)
		(end 162.663632 -29.328618)
		(stroke
			(width 0.2)
			(type default)
		)
		(layer "In4.Cu")
	)
	(gr_line
		(start 161.916618 -26.922984)
		(end 162.663632 -25.528524)
		(stroke
			(width 0.2)
			(type default)
		)
		(layer "In4.Cu")
	)
	(gr_line
		(start 161.916618 -19.32305)
		(end 162.663632 -17.92859)
		(stroke
			(width 0.2)
			(type default)
		)
		(layer "In4.Cu")
	)
	(gr_line
		(start 161.91865 -23.12416)
		(end 162.668712 -21.72462)
		(stroke
			(width 0.2)
			(type default)
		)
		(layer "In4.Cu")
	)
	(gr_arc
		(start 162.663632 -29.328618)
		(mid 162.47593 -28.684976)
		(end 161.83356 -28.877006)
		(stroke
			(width 0.2)
			(type default)
		)
		(layer "In4.Cu")
	)
	(gr_arc
		(start 162.663632 -25.528524)
		(mid 162.47593 -24.884882)
		(end 161.83356 -25.076912)
		(stroke
			(width 0.2)
			(type default)
		)
		(layer "In4.Cu")
	)
	(gr_arc
		(start 162.663632 -17.92859)
		(mid 162.47593 -17.284948)
		(end 161.83356 -17.476978)
		(stroke
			(width 0.2)
			(type default)
		)
		(layer "In4.Cu")
	)
	(gr_arc
		(start 162.666426 -21.72335)
		(mid 162.473287 -21.083725)
		(end 161.833814 -21.277072)
		(stroke
			(width 0.2)
			(type default)
		)
		(layer "In4.Cu")
	)
	(gr_line
		(start 162.668458 -21.724366)
		(end 162.666426 -21.72335)
		(stroke
			(width 0.2)
			(type default)
		)
		(layer "In4.Cu")
	)
	(gr_line
		(start 162.668712 -21.72462)
		(end 162.668458 -21.724366)
		(stroke
			(width 0.2)
			(type default)
		)
		(layer "In4.Cu")
	)
	(gr_line
		(start 165.123622 -91.0082)
		(end 150.8252 -91.0082)
		(stroke
			(width 0.381)
			(type default)
		)
		(layer "In4.Cu")
	)
	(gr_line
		(start 169.577258 -95.461836)
		(end 165.123622 -91.0082)
		(stroke
			(width 0.381)
			(type default)
		)
		(layer "In4.Cu")
	)
	(gr_line
		(start 170.3832 -133.4262)
		(end 170.3832 -117.8814)
		(stroke
			(width 0.381)
			(type default)
		)
		(layer "In4.Cu")
	)
	(gr_line
		(start 170.3832 -117.8814)
		(end 157.734 -105.2322)
		(stroke
			(width 0.381)
			(type default)
		)
		(layer "In4.Cu")
	)
	(gr_line
		(start 172.652436 -95.461836)
		(end 169.577258 -95.461836)
		(stroke
			(width 0.381)
			(type default)
		)
		(layer "In4.Cu")
	)
	(gr_line
		(start 175.0314 -138.0744)
		(end 170.3832 -133.4262)
		(stroke
			(width 0.381)
			(type default)
		)
		(layer "In4.Cu")
	)
	(gr_line
		(start 178.0413 -80.267302)
		(end 180.323998 -82.55)
		(stroke
			(width 0.3048)
			(type default)
		)
		(layer "In4.Cu")
	)
	(gr_line
		(start 178.0413 -75.5523)
		(end 178.0413 -80.267302)
		(stroke
			(width 0.3048)
			(type default)
		)
		(layer "In4.Cu")
	)
	(gr_arc
		(start 178.811174 -26.465022)
		(mid 179.015136 -27.138884)
		(end 179.688998 -26.934922)
		(stroke
			(width 0.2)
			(type default)
		)
		(layer "In4.Cu")
	)
	(gr_arc
		(start 178.833526 -30.277054)
		(mid 179.027074 -30.916626)
		(end 179.666646 -30.723078)
		(stroke
			(width 0.2)
			(type default)
		)
		(layer "In4.Cu")
	)
	(gr_arc
		(start 178.833526 -18.877026)
		(mid 179.027074 -19.516598)
		(end 179.666646 -19.32305)
		(stroke
			(width 0.2)
			(type default)
		)
		(layer "In4.Cu")
	)
	(gr_line
		(start 178.83632 -74.75728)
		(end 178.0413 -75.5523)
		(stroke
			(width 0.3048)
			(type default)
		)
		(layer "In4.Cu")
	)
	(gr_line
		(start 178.83632 -72.48144)
		(end 178.83632 -74.75728)
		(stroke
			(width 0.3048)
			(type default)
		)
		(layer "In4.Cu")
	)
	(gr_arc
		(start 178.836574 -22.671278)
		(mid 179.024276 -23.31492)
		(end 179.666646 -23.12289)
		(stroke
			(width 0.2)
			(type default)
		)
		(layer "In4.Cu")
	)
	(gr_line
		(start 179.560982 -25.064974)
		(end 178.811174 -26.465022)
		(stroke
			(width 0.2)
			(type default)
		)
		(layer "In4.Cu")
	)
	(gr_line
		(start 179.583334 -28.877006)
		(end 178.833526 -30.277054)
		(stroke
			(width 0.2)
			(type default)
		)
		(layer "In4.Cu")
	)
	(gr_line
		(start 179.583334 -21.277072)
		(end 178.836574 -22.671278)
		(stroke
			(width 0.2)
			(type default)
		)
		(layer "In4.Cu")
	)
	(gr_line
		(start 179.583334 -17.476978)
		(end 178.833526 -18.877026)
		(stroke
			(width 0.2)
			(type default)
		)
		(layer "In4.Cu")
	)
	(gr_line
		(start 179.666646 -30.723078)
		(end 180.413406 -29.328618)
		(stroke
			(width 0.2)
			(type default)
		)
		(layer "In4.Cu")
	)
	(gr_line
		(start 179.666646 -23.12289)
		(end 180.416454 -21.723096)
		(stroke
			(width 0.2)
			(type default)
		)
		(layer "In4.Cu")
	)
	(gr_line
		(start 179.666646 -19.32305)
		(end 180.413406 -17.92859)
		(stroke
			(width 0.2)
			(type default)
		)
		(layer "In4.Cu")
	)
	(gr_line
		(start 179.688998 -26.934922)
		(end 180.43398 -25.543764)
		(stroke
			(width 0.2)
			(type default)
		)
		(layer "In4.Cu")
	)
	(gr_line
		(start 180.323998 -82.55)
		(end 197.960488 -82.55)
		(stroke
			(width 0.3048)
			(type default)
		)
		(layer "In4.Cu")
	)
	(gr_arc
		(start 180.413406 -29.328618)
		(mid 180.225704 -28.684976)
		(end 179.583334 -28.877006)
		(stroke
			(width 0.2)
			(type default)
		)
		(layer "In4.Cu")
	)
	(gr_arc
		(start 180.413406 -17.92859)
		(mid 180.225704 -17.284948)
		(end 179.583334 -17.476978)
		(stroke
			(width 0.2)
			(type default)
		)
		(layer "In4.Cu")
	)
	(gr_arc
		(start 180.416454 -21.723096)
		(mid 180.222906 -21.083524)
		(end 179.583334 -21.277072)
		(stroke
			(width 0.2)
			(type default)
		)
		(layer "In4.Cu")
	)
	(gr_arc
		(start 180.43398 -25.543764)
		(mid 180.239312 -24.863383)
		(end 179.560982 -25.064974)
		(stroke
			(width 0.2)
			(type default)
		)
		(layer "In4.Cu")
	)
	(gr_arc
		(start 181.061106 -26.464768)
		(mid 181.264814 -27.138884)
		(end 181.93893 -26.935176)
		(stroke
			(width 0.2)
			(type default)
		)
		(layer "In4.Cu")
	)
	(gr_line
		(start 181.081426 -22.675596)
		(end 181.083712 -22.676866)
		(stroke
			(width 0.2)
			(type default)
		)
		(layer "In4.Cu")
	)
	(gr_arc
		(start 181.083458 -30.277054)
		(mid 181.277006 -30.916626)
		(end 181.916578 -30.723078)
		(stroke
			(width 0.2)
			(type default)
		)
		(layer "In4.Cu")
	)
	(gr_arc
		(start 181.083458 -18.877026)
		(mid 181.277006 -19.516598)
		(end 181.916578 -19.32305)
		(stroke
			(width 0.2)
			(type default)
		)
		(layer "In4.Cu")
	)
	(gr_arc
		(start 181.083712 -22.676866)
		(mid 181.277006 -23.316184)
		(end 181.916324 -23.12289)
		(stroke
			(width 0.2)
			(type default)
		)
		(layer "In4.Cu")
	)
	(gr_line
		(start 181.138576 -70.179184)
		(end 178.83632 -72.48144)
		(stroke
			(width 0.3048)
			(type default)
		)
		(layer "In4.Cu")
	)
	(gr_line
		(start 181.811168 -25.06472)
		(end 181.061106 -26.464768)
		(stroke
			(width 0.2)
			(type default)
		)
		(layer "In4.Cu")
	)
	(gr_line
		(start 181.831488 -21.275802)
		(end 181.081426 -22.675596)
		(stroke
			(width 0.2)
			(type default)
		)
		(layer "In4.Cu")
	)
	(gr_line
		(start 181.83352 -28.877006)
		(end 181.083458 -30.277054)
		(stroke
			(width 0.2)
			(type default)
		)
		(layer "In4.Cu")
	)
	(gr_line
		(start 181.83352 -17.476978)
		(end 181.083458 -18.877026)
		(stroke
			(width 0.2)
			(type default)
		)
		(layer "In4.Cu")
	)
	(gr_line
		(start 181.833774 -21.277072)
		(end 181.831488 -21.275802)
		(stroke
			(width 0.2)
			(type default)
		)
		(layer "In4.Cu")
	)
	(gr_line
		(start 181.916324 -23.12289)
		(end 181.91861 -23.12416)
		(stroke
			(width 0.2)
			(type default)
		)
		(layer "In4.Cu")
	)
	(gr_line
		(start 181.916578 -30.723078)
		(end 182.663592 -29.328618)
		(stroke
			(width 0.2)
			(type default)
		)
		(layer "In4.Cu")
	)
	(gr_line
		(start 181.916578 -19.32305)
		(end 182.663592 -17.92859)
		(stroke
			(width 0.2)
			(type default)
		)
		(layer "In4.Cu")
	)
	(gr_line
		(start 181.91861 -23.12416)
		(end 182.668672 -21.72462)
		(stroke
			(width 0.2)
			(type default)
		)
		(layer "In4.Cu")
	)
	(gr_line
		(start 181.93893 -26.935176)
		(end 182.684166 -25.543764)
		(stroke
			(width 0.2)
			(type default)
		)
		(layer "In4.Cu")
	)
	(gr_line
		(start 182.626 -138.0744)
		(end 175.0314 -138.0744)
		(stroke
			(width 0.381)
			(type default)
		)
		(layer "In4.Cu")
	)
	(gr_arc
		(start 182.663592 -29.328618)
		(mid 182.47589 -28.684976)
		(end 181.83352 -28.877006)
		(stroke
			(width 0.2)
			(type default)
		)
		(layer "In4.Cu")
	)
	(gr_arc
		(start 182.663592 -17.92859)
		(mid 182.47589 -17.284948)
		(end 181.83352 -17.476978)
		(stroke
			(width 0.2)
			(type default)
		)
		(layer "In4.Cu")
	)
	(gr_arc
		(start 182.666386 -21.72335)
		(mid 182.473247 -21.083725)
		(end 181.833774 -21.277072)
		(stroke
			(width 0.2)
			(type default)
		)
		(layer "In4.Cu")
	)
	(gr_line
		(start 182.668418 -21.724366)
		(end 182.666386 -21.72335)
		(stroke
			(width 0.2)
			(type default)
		)
		(layer "In4.Cu")
	)
	(gr_line
		(start 182.668672 -21.72462)
		(end 182.668418 -21.724366)
		(stroke
			(width 0.2)
			(type default)
		)
		(layer "In4.Cu")
	)
	(gr_arc
		(start 182.684166 -25.543764)
		(mid 182.489596 -24.863437)
		(end 181.811168 -25.06472)
		(stroke
			(width 0.2)
			(type default)
		)
		(layer "In4.Cu")
	)
	(gr_line
		(start 183.4642 -119.7102)
		(end 183.4642 -106.2736)
		(stroke
			(width 0.381)
			(type default)
		)
		(layer "In4.Cu")
	)
	(gr_line
		(start 183.4642 -106.2736)
		(end 172.652436 -95.461836)
		(stroke
			(width 0.381)
			(type default)
		)
		(layer "In4.Cu")
	)
	(gr_line
		(start 184.7342 -120.9802)
		(end 183.4642 -119.7102)
		(stroke
			(width 0.381)
			(type default)
		)
		(layer "In4.Cu")
	)
	(gr_line
		(start 188.341 -70.179184)
		(end 181.138576 -70.179184)
		(stroke
			(width 0.3048)
			(type default)
		)
		(layer "In4.Cu")
	)
	(gr_line
		(start 188.341 -60.7314)
		(end 188.341 -70.179184)
		(stroke
			(width 0.3048)
			(type default)
		)
		(layer "In4.Cu")
	)
	(gr_line
		(start 188.3791 -69.7992)
		(end 187.9981 -70.1802)
		(stroke
			(width 0.3048)
			(type default)
		)
		(layer "In4.Cu")
	)
	(gr_line
		(start 188.5696 -60.5028)
		(end 188.341 -60.7314)
		(stroke
			(width 0.3048)
			(type default)
		)
		(layer "In4.Cu")
	)
	(gr_line
		(start 188.7601 -70.1802)
		(end 188.3791 -69.7992)
		(stroke
			(width 0.3048)
			(type default)
		)
		(layer "In4.Cu")
	)
	(gr_arc
		(start 189.286134 -84.241132)
		(mid 189.279055 -84.782246)
		(end 189.820296 -84.784692)
		(stroke
			(width 0.2)
			(type default)
		)
		(layer "In4.Cu")
	)
	(gr_line
		(start 189.4078 -112.8268)
		(end 189.7253 -113.1443)
		(stroke
			(width 0.381)
			(type default)
		)
		(layer "In4.Cu")
	)
	(gr_line
		(start 189.4078 -106.6419)
		(end 189.4078 -112.8268)
		(stroke
			(width 0.381)
			(type default)
		)
		(layer "In4.Cu")
	)
	(gr_line
		(start 189.7253 -113.1443)
		(end 211.2518 -113.1443)
		(stroke
			(width 0.381)
			(type default)
		)
		(layer "In4.Cu")
	)
	(gr_line
		(start 189.8142 -106.2355)
		(end 189.4078 -106.6419)
		(stroke
			(width 0.381)
			(type default)
		)
		(layer "In4.Cu")
	)
	(gr_line
		(start 189.820296 -84.784692)
		(end 190.448692 -84.156296)
		(stroke
			(width 0.2)
			(type default)
		)
		(layer "In4.Cu")
	)
	(gr_line
		(start 189.909704 -83.617308)
		(end 189.286134 -84.241132)
		(stroke
			(width 0.2)
			(type default)
		)
		(layer "In4.Cu")
	)
	(gr_arc
		(start 190.448692 -84.156296)
		(mid 190.448692 -83.617308)
		(end 189.909704 -83.617308)
		(stroke
			(width 0.2)
			(type default)
		)
		(layer "In4.Cu")
	)
	(gr_arc
		(start 190.835534 -87.035132)
		(mid 190.828455 -87.576246)
		(end 191.369696 -87.578692)
		(stroke
			(width 0.2)
			(type default)
		)
		(layer "In4.Cu")
	)
	(gr_line
		(start 191.369696 -87.578692)
		(end 191.998092 -86.950296)
		(stroke
			(width 0.2)
			(type default)
		)
		(layer "In4.Cu")
	)
	(gr_line
		(start 191.459104 -86.411308)
		(end 190.835534 -87.035132)
		(stroke
			(width 0.2)
			(type default)
		)
		(layer "In4.Cu")
	)
	(gr_arc
		(start 191.64173 -74.699622)
		(mid 191.99987 -75.057762)
		(end 192.35801 -74.699622)
		(stroke
			(width 0.2)
			(type default)
		)
		(layer "In4.Cu")
	)
	(gr_line
		(start 191.64173 -73.899776)
		(end 191.64173 -74.699622)
		(stroke
			(width 0.2)
			(type default)
		)
		(layer "In4.Cu")
	)
	(gr_arc
		(start 191.998092 -86.950296)
		(mid 191.998092 -86.411308)
		(end 191.459104 -86.411308)
		(stroke
			(width 0.2)
			(type default)
		)
		(layer "In4.Cu")
	)
	(gr_line
		(start 192.35801 -74.699622)
		(end 192.35801 -73.90003)
		(stroke
			(width 0.2)
			(type default)
		)
		(layer "In4.Cu")
	)
	(gr_arc
		(start 192.35801 -73.90003)
		(mid 191.999997 -73.541636)
		(end 191.64173 -73.899776)
		(stroke
			(width 0.2)
			(type default)
		)
		(layer "In4.Cu")
	)
	(gr_line
		(start 192.441576 -73.90003)
		(end 192.44183 -74.699876)
		(stroke
			(width 0.2)
			(type default)
		)
		(layer "In4.Cu")
	)
	(gr_arc
		(start 192.44183 -74.699876)
		(mid 192.800097 -75.058016)
		(end 193.15811 -74.699622)
		(stroke
			(width 0.2)
			(type default)
		)
		(layer "In4.Cu")
	)
	(gr_arc
		(start 193.157856 -73.90003)
		(mid 192.799716 -73.541636)
		(end 192.441576 -73.90003)
		(stroke
			(width 0.2)
			(type default)
		)
		(layer "In4.Cu")
	)
	(gr_line
		(start 193.15811 -74.699622)
		(end 193.157856 -73.90003)
		(stroke
			(width 0.2)
			(type default)
		)
		(layer "In4.Cu")
	)
	(gr_arc
		(start 193.557906 -88.736932)
		(mid 193.550827 -89.278046)
		(end 194.092068 -89.280492)
		(stroke
			(width 0.2)
			(type default)
		)
		(layer "In4.Cu")
	)
	(gr_arc
		(start 193.781934 -84.012532)
		(mid 193.774855 -84.553646)
		(end 194.316096 -84.556092)
		(stroke
			(width 0.2)
			(type default)
		)
		(layer "In4.Cu")
	)
	(gr_arc
		(start 194.03441 -74.698606)
		(mid 194.389248 -75.060048)
		(end 194.75069 -74.70521)
		(stroke
			(width 0.2)
			(type default)
		)
		(layer "In4.Cu")
	)
	(gr_line
		(start 194.041522 -73.896474)
		(end 194.03441 -74.698606)
		(stroke
			(width 0.2)
			(type default)
		)
		(layer "In4.Cu")
	)
	(gr_line
		(start 194.092068 -89.280492)
		(end 194.720464 -88.652096)
		(stroke
			(width 0.2)
			(type default)
		)
		(layer "In4.Cu")
	)
	(gr_line
		(start 194.181476 -88.113108)
		(end 193.557906 -88.736932)
		(stroke
			(width 0.2)
			(type default)
		)
		(layer "In4.Cu")
	)
	(gr_line
		(start 194.316096 -84.556092)
		(end 194.944492 -83.927696)
		(stroke
			(width 0.2)
			(type default)
		)
		(layer "In4.Cu")
	)
	(gr_line
		(start 194.405504 -83.388708)
		(end 193.781934 -84.012532)
		(stroke
			(width 0.2)
			(type default)
		)
		(layer "In4.Cu")
	)
	(gr_arc
		(start 194.720464 -88.652096)
		(mid 194.720464 -88.113108)
		(end 194.181476 -88.113108)
		(stroke
			(width 0.2)
			(type default)
		)
		(layer "In4.Cu")
	)
	(gr_line
		(start 194.75069 -74.70521)
		(end 194.757802 -73.903332)
		(stroke
			(width 0.2)
			(type default)
		)
		(layer "In4.Cu")
	)
	(gr_arc
		(start 194.757802 -73.903332)
		(mid 194.403091 -73.541891)
		(end 194.041522 -73.896474)
		(stroke
			(width 0.2)
			(type default)
		)
		(layer "In4.Cu")
	)
	(gr_arc
		(start 194.840352 -74.706988)
		(mid 195.197984 -75.065636)
		(end 195.556632 -74.708004)
		(stroke
			(width 0.2)
			(type default)
		)
		(layer "In4.Cu")
	)
	(gr_line
		(start 194.841622 -73.899268)
		(end 194.840352 -74.706988)
		(stroke
			(width 0.2)
			(type default)
		)
		(layer "In4.Cu")
	)
	(gr_arc
		(start 194.944492 -83.927696)
		(mid 194.944492 -83.388708)
		(end 194.405504 -83.388708)
		(stroke
			(width 0.2)
			(type default)
		)
		(layer "In4.Cu")
	)
	(gr_line
		(start 195.106036 -12.635484)
		(end 158.30931 -12.635484)
		(stroke
			(width 0.381)
			(type default)
		)
		(layer "In4.Cu")
	)
	(gr_line
		(start 195.556632 -74.708004)
		(end 195.557902 -73.900538)
		(stroke
			(width 0.2)
			(type default)
		)
		(layer "In4.Cu")
	)
	(gr_arc
		(start 195.557902 -73.900538)
		(mid 195.200397 -73.54189)
		(end 194.841622 -73.899268)
		(stroke
			(width 0.2)
			(type default)
		)
		(layer "In4.Cu")
	)
	(gr_line
		(start 196.2658 -151.7142)
		(end 182.626 -138.0744)
		(stroke
			(width 0.381)
			(type default)
		)
		(layer "In4.Cu")
	)
	(gr_line
		(start 196.441568 -73.903586)
		(end 196.44995 -74.702162)
		(stroke
			(width 0.2)
			(type default)
		)
		(layer "In4.Cu")
	)
	(gr_arc
		(start 196.44995 -74.702162)
		(mid 196.8119 -75.056492)
		(end 197.16623 -74.694542)
		(stroke
			(width 0.2)
			(type default)
		)
		(layer "In4.Cu")
	)
	(gr_arc
		(start 196.631306 -85.688932)
		(mid 196.624227 -86.230046)
		(end 197.165468 -86.232492)
		(stroke
			(width 0.2)
			(type default)
		)
		(layer "In4.Cu")
	)
	(gr_arc
		(start 197.157848 -73.89622)
		(mid 196.796025 -73.541889)
		(end 196.441568 -73.903586)
		(stroke
			(width 0.2)
			(type default)
		)
		(layer "In4.Cu")
	)
	(gr_line
		(start 197.165468 -86.232492)
		(end 197.793864 -85.604096)
		(stroke
			(width 0.2)
			(type default)
		)
		(layer "In4.Cu")
	)
	(gr_line
		(start 197.16623 -74.694542)
		(end 197.157848 -73.89622)
		(stroke
			(width 0.2)
			(type default)
		)
		(layer "In4.Cu")
	)
	(gr_line
		(start 197.241668 -73.904094)
		(end 197.251066 -74.70394)
		(stroke
			(width 0.2)
			(type default)
		)
		(layer "In4.Cu")
	)
	(gr_arc
		(start 197.251066 -74.70394)
		(mid 197.613524 -75.057762)
		(end 197.967346 -74.695304)
		(stroke
			(width 0.2)
			(type default)
		)
		(layer "In4.Cu")
	)
	(gr_line
		(start 197.254876 -85.065108)
		(end 196.631306 -85.688932)
		(stroke
			(width 0.2)
			(type default)
		)
		(layer "In4.Cu")
	)
	(gr_arc
		(start 197.793864 -85.604096)
		(mid 197.793864 -85.065108)
		(end 197.254876 -85.065108)
		(stroke
			(width 0.2)
			(type default)
		)
		(layer "In4.Cu")
	)
	(gr_arc
		(start 197.922134 -88.813132)
		(mid 197.915055 -89.354246)
		(end 198.456296 -89.356692)
		(stroke
			(width 0.2)
			(type default)
		)
		(layer "In4.Cu")
	)
	(gr_arc
		(start 197.957948 -73.895712)
		(mid 197.595617 -73.541888)
		(end 197.241668 -73.904094)
		(stroke
			(width 0.2)
			(type default)
		)
		(layer "In4.Cu")
	)
	(gr_line
		(start 197.960488 -82.55)
		(end 202.052428 -78.45806)
		(stroke
			(width 0.3048)
			(type default)
		)
		(layer "In4.Cu")
	)
	(gr_line
		(start 197.967346 -74.695304)
		(end 197.957948 -73.895712)
		(stroke
			(width 0.2)
			(type default)
		)
		(layer "In4.Cu")
	)
	(gr_line
		(start 198.456296 -89.356692)
		(end 199.084692 -88.728296)
		(stroke
			(width 0.2)
			(type default)
		)
		(layer "In4.Cu")
	)
	(gr_line
		(start 198.545704 -88.189308)
		(end 197.922134 -88.813132)
		(stroke
			(width 0.2)
			(type default)
		)
		(layer "In4.Cu")
	)
	(gr_line
		(start 198.841614 -73.900538)
		(end 198.843392 -74.693018)
		(stroke
			(width 0.2)
			(type default)
		)
		(layer "In4.Cu")
	)
	(gr_arc
		(start 198.843392 -74.693018)
		(mid 199.202294 -75.050396)
		(end 199.559672 -74.691494)
		(stroke
			(width 0.2)
			(type default)
		)
		(layer "In4.Cu")
	)
	(gr_arc
		(start 199.084692 -88.728296)
		(mid 199.084692 -88.189308)
		(end 198.545704 -88.189308)
		(stroke
			(width 0.2)
			(type default)
		)
		(layer "In4.Cu")
	)
	(gr_line
		(start 199.263 -120.9802)
		(end 184.7342 -120.9802)
		(stroke
			(width 0.381)
			(type default)
		)
		(layer "In4.Cu")
	)
	(gr_arc
		(start 199.557894 -73.899268)
		(mid 199.199119 -73.54189)
		(end 198.841614 -73.900538)
		(stroke
			(width 0.2)
			(type default)
		)
		(layer "In4.Cu")
	)
	(gr_line
		(start 199.559672 -74.691494)
		(end 199.557894 -73.899268)
		(stroke
			(width 0.2)
			(type default)
		)
		(layer "In4.Cu")
	)
	(gr_line
		(start 199.641714 -73.900538)
		(end 199.643492 -74.695558)
		(stroke
			(width 0.2)
			(type default)
		)
		(layer "In4.Cu")
	)
	(gr_arc
		(start 199.643492 -74.695558)
		(mid 200.002394 -75.052936)
		(end 200.359772 -74.694034)
		(stroke
			(width 0.2)
			(type default)
		)
		(layer "In4.Cu")
	)
	(gr_arc
		(start 200.357994 -73.899268)
		(mid 199.999219 -73.54189)
		(end 199.641714 -73.900538)
		(stroke
			(width 0.2)
			(type default)
		)
		(layer "In4.Cu")
	)
	(gr_line
		(start 200.359772 -74.694034)
		(end 200.357994 -73.899268)
		(stroke
			(width 0.2)
			(type default)
		)
		(layer "In4.Cu")
	)
	(gr_line
		(start 200.496678 -70.179184)
		(end 188.341 -70.179184)
		(stroke
			(width 0.3048)
			(type default)
		)
		(layer "In4.Cu")
	)
	(gr_line
		(start 200.79843 -74.287126)
		(end 201.598276 -74.287126)
		(stroke
			(width 0.2)
			(type default)
		)
		(layer "In4.Cu")
	)
	(gr_arc
		(start 200.798684 -73.520046)
		(mid 200.41489 -73.903459)
		(end 200.79843 -74.287126)
		(stroke
			(width 0.2)
			(type default)
		)
		(layer "In4.Cu")
	)
	(gr_arc
		(start 200.944734 -85.815932)
		(mid 200.937655 -86.357046)
		(end 201.478896 -86.359492)
		(stroke
			(width 0.2)
			(type default)
		)
		(layer "In4.Cu")
	)
	(gr_line
		(start 200.9902 -128.9558)
		(end 200.9902 -122.7074)
		(stroke
			(width 0.381)
			(type default)
		)
		(layer "In4.Cu")
	)
	(gr_line
		(start 200.9902 -122.7074)
		(end 199.263 -120.9802)
		(stroke
			(width 0.381)
			(type default)
		)
		(layer "In4.Cu")
	)
	(gr_arc
		(start 201.209656 -67.49923)
		(mid 201.590021 -67.886073)
		(end 201.976736 -67.50558)
		(stroke
			(width 0.2)
			(type default)
		)
		(layer "In4.Cu")
	)
	(gr_arc
		(start 201.20991 -72.297036)
		(mid 201.592815 -72.681338)
		(end 201.97699 -72.298306)
		(stroke
			(width 0.2)
			(type default)
		)
		(layer "In4.Cu")
	)
	(gr_line
		(start 201.210926 -71.502524)
		(end 201.20991 -72.297036)
		(stroke
			(width 0.2)
			(type default)
		)
		(layer "In4.Cu")
	)
	(gr_line
		(start 201.211688 -69.111114)
		(end 201.225658 -69.906388)
		(stroke
			(width 0.2)
			(type default)
		)
		(layer "In4.Cu")
	)
	(gr_line
		(start 201.216006 -66.705988)
		(end 201.209656 -67.49923)
		(stroke
			(width 0.2)
			(type default)
		)
		(layer "In4.Cu")
	)
	(gr_arc
		(start 201.225658 -69.906388)
		(mid 201.615929 -70.283322)
		(end 201.992738 -69.892926)
		(stroke
			(width 0.2)
			(type default)
		)
		(layer "In4.Cu")
	)
	(gr_line
		(start 201.478896 -86.359492)
		(end 202.107292 -85.731096)
		(stroke
			(width 0.2)
			(type default)
		)
		(layer "In4.Cu")
	)
	(gr_line
		(start 201.568304 -85.192108)
		(end 200.944734 -85.815932)
		(stroke
			(width 0.2)
			(type default)
		)
		(layer "In4.Cu")
	)
	(gr_line
		(start 201.591672 -68.678806)
		(end 202.39609 -68.68668)
		(stroke
			(width 0.2)
			(type default)
		)
		(layer "In4.Cu")
	)
	(gr_line
		(start 201.592688 -71.086218)
		(end 202.40371 -71.087996)
		(stroke
			(width 0.2)
			(type default)
		)
		(layer "In4.Cu")
	)
	(gr_arc
		(start 201.594466 -70.319138)
		(mid 201.210164 -70.701789)
		(end 201.592688 -71.086218)
		(stroke
			(width 0.2)
			(type default)
		)
		(layer "In4.Cu")
	)
	(gr_arc
		(start 201.598276 -74.287126)
		(mid 201.981816 -73.903586)
		(end 201.598276 -73.520046)
		(stroke
			(width 0.2)
			(type default)
		)
		(layer "In4.Cu")
	)
	(gr_line
		(start 201.598276 -73.520046)
		(end 200.798684 -73.520046)
		(stroke
			(width 0.2)
			(type default)
		)
		(layer "In4.Cu")
	)
	(gr_arc
		(start 201.599292 -72.716898)
		(mid 201.217276 -73.101835)
		(end 201.602086 -73.483978)
		(stroke
			(width 0.2)
			(type default)
		)
		(layer "In4.Cu")
	)
	(gr_arc
		(start 201.599546 -67.911726)
		(mid 201.212197 -68.291329)
		(end 201.591672 -68.678806)
		(stroke
			(width 0.2)
			(type default)
		)
		(layer "In4.Cu")
	)
	(gr_line
		(start 201.5998 -75.883262)
		(end 202.399646 -75.883262)
		(stroke
			(width 0.2)
			(type default)
		)
		(layer "In4.Cu")
	)
	(gr_arc
		(start 201.600054 -75.116182)
		(mid 201.21626 -75.499595)
		(end 201.5998 -75.883262)
		(stroke
			(width 0.2)
			(type default)
		)
		(layer "In4.Cu")
	)
	(gr_line
		(start 201.602086 -73.483978)
		(end 202.39863 -73.480676)
		(stroke
			(width 0.2)
			(type default)
		)
		(layer "In4.Cu")
	)
	(gr_line
		(start 201.678794 -19.208242)
		(end 195.106036 -12.635484)
		(stroke
			(width 0.381)
			(type default)
		)
		(layer "In4.Cu")
	)
	(gr_line
		(start 201.8157 -78.7781)
		(end 202.3237 -78.7781)
		(stroke
			(width 0.3048)
			(type default)
		)
		(layer "In4.Cu")
	)
	(gr_line
		(start 201.976736 -67.50558)
		(end 201.983086 -66.712084)
		(stroke
			(width 0.2)
			(type default)
		)
		(layer "In4.Cu")
	)
	(gr_line
		(start 201.97699 -72.298306)
		(end 201.978006 -71.50354)
		(stroke
			(width 0.2)
			(type default)
		)
		(layer "In4.Cu")
	)
	(gr_arc
		(start 201.978006 -71.50354)
		(mid 201.594974 -71.119492)
		(end 201.210926 -71.502524)
		(stroke
			(width 0.2)
			(type default)
		)
		(layer "In4.Cu")
	)
	(gr_arc
		(start 201.978768 -69.097398)
		(mid 201.58837 -68.720716)
		(end 201.211688 -69.111114)
		(stroke
			(width 0.2)
			(type default)
		)
		(layer "In4.Cu")
	)
	(gr_arc
		(start 201.983086 -66.712084)
		(mid 201.602594 -66.325496)
		(end 201.216006 -66.705988)
		(stroke
			(width 0.2)
			(type default)
		)
		(layer "In4.Cu")
	)
	(gr_line
		(start 201.992738 -69.892926)
		(end 201.978768 -69.097398)
		(stroke
			(width 0.2)
			(type default)
		)
		(layer "In4.Cu")
	)
	(gr_line
		(start 202.052428 -78.45806)
		(end 202.052428 -71.734934)
		(stroke
			(width 0.3048)
			(type default)
		)
		(layer "In4.Cu")
	)
	(gr_line
		(start 202.052428 -78.45806)
		(end 203.312268 -79.7179)
		(stroke
			(width 0.3048)
			(type default)
		)
		(layer "In4.Cu")
	)
	(gr_line
		(start 202.052428 -71.734934)
		(end 200.496678 -70.179184)
		(stroke
			(width 0.3048)
			(type default)
		)
		(layer "In4.Cu")
	)
	(gr_arc
		(start 202.107292 -85.731096)
		(mid 202.107292 -85.192108)
		(end 201.568304 -85.192108)
		(stroke
			(width 0.2)
			(type default)
		)
		(layer "In4.Cu")
	)
	(gr_line
		(start 202.395582 -72.713596)
		(end 201.599292 -72.716898)
		(stroke
			(width 0.2)
			(type default)
		)
		(layer "In4.Cu")
	)
	(gr_arc
		(start 202.39609 -68.68668)
		(mid 202.78344 -68.30695)
		(end 202.40371 -67.9196)
		(stroke
			(width 0.2)
			(type default)
		)
		(layer "In4.Cu")
	)
	(gr_arc
		(start 202.39863 -73.480676)
		(mid 202.780646 -73.095612)
		(end 202.395582 -72.713596)
		(stroke
			(width 0.2)
			(type default)
		)
		(layer "In4.Cu")
	)
	(gr_arc
		(start 202.399646 -75.883262)
		(mid 202.783186 -75.499722)
		(end 202.399646 -75.116182)
		(stroke
			(width 0.2)
			(type default)
		)
		(layer "In4.Cu")
	)
	(gr_line
		(start 202.399646 -75.116182)
		(end 201.600054 -75.116182)
		(stroke
			(width 0.2)
			(type default)
		)
		(layer "In4.Cu")
	)
	(gr_arc
		(start 202.40371 -71.087996)
		(mid 202.788012 -70.705218)
		(end 202.405234 -70.320916)
		(stroke
			(width 0.2)
			(type default)
		)
		(layer "In4.Cu")
	)
	(gr_line
		(start 202.40371 -67.9196)
		(end 201.599546 -67.911726)
		(stroke
			(width 0.2)
			(type default)
		)
		(layer "In4.Cu")
	)
	(gr_line
		(start 202.405234 -70.320916)
		(end 201.594466 -70.319138)
		(stroke
			(width 0.2)
			(type default)
		)
		(layer "In4.Cu")
	)
	(gr_line
		(start 203.312268 -79.7179)
		(end 203.3143 -79.7179)
		(stroke
			(width 0.3048)
			(type default)
		)
		(layer "In4.Cu")
	)
	(gr_line
		(start 203.3143 -79.7179)
		(end 206.3242 -82.7278)
		(stroke
			(width 0.381)
			(type default)
		)
		(layer "In4.Cu")
	)
	(gr_arc
		(start 203.535534 -85.231732)
		(mid 203.528455 -85.772846)
		(end 204.069696 -85.775292)
		(stroke
			(width 0.2)
			(type default)
		)
		(layer "In4.Cu")
	)
	(gr_line
		(start 204.069696 -85.775292)
		(end 204.698092 -85.146896)
		(stroke
			(width 0.2)
			(type default)
		)
		(layer "In4.Cu")
	)
	(gr_line
		(start 204.159104 -84.607908)
		(end 203.535534 -85.231732)
		(stroke
			(width 0.2)
			(type default)
		)
		(layer "In4.Cu")
	)
	(gr_line
		(start 204.597 -106.2355)
		(end 189.8142 -106.2355)
		(stroke
			(width 0.381)
			(type default)
		)
		(layer "In4.Cu")
	)
	(gr_arc
		(start 204.698092 -85.146896)
		(mid 204.698092 -84.607908)
		(end 204.159104 -84.607908)
		(stroke
			(width 0.2)
			(type default)
		)
		(layer "In4.Cu")
	)
	(gr_line
		(start 206.3242 -104.5083)
		(end 204.597 -106.2355)
		(stroke
			(width 0.381)
			(type default)
		)
		(layer "In4.Cu")
	)
	(gr_line
		(start 206.3242 -82.7278)
		(end 206.3242 -104.5083)
		(stroke
			(width 0.381)
			(type default)
		)
		(layer "In4.Cu")
	)
	(gr_line
		(start 206.883 -151.7142)
		(end 196.2658 -151.7142)
		(stroke
			(width 0.381)
			(type default)
		)
		(layer "In4.Cu")
	)
	(gr_line
		(start 206.883 -151.7142)
		(end 207.4164 -151.1808)
		(stroke
			(width 0.381)
			(type default)
		)
		(layer "In4.Cu")
	)
	(gr_line
		(start 207.396334 -19.208242)
		(end 201.678794 -19.208242)
		(stroke
			(width 0.381)
			(type default)
		)
		(layer "In4.Cu")
	)
	(gr_line
		(start 207.4164 -151.1808)
		(end 208.8134 -151.1808)
		(stroke
			(width 0.381)
			(type default)
		)
		(layer "In4.Cu")
	)
	(gr_line
		(start 208.1276 -136.0932)
		(end 200.9902 -128.9558)
		(stroke
			(width 0.381)
			(type default)
		)
		(layer "In4.Cu")
	)
	(gr_line
		(start 208.153 -136.0932)
		(end 208.1276 -136.0932)
		(stroke
			(width 0.381)
			(type default)
		)
		(layer "In4.Cu")
	)
	(gr_line
		(start 208.8134 -151.1808)
		(end 209.4738 -150.5204)
		(stroke
			(width 0.381)
			(type default)
		)
		(layer "In4.Cu")
	)
	(gr_line
		(start 209.4738 -150.5204)
		(end 209.4738 -137.414)
		(stroke
			(width 0.381)
			(type default)
		)
		(layer "In4.Cu")
	)
	(gr_line
		(start 209.4738 -137.414)
		(end 208.153 -136.0932)
		(stroke
			(width 0.381)
			(type default)
		)
		(layer "In4.Cu")
	)
	(gr_line
		(start 210.0707 -60.5028)
		(end 188.5696 -60.5028)
		(stroke
			(width 0.3048)
			(type default)
		)
		(layer "In4.Cu")
	)
	(gr_line
		(start 210.790536 -63.655194)
		(end 210.79079 -63.655448)
		(stroke
			(width 0.2)
			(type default)
		)
		(layer "In4.Cu")
	)
	(gr_arc
		(start 210.79079 -63.655448)
		(mid 210.79079 -64.193928)
		(end 211.32927 -64.193928)
		(stroke
			(width 0.2)
			(type default)
		)
		(layer "In4.Cu")
	)
	(gr_line
		(start 210.959192 -66.09842)
		(end 210.959446 -66.098674)
		(stroke
			(width 0.2)
			(type default)
		)
		(layer "In4.Cu")
	)
	(gr_arc
		(start 210.959446 -66.098674)
		(mid 210.959446 -66.637154)
		(end 211.497926 -66.637154)
		(stroke
			(width 0.2)
			(type default)
		)
		(layer "In4.Cu")
	)
	(gr_line
		(start 211.2518 -113.1443)
		(end 219.9767 -104.4194)
		(stroke
			(width 0.381)
			(type default)
		)
		(layer "In4.Cu")
	)
	(gr_line
		(start 211.32927 -64.193928)
		(end 211.329524 -64.194182)
		(stroke
			(width 0.2)
			(type default)
		)
		(layer "In4.Cu")
	)
	(gr_line
		(start 211.329524 -64.194182)
		(end 212.137498 -63.385954)
		(stroke
			(width 0.2)
			(type default)
		)
		(layer "In4.Cu")
	)
	(gr_line
		(start 211.497926 -66.637154)
		(end 211.49818 -66.637408)
		(stroke
			(width 0.2)
			(type default)
		)
		(layer "In4.Cu")
	)
	(gr_line
		(start 211.49818 -66.637408)
		(end 212.306154 -65.82918)
		(stroke
			(width 0.2)
			(type default)
		)
		(layer "In4.Cu")
	)
	(gr_line
		(start 211.5312 -1.651)
		(end 211.0232 -1.143)
		(stroke
			(width 0.381)
			(type default)
		)
		(layer "In4.Cu")
	)
	(gr_line
		(start 211.537804 -15.066772)
		(end 207.396334 -19.208242)
		(stroke
			(width 0.381)
			(type default)
		)
		(layer "In4.Cu")
	)
	(gr_line
		(start 211.537804 -1.618996)
		(end 212.0646 -1.0922)
		(stroke
			(width 0.381)
			(type default)
		)
		(layer "In4.Cu")
	)
	(gr_line
		(start 211.537804 -1.078484)
		(end 211.537804 -15.066772)
		(stroke
			(width 0.381)
			(type default)
		)
		(layer "In4.Cu")
	)
	(gr_line
		(start 211.598764 -62.846966)
		(end 210.790536 -63.655194)
		(stroke
			(width 0.2)
			(type default)
		)
		(layer "In4.Cu")
	)
	(gr_line
		(start 211.599018 -62.84722)
		(end 211.598764 -62.846966)
		(stroke
			(width 0.2)
			(type default)
		)
		(layer "In4.Cu")
	)
	(gr_line
		(start 211.76742 -65.290192)
		(end 210.959192 -66.09842)
		(stroke
			(width 0.2)
			(type default)
		)
		(layer "In4.Cu")
	)
	(gr_line
		(start 211.767674 -65.290446)
		(end 211.76742 -65.290192)
		(stroke
			(width 0.2)
			(type default)
		)
		(layer "In4.Cu")
	)
	(gr_line
		(start 212.137498 -63.385954)
		(end 212.137498 -63.3857)
		(stroke
			(width 0.2)
			(type default)
		)
		(layer "In4.Cu")
	)
	(gr_arc
		(start 212.137498 -63.3857)
		(mid 212.137498 -62.84722)
		(end 211.599018 -62.84722)
		(stroke
			(width 0.2)
			(type default)
		)
		(layer "In4.Cu")
	)
	(gr_line
		(start 212.306154 -65.82918)
		(end 212.306154 -65.828926)
		(stroke
			(width 0.2)
			(type default)
		)
		(layer "In4.Cu")
	)
	(gr_arc
		(start 212.306154 -65.828926)
		(mid 212.306154 -65.290446)
		(end 211.767674 -65.290446)
		(stroke
			(width 0.2)
			(type default)
		)
		(layer "In4.Cu")
	)
	(gr_line
		(start 212.432392 -67.74942)
		(end 212.432646 -67.749674)
		(stroke
			(width 0.2)
			(type default)
		)
		(layer "In4.Cu")
	)
	(gr_arc
		(start 212.432646 -67.749674)
		(mid 212.432646 -68.288154)
		(end 212.971126 -68.288154)
		(stroke
			(width 0.2)
			(type default)
		)
		(layer "In4.Cu")
	)
	(gr_line
		(start 212.8901 -60.5028)
		(end 210.0707 -60.5028)
		(stroke
			(width 0.381)
			(type default)
		)
		(layer "In4.Cu")
	)
	(gr_line
		(start 212.971126 -68.288154)
		(end 212.97138 -68.288408)
		(stroke
			(width 0.2)
			(type default)
		)
		(layer "In4.Cu")
	)
	(gr_line
		(start 212.97138 -68.288408)
		(end 213.779354 -67.48018)
		(stroke
			(width 0.2)
			(type default)
		)
		(layer "In4.Cu")
	)
	(gr_line
		(start 213.24062 -66.941192)
		(end 212.432392 -67.74942)
		(stroke
			(width 0.2)
			(type default)
		)
		(layer "In4.Cu")
	)
	(gr_line
		(start 213.240874 -66.941446)
		(end 213.24062 -66.941192)
		(stroke
			(width 0.2)
			(type default)
		)
		(layer "In4.Cu")
	)
	(gr_line
		(start 213.448392 -72.52462)
		(end 213.448646 -72.524874)
		(stroke
			(width 0.2)
			(type default)
		)
		(layer "In4.Cu")
	)
	(gr_arc
		(start 213.448646 -72.524874)
		(mid 213.448646 -73.063354)
		(end 213.987126 -73.063354)
		(stroke
			(width 0.2)
			(type default)
		)
		(layer "In4.Cu")
	)
	(gr_line
		(start 213.779354 -67.48018)
		(end 213.779354 -67.479926)
		(stroke
			(width 0.2)
			(type default)
		)
		(layer "In4.Cu")
	)
	(gr_arc
		(start 213.779354 -67.479926)
		(mid 213.779354 -66.941446)
		(end 213.240874 -66.941446)
		(stroke
			(width 0.2)
			(type default)
		)
		(layer "In4.Cu")
	)
	(gr_line
		(start 213.956392 -69.22262)
		(end 213.956646 -69.222874)
		(stroke
			(width 0.2)
			(type default)
		)
		(layer "In4.Cu")
	)
	(gr_arc
		(start 213.956646 -69.222874)
		(mid 213.956646 -69.761354)
		(end 214.495126 -69.761354)
		(stroke
			(width 0.2)
			(type default)
		)
		(layer "In4.Cu")
	)
	(gr_line
		(start 213.987126 -73.063354)
		(end 213.98738 -73.063608)
		(stroke
			(width 0.2)
			(type default)
		)
		(layer "In4.Cu")
	)
	(gr_line
		(start 213.98738 -73.063608)
		(end 214.795354 -72.25538)
		(stroke
			(width 0.2)
			(type default)
		)
		(layer "In4.Cu")
	)
	(gr_line
		(start 214.25662 -71.716392)
		(end 213.448392 -72.52462)
		(stroke
			(width 0.2)
			(type default)
		)
		(layer "In4.Cu")
	)
	(gr_line
		(start 214.256874 -71.716646)
		(end 214.25662 -71.716392)
		(stroke
			(width 0.2)
			(type default)
		)
		(layer "In4.Cu")
	)
	(gr_line
		(start 214.495126 -69.761354)
		(end 214.49538 -69.761608)
		(stroke
			(width 0.2)
			(type default)
		)
		(layer "In4.Cu")
	)
	(gr_line
		(start 214.49538 -69.761608)
		(end 215.303354 -68.95338)
		(stroke
			(width 0.2)
			(type default)
		)
		(layer "In4.Cu")
	)
	(gr_line
		(start 214.76462 -68.414392)
		(end 213.956392 -69.22262)
		(stroke
			(width 0.2)
			(type default)
		)
		(layer "In4.Cu")
	)
	(gr_line
		(start 214.764874 -68.414646)
		(end 214.76462 -68.414392)
		(stroke
			(width 0.2)
			(type default)
		)
		(layer "In4.Cu")
	)
	(gr_line
		(start 214.795354 -72.25538)
		(end 214.795354 -72.255126)
		(stroke
			(width 0.2)
			(type default)
		)
		(layer "In4.Cu")
	)
	(gr_arc
		(start 214.795354 -72.255126)
		(mid 214.795354 -71.716646)
		(end 214.256874 -71.716646)
		(stroke
			(width 0.2)
			(type default)
		)
		(layer "In4.Cu")
	)
	(gr_line
		(start 214.845392 -73.92162)
		(end 214.845646 -73.921874)
		(stroke
			(width 0.2)
			(type default)
		)
		(layer "In4.Cu")
	)
	(gr_arc
		(start 214.845646 -73.921874)
		(mid 214.845646 -74.460354)
		(end 215.384126 -74.460354)
		(stroke
			(width 0.2)
			(type default)
		)
		(layer "In4.Cu")
	)
	(gr_line
		(start 215.226392 -79.38262)
		(end 215.226646 -79.382874)
		(stroke
			(width 0.2)
			(type default)
		)
		(layer "In4.Cu")
	)
	(gr_arc
		(start 215.226646 -79.382874)
		(mid 215.226646 -79.921354)
		(end 215.765126 -79.921354)
		(stroke
			(width 0.2)
			(type default)
		)
		(layer "In4.Cu")
	)
	(gr_line
		(start 215.303354 -68.95338)
		(end 215.303354 -68.953126)
		(stroke
			(width 0.2)
			(type default)
		)
		(layer "In4.Cu")
	)
	(gr_arc
		(start 215.303354 -68.953126)
		(mid 215.303354 -68.414646)
		(end 214.764874 -68.414646)
		(stroke
			(width 0.2)
			(type default)
		)
		(layer "In4.Cu")
	)
	(gr_line
		(start 215.384126 -74.460354)
		(end 215.38438 -74.460608)
		(stroke
			(width 0.2)
			(type default)
		)
		(layer "In4.Cu")
	)
	(gr_line
		(start 215.38438 -74.460608)
		(end 216.192354 -73.65238)
		(stroke
			(width 0.2)
			(type default)
		)
		(layer "In4.Cu")
	)
	(gr_line
		(start 215.65362 -73.113392)
		(end 214.845392 -73.92162)
		(stroke
			(width 0.2)
			(type default)
		)
		(layer "In4.Cu")
	)
	(gr_line
		(start 215.653874 -73.113646)
		(end 215.65362 -73.113392)
		(stroke
			(width 0.2)
			(type default)
		)
		(layer "In4.Cu")
	)
	(gr_line
		(start 215.765126 -79.921354)
		(end 215.76538 -79.921608)
		(stroke
			(width 0.2)
			(type default)
		)
		(layer "In4.Cu")
	)
	(gr_line
		(start 215.76538 -79.921608)
		(end 216.573354 -79.11338)
		(stroke
			(width 0.2)
			(type default)
		)
		(layer "In4.Cu")
	)
	(gr_line
		(start 216.03462 -78.574392)
		(end 215.226392 -79.38262)
		(stroke
			(width 0.2)
			(type default)
		)
		(layer "In4.Cu")
	)
	(gr_line
		(start 216.034874 -78.574646)
		(end 216.03462 -78.574392)
		(stroke
			(width 0.2)
			(type default)
		)
		(layer "In4.Cu")
	)
	(gr_line
		(start 216.192354 -73.65238)
		(end 216.192354 -73.652126)
		(stroke
			(width 0.2)
			(type default)
		)
		(layer "In4.Cu")
	)
	(gr_arc
		(start 216.192354 -73.652126)
		(mid 216.192354 -73.113646)
		(end 215.653874 -73.113646)
		(stroke
			(width 0.2)
			(type default)
		)
		(layer "In4.Cu")
	)
	(gr_line
		(start 216.369392 -75.44562)
		(end 216.369646 -75.445874)
		(stroke
			(width 0.2)
			(type default)
		)
		(layer "In4.Cu")
	)
	(gr_arc
		(start 216.369646 -75.445874)
		(mid 216.369646 -75.984354)
		(end 216.908126 -75.984354)
		(stroke
			(width 0.2)
			(type default)
		)
		(layer "In4.Cu")
	)
	(gr_line
		(start 216.573354 -79.11338)
		(end 216.573354 -79.113126)
		(stroke
			(width 0.2)
			(type default)
		)
		(layer "In4.Cu")
	)
	(gr_arc
		(start 216.573354 -79.113126)
		(mid 216.573354 -78.574646)
		(end 216.034874 -78.574646)
		(stroke
			(width 0.2)
			(type default)
		)
		(layer "In4.Cu")
	)
	(gr_line
		(start 216.908126 -75.984354)
		(end 216.90838 -75.984608)
		(stroke
			(width 0.2)
			(type default)
		)
		(layer "In4.Cu")
	)
	(gr_line
		(start 216.90838 -75.984608)
		(end 217.716354 -75.17638)
		(stroke
			(width 0.2)
			(type default)
		)
		(layer "In4.Cu")
	)
	(gr_line
		(start 217.17762 -74.637392)
		(end 216.369392 -75.44562)
		(stroke
			(width 0.2)
			(type default)
		)
		(layer "In4.Cu")
	)
	(gr_line
		(start 217.177874 -74.637646)
		(end 217.17762 -74.637392)
		(stroke
			(width 0.2)
			(type default)
		)
		(layer "In4.Cu")
	)
	(gr_line
		(start 217.716354 -75.17638)
		(end 217.716354 -75.176126)
		(stroke
			(width 0.2)
			(type default)
		)
		(layer "In4.Cu")
	)
	(gr_arc
		(start 217.716354 -75.176126)
		(mid 217.716354 -74.637646)
		(end 217.177874 -74.637646)
		(stroke
			(width 0.2)
			(type default)
		)
		(layer "In4.Cu")
	)
	(gr_line
		(start 219.9767 -104.4194)
		(end 224.2439 -104.4194)
		(stroke
			(width 0.381)
			(type default)
		)
		(layer "In4.Cu")
	)
	(gr_line
		(start 224.2439 -104.4194)
		(end 224.9297 -103.7336)
		(stroke
			(width 0.381)
			(type default)
		)
		(layer "In4.Cu")
	)
	(gr_line
		(start 224.9297 -103.7336)
		(end 224.9297 -72.5424)
		(stroke
			(width 0.381)
			(type default)
		)
		(layer "In4.Cu")
	)
	(gr_line
		(start 224.9297 -72.5424)
		(end 212.8901 -60.5028)
		(stroke
			(width 0.381)
			(type default)
		)
		(layer "In4.Cu")
	)
	(gr_line
		(start 229.382066 -194.00012)
		(end 149.917912 -194.00012)
		(stroke
			(width 2.54)
			(type default)
		)
		(layer "In4.Cu")
	)
	(gr_arc
		(start 229.382066 -194.00012)
		(mid 229.907793 -193.850701)
		(end 230.2764 -193.447162)
		(stroke
			(width 2.54)
			(type default)
		)
		(layer "In4.Cu")
	)
	(gr_line
		(start 234.894374 -184.211214)
		(end 230.2764 -193.447162)
		(stroke
			(width 2.54)
			(type default)
		)
		(layer "In4.Cu")
	)
	(gr_arc
		(start 234.894374 -184.211214)
		(mid 234.97328 -183.993726)
		(end 235.000038 -183.76392)
		(stroke
			(width 2.54)
			(type default)
		)
		(layer "In4.Cu")
	)
	(gr_arc
		(start 235.000038 -0.999998)
		(mid 234.707147 -0.29288)
		(end 234.00004 0)
		(stroke
			(width 2.54)
			(type default)
		)
		(layer "In4.Cu")
	)
	(gr_line
		(start 235.000038 -0.999998)
		(end 235.000038 -183.76392)
		(stroke
			(width 2.54)
			(type default)
		)
		(layer "In4.Cu")
	)
	(gr_line
		(start 63.833756 -151.918924)
		(end 64.0334 -152.118568)
		(stroke
			(width 0.06985)
			(type default)
		)
		(layer "In5.Cu")
	)
	(gr_line
		(start 63.839852 -152.782524)
		(end 64.0334 -152.588976)
		(stroke
			(width 0.06985)
			(type default)
		)
		(layer "In5.Cu")
	)
	(gr_line
		(start 65.6717 -154.964384)
		(end 65.973198 -154.66314)
		(stroke
			(width 0.06985)
			(type default)
		)
		(layer "In5.Cu")
	)
	(gr_line
		(start 65.6717 -154.057858)
		(end 65.943226 -154.329384)
		(stroke
			(width 0.06985)
			(type default)
		)
		(layer "In5.Cu")
	)
	(gr_line
		(start 71.22795 -152.746202)
		(end 71.40321 -152.921462)
		(stroke
			(width 0.06985)
			(type default)
		)
		(layer "In5.Cu")
	)
	(gr_line
		(start 71.40321 -152.921462)
		(end 71.82231 -152.921462)
		(stroke
			(width 0.06985)
			(type default)
		)
		(layer "In5.Cu")
	)
	(gr_line
		(start 71.55815 -152.413462)
		(end 71.66737 -152.413462)
		(stroke
			(width 0.06985)
			(type default)
		)
		(layer "In5.Cu")
	)
	(gr_line
		(start 71.82231 -152.921462)
		(end 71.99757 -152.746202)
		(stroke
			(width 0.06985)
			(type default)
		)
		(layer "In5.Cu")
	)
	(gr_line
		(start 72.42175 -152.746202)
		(end 72.59701 -152.921462)
		(stroke
			(width 0.06985)
			(type default)
		)
		(layer "In5.Cu")
	)
	(gr_line
		(start 72.59701 -152.921462)
		(end 73.01611 -152.921462)
		(stroke
			(width 0.06985)
			(type default)
		)
		(layer "In5.Cu")
	)
	(gr_line
		(start 72.75195 -152.413462)
		(end 72.86117 -152.413462)
		(stroke
			(width 0.06985)
			(type default)
		)
		(layer "In5.Cu")
	)
	(gr_line
		(start 73.01611 -152.921462)
		(end 73.19137 -152.746202)
		(stroke
			(width 0.06985)
			(type default)
		)
		(layer "In5.Cu")
	)
	(gr_line
		(start 76.434188 -155.14574)
		(end 76.609448 -155.321)
		(stroke
			(width 0.06985)
			(type default)
		)
		(layer "In5.Cu")
	)
	(gr_line
		(start 76.609448 -155.321)
		(end 77.028548 -155.321)
		(stroke
			(width 0.06985)
			(type default)
		)
		(layer "In5.Cu")
	)
	(gr_line
		(start 76.764388 -154.813)
		(end 76.873608 -154.813)
		(stroke
			(width 0.06985)
			(type default)
		)
		(layer "In5.Cu")
	)
	(gr_line
		(start 77.028548 -155.321)
		(end 77.203808 -155.14574)
		(stroke
			(width 0.06985)
			(type default)
		)
		(layer "In5.Cu")
	)
	(gr_line
		(start 77.143864 -156.488892)
		(end 77.319124 -156.313632)
		(stroke
			(width 0.06985)
			(type default)
		)
		(layer "In5.Cu")
	)
	(gr_line
		(start 77.319124 -156.313632)
		(end 77.738224 -156.313632)
		(stroke
			(width 0.06985)
			(type default)
		)
		(layer "In5.Cu")
	)
	(gr_line
		(start 77.474064 -156.821632)
		(end 77.583284 -156.821632)
		(stroke
			(width 0.06985)
			(type default)
		)
		(layer "In5.Cu")
	)
	(gr_line
		(start 77.627988 -155.14574)
		(end 77.803248 -155.321)
		(stroke
			(width 0.06985)
			(type default)
		)
		(layer "In5.Cu")
	)
	(gr_line
		(start 77.738224 -156.313632)
		(end 77.913484 -156.488892)
		(stroke
			(width 0.06985)
			(type default)
		)
		(layer "In5.Cu")
	)
	(gr_line
		(start 77.803248 -155.321)
		(end 78.222348 -155.321)
		(stroke
			(width 0.06985)
			(type default)
		)
		(layer "In5.Cu")
	)
	(gr_line
		(start 77.958188 -154.813)
		(end 78.067408 -154.813)
		(stroke
			(width 0.06985)
			(type default)
		)
		(layer "In5.Cu")
	)
	(gr_line
		(start 78.222348 -155.321)
		(end 78.397608 -155.14574)
		(stroke
			(width 0.06985)
			(type default)
		)
		(layer "In5.Cu")
	)
	(gr_line
		(start 78.337664 -156.488892)
		(end 78.512924 -156.313632)
		(stroke
			(width 0.06985)
			(type default)
		)
		(layer "In5.Cu")
	)
	(gr_line
		(start 78.512924 -156.313632)
		(end 78.932024 -156.313632)
		(stroke
			(width 0.06985)
			(type default)
		)
		(layer "In5.Cu")
	)
	(gr_line
		(start 78.667864 -156.821632)
		(end 78.777084 -156.821632)
		(stroke
			(width 0.06985)
			(type default)
		)
		(layer "In5.Cu")
	)
	(gr_line
		(start 78.821788 -155.14574)
		(end 78.997048 -155.321)
		(stroke
			(width 0.06985)
			(type default)
		)
		(layer "In5.Cu")
	)
	(gr_line
		(start 78.932024 -156.313632)
		(end 79.107284 -156.488892)
		(stroke
			(width 0.06985)
			(type default)
		)
		(layer "In5.Cu")
	)
	(gr_line
		(start 78.997048 -155.321)
		(end 79.416148 -155.321)
		(stroke
			(width 0.06985)
			(type default)
		)
		(layer "In5.Cu")
	)
	(gr_line
		(start 79.151988 -154.813)
		(end 79.261208 -154.813)
		(stroke
			(width 0.06985)
			(type default)
		)
		(layer "In5.Cu")
	)
	(gr_line
		(start 79.416148 -155.321)
		(end 79.591408 -155.14574)
		(stroke
			(width 0.06985)
			(type default)
		)
		(layer "In5.Cu")
	)
	(gr_line
		(start 79.531464 -156.488892)
		(end 79.706724 -156.313632)
		(stroke
			(width 0.06985)
			(type default)
		)
		(layer "In5.Cu")
	)
	(gr_line
		(start 79.706724 -156.313632)
		(end 80.125824 -156.313632)
		(stroke
			(width 0.06985)
			(type default)
		)
		(layer "In5.Cu")
	)
	(gr_line
		(start 79.861664 -156.821632)
		(end 79.970884 -156.821632)
		(stroke
			(width 0.06985)
			(type default)
		)
		(layer "In5.Cu")
	)
	(gr_line
		(start 80.125824 -156.313632)
		(end 80.301084 -156.488892)
		(stroke
			(width 0.06985)
			(type default)
		)
		(layer "In5.Cu")
	)
	(gr_line
		(start 80.725264 -156.488892)
		(end 80.900524 -156.313632)
		(stroke
			(width 0.06985)
			(type default)
		)
		(layer "In5.Cu")
	)
	(gr_line
		(start 80.890618 -154.377898)
		(end 80.96758 -154.300936)
		(stroke
			(width 0.06985)
			(type default)
		)
		(layer "In5.Cu")
	)
	(gr_line
		(start 80.892396 -154.846782)
		(end 81.1403 -154.846782)
		(stroke
			(width 0.06985)
			(type default)
		)
		(layer "In5.Cu")
	)
	(gr_line
		(start 80.900524 -156.313632)
		(end 81.319624 -156.313632)
		(stroke
			(width 0.06985)
			(type default)
		)
		(layer "In5.Cu")
	)
	(gr_line
		(start 81.055464 -156.821632)
		(end 81.164684 -156.821632)
		(stroke
			(width 0.06985)
			(type default)
		)
		(layer "In5.Cu")
	)
	(gr_line
		(start 81.1403 -154.846782)
		(end 81.436464 -154.550618)
		(stroke
			(width 0.06985)
			(type default)
		)
		(layer "In5.Cu")
	)
	(gr_line
		(start 81.319624 -156.313632)
		(end 81.494884 -156.488892)
		(stroke
			(width 0.06985)
			(type default)
		)
		(layer "In5.Cu")
	)
	(gr_line
		(start 81.436464 -154.302714)
		(end 81.436464 -154.550618)
		(stroke
			(width 0.06985)
			(type default)
		)
		(layer "In5.Cu")
	)
	(gr_line
		(start 81.73466 -153.533856)
		(end 81.811876 -153.45664)
		(stroke
			(width 0.06985)
			(type default)
		)
		(layer "In5.Cu")
	)
	(gr_line
		(start 81.736438 -154.00274)
		(end 81.984342 -154.00274)
		(stroke
			(width 0.06985)
			(type default)
		)
		(layer "In5.Cu")
	)
	(gr_line
		(start 81.984342 -154.00274)
		(end 82.28076 -153.706322)
		(stroke
			(width 0.06985)
			(type default)
		)
		(layer "In5.Cu")
	)
	(gr_line
		(start 82.28076 -153.458418)
		(end 82.28076 -153.706322)
		(stroke
			(width 0.06985)
			(type default)
		)
		(layer "In5.Cu")
	)
	(gr_line
		(start 82.967576 -155.411678)
		(end 82.967576 -155.659582)
		(stroke
			(width 0.06985)
			(type default)
		)
		(layer "In5.Cu")
	)
	(gr_line
		(start 82.967576 -155.411678)
		(end 83.263994 -155.11526)
		(stroke
			(width 0.06985)
			(type default)
		)
		(layer "In5.Cu")
	)
	(gr_line
		(start 83.263994 -155.11526)
		(end 83.511898 -155.11526)
		(stroke
			(width 0.06985)
			(type default)
		)
		(layer "In5.Cu")
	)
	(gr_line
		(start 83.358228 -95.348298)
		(end 83.358228 -95.381572)
		(stroke
			(width 0.06985)
			(type default)
		)
		(layer "In5.Cu")
	)
	(gr_arc
		(start 83.358228 -94.535498)
		(mid 83.428903 -94.706123)
		(end 83.599528 -94.776798)
		(stroke
			(width 0.06985)
			(type default)
		)
		(layer "In5.Cu")
	)
	(gr_line
		(start 83.358228 -94.492572)
		(end 83.358228 -94.535498)
		(stroke
			(width 0.06985)
			(type default)
		)
		(layer "In5.Cu")
	)
	(gr_arc
		(start 83.358228 -88.105234)
		(mid 83.440076 -88.302768)
		(end 83.637628 -88.384634)
		(stroke
			(width 0.06985)
			(type default)
		)
		(layer "In5.Cu")
	)
	(gr_arc
		(start 83.358228 -81.705196)
		(mid 83.440063 -81.902754)
		(end 83.637628 -81.984596)
		(stroke
			(width 0.06985)
			(type default)
		)
		(layer "In5.Cu")
	)
	(gr_arc
		(start 83.358228 -75.305158)
		(mid 83.440049 -75.502741)
		(end 83.637628 -75.584558)
		(stroke
			(width 0.06985)
			(type default)
		)
		(layer "In5.Cu")
	)
	(gr_line
		(start 83.43646 -155.66136)
		(end 83.513676 -155.584144)
		(stroke
			(width 0.06985)
			(type default)
		)
		(layer "In5.Cu")
	)
	(gr_arc
		(start 83.599528 -95.106998)
		(mid 83.428884 -95.177663)
		(end 83.358228 -95.348298)
		(stroke
			(width 0.06985)
			(type default)
		)
		(layer "In5.Cu")
	)
	(gr_arc
		(start 83.637628 -88.714834)
		(mid 83.440062 -88.796668)
		(end 83.358228 -88.994234)
		(stroke
			(width 0.06985)
			(type default)
		)
		(layer "In5.Cu")
	)
	(gr_arc
		(start 83.637628 -82.314796)
		(mid 83.440043 -82.39662)
		(end 83.358228 -82.594196)
		(stroke
			(width 0.06985)
			(type default)
		)
		(layer "In5.Cu")
	)
	(gr_arc
		(start 83.637628 -75.914758)
		(mid 83.440062 -75.996592)
		(end 83.358228 -76.194158)
		(stroke
			(width 0.06985)
			(type default)
		)
		(layer "In5.Cu")
	)
	(gr_line
		(start 83.811872 -154.567382)
		(end 83.811872 -154.815286)
		(stroke
			(width 0.06985)
			(type default)
		)
		(layer "In5.Cu")
	)
	(gr_line
		(start 83.811872 -154.567382)
		(end 84.108036 -154.271218)
		(stroke
			(width 0.06985)
			(type default)
		)
		(layer "In5.Cu")
	)
	(gr_line
		(start 84.108036 -154.271218)
		(end 84.35594 -154.271218)
		(stroke
			(width 0.06985)
			(type default)
		)
		(layer "In5.Cu")
	)
	(gr_line
		(start 84.280756 -154.817064)
		(end 84.357718 -154.740102)
		(stroke
			(width 0.06985)
			(type default)
		)
		(layer "In5.Cu")
	)
	(gr_line
		(start 84.393024 -152.122886)
		(end 84.431632 -152.122886)
		(stroke
			(width 0.06985)
			(type default)
		)
		(layer "In5.Cu")
	)
	(gr_line
		(start 84.723224 -152.2984)
		(end 84.761832 -152.2984)
		(stroke
			(width 0.06985)
			(type default)
		)
		(layer "In5.Cu")
	)
	(gr_arc
		(start 84.983828 -91.306396)
		(mid 85.065662 -91.503962)
		(end 85.263228 -91.585796)
		(stroke
			(width 0.06985)
			(type default)
		)
		(layer "In5.Cu")
	)
	(gr_arc
		(start 84.983828 -84.904834)
		(mid 85.065676 -85.102368)
		(end 85.263228 -85.184234)
		(stroke
			(width 0.06985)
			(type default)
		)
		(layer "In5.Cu")
	)
	(gr_arc
		(start 84.983828 -78.504796)
		(mid 85.065663 -78.702354)
		(end 85.263228 -78.784196)
		(stroke
			(width 0.06985)
			(type default)
		)
		(layer "In5.Cu")
	)
	(gr_arc
		(start 84.983828 -72.081136)
		(mid 85.065677 -72.278668)
		(end 85.263228 -72.360536)
		(stroke
			(width 0.06985)
			(type default)
		)
		(layer "In5.Cu")
	)
	(gr_line
		(start 85.099144 -153.171906)
		(end 85.333332 -153.406094)
		(stroke
			(width 0.06985)
			(type default)
		)
		(layer "In5.Cu")
	)
	(gr_arc
		(start 85.263228 -91.915996)
		(mid 85.065643 -91.99782)
		(end 84.983828 -92.195396)
		(stroke
			(width 0.06985)
			(type default)
		)
		(layer "In5.Cu")
	)
	(gr_arc
		(start 85.263228 -85.514434)
		(mid 85.065656 -85.596261)
		(end 84.983828 -85.793834)
		(stroke
			(width 0.06985)
			(type default)
		)
		(layer "In5.Cu")
	)
	(gr_arc
		(start 85.263228 -79.114396)
		(mid 85.065662 -79.19623)
		(end 84.983828 -79.393796)
		(stroke
			(width 0.06985)
			(type default)
		)
		(layer "In5.Cu")
	)
	(gr_arc
		(start 85.263228 -72.690736)
		(mid 85.065662 -72.77257)
		(end 84.983828 -72.970136)
		(stroke
			(width 0.06985)
			(type default)
		)
		(layer "In5.Cu")
	)
	(gr_line
		(start 85.803994 -153.406094)
		(end 86.038182 -153.171906)
		(stroke
			(width 0.06985)
			(type default)
		)
		(layer "In5.Cu")
	)
	(gr_line
		(start 86.296754 -156.688028)
		(end 86.530942 -156.45384)
		(stroke
			(width 0.06985)
			(type default)
		)
		(layer "In5.Cu")
	)
	(gr_line
		(start 86.296754 -155.74899)
		(end 86.530942 -155.983178)
		(stroke
			(width 0.06985)
			(type default)
		)
		(layer "In5.Cu")
	)
	(gr_line
		(start 88.693244 -71.37019)
		(end 88.708992 -71.346568)
		(stroke
			(width 0.06985)
			(type default)
		)
		(layer "In5.Cu")
	)
	(gr_line
		(start 88.708738 -71.346314)
		(end 88.708992 -71.346568)
		(stroke
			(width 0.06985)
			(type default)
		)
		(layer "In5.Cu")
	)
	(gr_line
		(start 88.708738 -71.346314)
		(end 88.713818 -71.321168)
		(stroke
			(width 0.06985)
			(type default)
		)
		(layer "In5.Cu")
	)
	(gr_line
		(start 88.803988 -45.525944)
		(end 88.808814 -45.550836)
		(stroke
			(width 0.06985)
			(type default)
		)
		(layer "In5.Cu")
	)
	(gr_line
		(start 88.803988 -45.525944)
		(end 88.809068 -45.500544)
		(stroke
			(width 0.06985)
			(type default)
		)
		(layer "In5.Cu")
	)
	(gr_line
		(start 88.809068 -45.500036)
		(end 88.809068 -45.50029)
		(stroke
			(width 0.06985)
			(type default)
		)
		(layer "In5.Cu")
	)
	(gr_line
		(start 89.014808 -50.70729)
		(end 89.01938 -50.73142)
		(stroke
			(width 0.06985)
			(type default)
		)
		(layer "In5.Cu")
	)
	(gr_line
		(start 89.014808 -50.70729)
		(end 89.019634 -50.682144)
		(stroke
			(width 0.06985)
			(type default)
		)
		(layer "In5.Cu")
	)
	(gr_line
		(start 89.243662 -59.826144)
		(end 89.248234 -59.849766)
		(stroke
			(width 0.06985)
			(type default)
		)
		(layer "In5.Cu")
	)
	(gr_line
		(start 89.243662 -59.826144)
		(end 89.248234 -59.802268)
		(stroke
			(width 0.06985)
			(type default)
		)
		(layer "In5.Cu")
	)
	(gr_line
		(start 89.248234 -59.80176)
		(end 89.248234 -59.802268)
		(stroke
			(width 0.06985)
			(type default)
		)
		(layer "In5.Cu")
	)
	(gr_line
		(start 89.25306 -73.212452)
		(end 89.267538 -73.190608)
		(stroke
			(width 0.06985)
			(type default)
		)
		(layer "In5.Cu")
	)
	(gr_line
		(start 89.267538 -73.190608)
		(end 89.272618 -73.165208)
		(stroke
			(width 0.06985)
			(type default)
		)
		(layer "In5.Cu")
	)
	(gr_line
		(start 89.745058 -48.633126)
		(end 89.749884 -48.658272)
		(stroke
			(width 0.06985)
			(type default)
		)
		(layer "In5.Cu")
	)
	(gr_line
		(start 89.745312 -48.682402)
		(end 89.749884 -48.658272)
		(stroke
			(width 0.06985)
			(type default)
		)
		(layer "In5.Cu")
	)
	(gr_line
		(start 89.765886 -45.604176)
		(end 89.770712 -45.629068)
		(stroke
			(width 0.06985)
			(type default)
		)
		(layer "In5.Cu")
	)
	(gr_line
		(start 89.765886 -45.604176)
		(end 89.770966 -45.578268)
		(stroke
			(width 0.06985)
			(type default)
		)
		(layer "In5.Cu")
	)
	(gr_line
		(start 89.770966 -45.578014)
		(end 89.770966 -45.578522)
		(stroke
			(width 0.06985)
			(type default)
		)
		(layer "In5.Cu")
	)
	(gr_line
		(start 90.162888 -50.365914)
		(end 90.16746 -50.390044)
		(stroke
			(width 0.06985)
			(type default)
		)
		(layer "In5.Cu")
	)
	(gr_line
		(start 90.162888 -50.365914)
		(end 90.167714 -50.340768)
		(stroke
			(width 0.06985)
			(type default)
		)
		(layer "In5.Cu")
	)
	(gr_line
		(start 90.267536 -74.006456)
		(end 90.281252 -73.98639)
		(stroke
			(width 0.06985)
			(type default)
		)
		(layer "In5.Cu")
	)
	(gr_line
		(start 90.281252 -73.98639)
		(end 90.286332 -73.961244)
		(stroke
			(width 0.06985)
			(type default)
		)
		(layer "In5.Cu")
	)
	(gr_line
		(start 90.28811 -63.45047)
		(end 90.29319 -63.425578)
		(stroke
			(width 0.06985)
			(type default)
		)
		(layer "In5.Cu")
	)
	(gr_line
		(start 90.28811 -63.400432)
		(end 90.29319 -63.425578)
		(stroke
			(width 0.06985)
			(type default)
		)
		(layer "In5.Cu")
	)
	(gr_line
		(start 90.34653 -55.830978)
		(end 90.351356 -55.856124)
		(stroke
			(width 0.06985)
			(type default)
		)
		(layer "In5.Cu")
	)
	(gr_line
		(start 90.346784 -55.880254)
		(end 90.351356 -55.856124)
		(stroke
			(width 0.06985)
			(type default)
		)
		(layer "In5.Cu")
	)
	(gr_line
		(start 90.38209 -59.49315)
		(end 90.386662 -59.516772)
		(stroke
			(width 0.06985)
			(type default)
		)
		(layer "In5.Cu")
	)
	(gr_line
		(start 90.38209 -59.49315)
		(end 90.386662 -59.469274)
		(stroke
			(width 0.06985)
			(type default)
		)
		(layer "In5.Cu")
	)
	(gr_line
		(start 90.386662 -59.468766)
		(end 90.386662 -59.469274)
		(stroke
			(width 0.06985)
			(type default)
		)
		(layer "In5.Cu")
	)
	(gr_line
		(start 90.520266 -76.71435)
		(end 90.53449 -76.693522)
		(stroke
			(width 0.06985)
			(type default)
		)
		(layer "In5.Cu")
	)
	(gr_line
		(start 90.53449 -76.693522)
		(end 90.53957 -76.668122)
		(stroke
			(width 0.06985)
			(type default)
		)
		(layer "In5.Cu")
	)
	(gr_line
		(start 90.680794 -36.131754)
		(end 90.685874 -36.106354)
		(stroke
			(width 0.06985)
			(type default)
		)
		(layer "In5.Cu")
	)
	(gr_line
		(start 90.685874 -36.106354)
		(end 90.700352 -36.085018)
		(stroke
			(width 0.06985)
			(type default)
		)
		(layer "In5.Cu")
	)
	(gr_line
		(start 90.710258 -45.558456)
		(end 90.715338 -45.583094)
		(stroke
			(width 0.06985)
			(type default)
		)
		(layer "In5.Cu")
	)
	(gr_line
		(start 90.710258 -45.558456)
		(end 90.715338 -45.53331)
		(stroke
			(width 0.06985)
			(type default)
		)
		(layer "In5.Cu")
	)
	(gr_line
		(start 90.759026 -48.98136)
		(end 90.763852 -49.006506)
		(stroke
			(width 0.06985)
			(type default)
		)
		(layer "In5.Cu")
	)
	(gr_line
		(start 90.75928 -49.030636)
		(end 90.763852 -49.006506)
		(stroke
			(width 0.06985)
			(type default)
		)
		(layer "In5.Cu")
	)
	(gr_line
		(start 91.077542 -79.00162)
		(end 91.091258 -78.981554)
		(stroke
			(width 0.06985)
			(type default)
		)
		(layer "In5.Cu")
	)
	(gr_line
		(start 91.091258 -78.981554)
		(end 91.096338 -78.956662)
		(stroke
			(width 0.06985)
			(type default)
		)
		(layer "In5.Cu")
	)
	(gr_line
		(start 91.353894 -62.748414)
		(end 91.358974 -62.723522)
		(stroke
			(width 0.06985)
			(type default)
		)
		(layer "In5.Cu")
	)
	(gr_line
		(start 91.353894 -62.698376)
		(end 91.358974 -62.723522)
		(stroke
			(width 0.06985)
			(type default)
		)
		(layer "In5.Cu")
	)
	(gr_line
		(start 91.491054 -55.468012)
		(end 91.49588 -55.493158)
		(stroke
			(width 0.06985)
			(type default)
		)
		(layer "In5.Cu")
	)
	(gr_line
		(start 91.491308 -55.517288)
		(end 91.49588 -55.493158)
		(stroke
			(width 0.06985)
			(type default)
		)
		(layer "In5.Cu")
	)
	(gr_line
		(start 91.559888 -45.74159)
		(end 91.564968 -45.766228)
		(stroke
			(width 0.06985)
			(type default)
		)
		(layer "In5.Cu")
	)
	(gr_line
		(start 91.559888 -45.74159)
		(end 91.564968 -45.716444)
		(stroke
			(width 0.06985)
			(type default)
		)
		(layer "In5.Cu")
	)
	(gr_line
		(start 91.567762 -81.582006)
		(end 91.581986 -81.561178)
		(stroke
			(width 0.06985)
			(type default)
		)
		(layer "In5.Cu")
	)
	(gr_line
		(start 91.581986 -81.561178)
		(end 91.587066 -81.535778)
		(stroke
			(width 0.06985)
			(type default)
		)
		(layer "In5.Cu")
	)
	(gr_line
		(start 91.60256 -36.420806)
		(end 91.60764 -36.395406)
		(stroke
			(width 0.06985)
			(type default)
		)
		(layer "In5.Cu")
	)
	(gr_line
		(start 91.60764 -36.395406)
		(end 91.622118 -36.37407)
		(stroke
			(width 0.06985)
			(type default)
		)
		(layer "In5.Cu")
	)
	(gr_line
		(start 92.016834 -83.646264)
		(end 92.031058 -83.625182)
		(stroke
			(width 0.06985)
			(type default)
		)
		(layer "In5.Cu")
	)
	(gr_line
		(start 92.031058 -83.625182)
		(end 92.036138 -83.600036)
		(stroke
			(width 0.06985)
			(type default)
		)
		(layer "In5.Cu")
	)
	(gr_line
		(start 92.374212 -37.234368)
		(end 92.379292 -37.209222)
		(stroke
			(width 0.06985)
			(type default)
		)
		(layer "In5.Cu")
	)
	(gr_line
		(start 92.379292 -37.209222)
		(end 92.393262 -37.18814)
		(stroke
			(width 0.06985)
			(type default)
		)
		(layer "In5.Cu")
	)
	(gr_line
		(start 92.477336 -46.063154)
		(end 92.482416 -46.087792)
		(stroke
			(width 0.06985)
			(type default)
		)
		(layer "In5.Cu")
	)
	(gr_line
		(start 92.477336 -46.063154)
		(end 92.482416 -46.038008)
		(stroke
			(width 0.06985)
			(type default)
		)
		(layer "In5.Cu")
	)
	(gr_line
		(start 92.51823 -85.366098)
		(end 92.52966 -85.348318)
		(stroke
			(width 0.06985)
			(type default)
		)
		(layer "In5.Cu")
	)
	(gr_line
		(start 92.52966 -85.348318)
		(end 92.533978 -85.326982)
		(stroke
			(width 0.06985)
			(type default)
		)
		(layer "In5.Cu")
	)
	(gr_line
		(start 92.865448 -32.848042)
		(end 92.880942 -32.824928)
		(stroke
			(width 0.06985)
			(type default)
		)
		(layer "In5.Cu")
	)
	(gr_line
		(start 92.880942 -32.824928)
		(end 92.90431 -32.809434)
		(stroke
			(width 0.06985)
			(type default)
		)
		(layer "In5.Cu")
	)
	(gr_line
		(start 93.13926 -37.839904)
		(end 93.144086 -37.816282)
		(stroke
			(width 0.06985)
			(type default)
		)
		(layer "In5.Cu")
	)
	(gr_line
		(start 93.144086 -37.816282)
		(end 93.157294 -37.796216)
		(stroke
			(width 0.06985)
			(type default)
		)
		(layer "In5.Cu")
	)
	(gr_line
		(start 93.323664 -33.828736)
		(end 93.339158 -33.805622)
		(stroke
			(width 0.06985)
			(type default)
		)
		(layer "In5.Cu")
	)
	(gr_line
		(start 93.339158 -33.805622)
		(end 93.362526 -33.790128)
		(stroke
			(width 0.06985)
			(type default)
		)
		(layer "In5.Cu")
	)
	(gr_line
		(start 93.94317 -38.72865)
		(end 93.94825 -38.703504)
		(stroke
			(width 0.06985)
			(type default)
		)
		(layer "In5.Cu")
	)
	(gr_line
		(start 93.94825 -38.703504)
		(end 93.961966 -38.683438)
		(stroke
			(width 0.06985)
			(type default)
		)
		(layer "In5.Cu")
	)
	(gr_line
		(start 94.310708 -34.312352)
		(end 94.326202 -34.289238)
		(stroke
			(width 0.06985)
			(type default)
		)
		(layer "In5.Cu")
	)
	(gr_line
		(start 94.326202 -34.289238)
		(end 94.349062 -34.274252)
		(stroke
			(width 0.06985)
			(type default)
		)
		(layer "In5.Cu")
	)
	(gr_line
		(start 94.393512 -46.317154)
		(end 94.397576 -46.317154)
		(stroke
			(width 0.06985)
			(type default)
		)
		(layer "In5.Cu")
	)
	(gr_line
		(start 94.393512 -46.317154)
		(end 94.398338 -46.293024)
		(stroke
			(width 0.06985)
			(type default)
		)
		(layer "In5.Cu")
	)
	(gr_line
		(start 94.400116 -46.317408)
		(end 94.406466 -46.382178)
		(stroke
			(width 0.06985)
			(type default)
		)
		(layer "In5.Cu")
	)
	(gr_line
		(start 94.730316 -46.317408)
		(end 94.733364 -46.332902)
		(stroke
			(width 0.06985)
			(type default)
		)
		(layer "In5.Cu")
	)
	(gr_line
		(start 94.730316 -46.317154)
		(end 94.730316 -46.317408)
		(stroke
			(width 0.06985)
			(type default)
		)
		(layer "In5.Cu")
	)
	(gr_line
		(start 94.730316 -46.317154)
		(end 94.731332 -46.31182)
		(stroke
			(width 0.06985)
			(type default)
		)
		(layer "In5.Cu")
	)
	(gr_line
		(start 94.944184 -35.094164)
		(end 94.960186 -35.070034)
		(stroke
			(width 0.06985)
			(type default)
		)
		(layer "In5.Cu")
	)
	(gr_line
		(start 94.960186 -35.070034)
		(end 94.984316 -35.054032)
		(stroke
			(width 0.06985)
			(type default)
		)
		(layer "In5.Cu")
	)
	(gr_line
		(start 95.235014 -58.167016)
		(end 95.240094 -58.192162)
		(stroke
			(width 0.06985)
			(type default)
		)
		(layer "In5.Cu")
	)
	(gr_line
		(start 95.235268 -58.216292)
		(end 95.240094 -58.192162)
		(stroke
			(width 0.06985)
			(type default)
		)
		(layer "In5.Cu")
	)
	(gr_line
		(start 95.273876 -46.531276)
		(end 95.278956 -46.555914)
		(stroke
			(width 0.06985)
			(type default)
		)
		(layer "In5.Cu")
	)
	(gr_line
		(start 95.273876 -46.531276)
		(end 95.278956 -46.50613)
		(stroke
			(width 0.06985)
			(type default)
		)
		(layer "In5.Cu")
	)
	(gr_line
		(start 95.817944 -35.898328)
		(end 95.833438 -35.875214)
		(stroke
			(width 0.06985)
			(type default)
		)
		(layer "In5.Cu")
	)
	(gr_line
		(start 95.833438 -35.875214)
		(end 95.856298 -35.860228)
		(stroke
			(width 0.06985)
			(type default)
		)
		(layer "In5.Cu")
	)
	(gr_line
		(start 96.15424 -46.959774)
		(end 96.15932 -46.984666)
		(stroke
			(width 0.06985)
			(type default)
		)
		(layer "In5.Cu")
	)
	(gr_line
		(start 96.15424 -46.95952)
		(end 96.15424 -46.959774)
		(stroke
			(width 0.06985)
			(type default)
		)
		(layer "In5.Cu")
	)
	(gr_line
		(start 96.15424 -46.95952)
		(end 96.15932 -46.934374)
		(stroke
			(width 0.06985)
			(type default)
		)
		(layer "In5.Cu")
	)
	(gr_line
		(start 96.208088 -37.241226)
		(end 96.213168 -37.215826)
		(stroke
			(width 0.06985)
			(type default)
		)
		(layer "In5.Cu")
	)
	(gr_line
		(start 96.213168 -37.215826)
		(end 96.227392 -37.194998)
		(stroke
			(width 0.06985)
			(type default)
		)
		(layer "In5.Cu")
	)
	(gr_line
		(start 96.675194 -56.09082)
		(end 96.680274 -56.066182)
		(stroke
			(width 0.06985)
			(type default)
		)
		(layer "In5.Cu")
	)
	(gr_line
		(start 96.675194 -56.041036)
		(end 96.680274 -56.066182)
		(stroke
			(width 0.06985)
			(type default)
		)
		(layer "In5.Cu")
	)
	(gr_line
		(start 96.81972 -36.305998)
		(end 96.835214 -36.282884)
		(stroke
			(width 0.06985)
			(type default)
		)
		(layer "In5.Cu")
	)
	(gr_line
		(start 96.835214 -36.282884)
		(end 96.858074 -36.267898)
		(stroke
			(width 0.06985)
			(type default)
		)
		(layer "In5.Cu")
	)
	(gr_line
		(start 96.95815 -38.114732)
		(end 96.96323 -38.089586)
		(stroke
			(width 0.06985)
			(type default)
		)
		(layer "In5.Cu")
	)
	(gr_line
		(start 96.96323 -38.089586)
		(end 96.977454 -38.068758)
		(stroke
			(width 0.06985)
			(type default)
		)
		(layer "In5.Cu")
	)
	(gr_line
		(start 97.52584 -56.154066)
		(end 97.53092 -56.129428)
		(stroke
			(width 0.06985)
			(type default)
		)
		(layer "In5.Cu")
	)
	(gr_line
		(start 97.52584 -56.104282)
		(end 97.53092 -56.129428)
		(stroke
			(width 0.06985)
			(type default)
		)
		(layer "In5.Cu")
	)
	(gr_line
		(start 97.674684 -39.350696)
		(end 97.679764 -39.325296)
		(stroke
			(width 0.06985)
			(type default)
		)
		(layer "In5.Cu")
	)
	(gr_line
		(start 97.679764 -39.325296)
		(end 97.694242 -39.303452)
		(stroke
			(width 0.06985)
			(type default)
		)
		(layer "In5.Cu")
	)
	(gr_line
		(start 97.689924 -37.010086)
		(end 97.704656 -36.987988)
		(stroke
			(width 0.06985)
			(type default)
		)
		(layer "In5.Cu")
	)
	(gr_line
		(start 97.704656 -36.987988)
		(end 97.727008 -36.973002)
		(stroke
			(width 0.06985)
			(type default)
		)
		(layer "In5.Cu")
	)
	(gr_line
		(start 98.343974 -56.275732)
		(end 98.349054 -56.251094)
		(stroke
			(width 0.06985)
			(type default)
		)
		(layer "In5.Cu")
	)
	(gr_line
		(start 98.343974 -56.225948)
		(end 98.349054 -56.251094)
		(stroke
			(width 0.06985)
			(type default)
		)
		(layer "In5.Cu")
	)
	(gr_line
		(start 99.99472 -36.64204)
		(end 99.99472 -36.642294)
		(stroke
			(width 0.06985)
			(type default)
		)
		(layer "In5.Cu")
	)
	(gr_line
		(start 100.2284 -36.87572)
		(end 100.32492 -36.87572)
		(stroke
			(width 0.06985)
			(type default)
		)
		(layer "In5.Cu")
	)
	(gr_line
		(start 103.385366 -25.875234)
		(end 103.434642 -25.842722)
		(stroke
			(width 0.06985)
			(type default)
		)
		(layer "In5.Cu")
	)
	(gr_line
		(start 104.145588 -26.655522)
		(end 104.194864 -26.62301)
		(stroke
			(width 0.06985)
			(type default)
		)
		(layer "In5.Cu")
	)
	(gr_line
		(start 104.636824 -27.464766)
		(end 104.6861 -27.432254)
		(stroke
			(width 0.06985)
			(type default)
		)
		(layer "In5.Cu")
	)
	(gr_line
		(start 105.25633 -28.256484)
		(end 105.305606 -28.223972)
		(stroke
			(width 0.06985)
			(type default)
		)
		(layer "In5.Cu")
	)
	(gr_line
		(start 106.139488 -29.054044)
		(end 106.188764 -29.021532)
		(stroke
			(width 0.06985)
			(type default)
		)
		(layer "In5.Cu")
	)
	(gr_line
		(start 106.581448 -29.833824)
		(end 106.630724 -29.801312)
		(stroke
			(width 0.06985)
			(type default)
		)
		(layer "In5.Cu")
	)
	(gr_line
		(start 106.726228 -30.999684)
		(end 106.775758 -30.966918)
		(stroke
			(width 0.06985)
			(type default)
		)
		(layer "In5.Cu")
	)
	(gr_arc
		(start 106.8959 -37.334952)
		(mid 107.040123 -37.275213)
		(end 107.099862 -37.13099)
		(stroke
			(width 0.06985)
			(type default)
		)
		(layer "In5.Cu")
	)
	(gr_arc
		(start 107.099862 -37.869114)
		(mid 107.040128 -37.724882)
		(end 106.8959 -37.665152)
		(stroke
			(width 0.06985)
			(type default)
		)
		(layer "In5.Cu")
	)
	(gr_line
		(start 107.099862 -37.869114)
		(end 107.099862 -38.200076)
		(stroke
			(width 0.06985)
			(type default)
		)
		(layer "In5.Cu")
	)
	(gr_line
		(start 107.099862 -36.800028)
		(end 107.099862 -37.13099)
		(stroke
			(width 0.06985)
			(type default)
		)
		(layer "In5.Cu")
	)
	(gr_arc
		(start 108.712 -36.135056)
		(mid 108.844908 -36.080004)
		(end 108.89996 -35.947096)
		(stroke
			(width 0.06985)
			(type default)
		)
		(layer "In5.Cu")
	)
	(gr_arc
		(start 108.89996 -36.653216)
		(mid 108.844913 -36.520298)
		(end 108.712 -36.465256)
		(stroke
			(width 0.06985)
			(type default)
		)
		(layer "In5.Cu")
	)
	(gr_line
		(start 108.89996 -36.653216)
		(end 108.89996 -37.00018)
		(stroke
			(width 0.06985)
			(type default)
		)
		(layer "In5.Cu")
	)
	(gr_line
		(start 108.89996 -35.600132)
		(end 108.89996 -35.947096)
		(stroke
			(width 0.06985)
			(type default)
		)
		(layer "In5.Cu")
	)
	(gr_arc
		(start 110.512098 -37.334952)
		(mid 110.645004 -37.2799)
		(end 110.700058 -37.146992)
		(stroke
			(width 0.06985)
			(type default)
		)
		(layer "In5.Cu")
	)
	(gr_arc
		(start 110.700058 -37.853112)
		(mid 110.645006 -37.720204)
		(end 110.512098 -37.665152)
		(stroke
			(width 0.06985)
			(type default)
		)
		(layer "In5.Cu")
	)
	(gr_line
		(start 110.700058 -37.853112)
		(end 110.700058 -38.200076)
		(stroke
			(width 0.06985)
			(type default)
		)
		(layer "In5.Cu")
	)
	(gr_line
		(start 110.700058 -36.800028)
		(end 110.700058 -37.146992)
		(stroke
			(width 0.06985)
			(type default)
		)
		(layer "In5.Cu")
	)
	(gr_arc
		(start 112.311942 -36.135056)
		(mid 112.444821 -36.079989)
		(end 112.499902 -35.947096)
		(stroke
			(width 0.06985)
			(type default)
		)
		(layer "In5.Cu")
	)
	(gr_arc
		(start 112.499902 -36.653216)
		(mid 112.444858 -36.520283)
		(end 112.311942 -36.465256)
		(stroke
			(width 0.06985)
			(type default)
		)
		(layer "In5.Cu")
	)
	(gr_line
		(start 112.499902 -36.653216)
		(end 112.499902 -37.00018)
		(stroke
			(width 0.06985)
			(type default)
		)
		(layer "In5.Cu")
	)
	(gr_line
		(start 112.499902 -35.600132)
		(end 112.499902 -35.947096)
		(stroke
			(width 0.06985)
			(type default)
		)
		(layer "In5.Cu")
	)
	(gr_arc
		(start 114.11204 -37.334952)
		(mid 114.244919 -37.279885)
		(end 114.3 -37.146992)
		(stroke
			(width 0.06985)
			(type default)
		)
		(layer "In5.Cu")
	)
	(gr_arc
		(start 114.3 -37.853112)
		(mid 114.244954 -37.720182)
		(end 114.11204 -37.665152)
		(stroke
			(width 0.06985)
			(type default)
		)
		(layer "In5.Cu")
	)
	(gr_line
		(start 114.3 -37.853112)
		(end 114.3 -38.200076)
		(stroke
			(width 0.06985)
			(type default)
		)
		(layer "In5.Cu")
	)
	(gr_line
		(start 114.3 -36.800028)
		(end 114.3 -37.146992)
		(stroke
			(width 0.06985)
			(type default)
		)
		(layer "In5.Cu")
	)
	(gr_arc
		(start 115.911884 -36.135056)
		(mid 116.044801 -36.080009)
		(end 116.099844 -35.947096)
		(stroke
			(width 0.06985)
			(type default)
		)
		(layer "In5.Cu")
	)
	(gr_arc
		(start 116.099844 -36.653216)
		(mid 116.044792 -36.520308)
		(end 115.911884 -36.465256)
		(stroke
			(width 0.06985)
			(type default)
		)
		(layer "In5.Cu")
	)
	(gr_line
		(start 116.099844 -36.653216)
		(end 116.099844 -37.00018)
		(stroke
			(width 0.06985)
			(type default)
		)
		(layer "In5.Cu")
	)
	(gr_line
		(start 116.099844 -35.600132)
		(end 116.099844 -35.947096)
		(stroke
			(width 0.06985)
			(type default)
		)
		(layer "In5.Cu")
	)
	(gr_arc
		(start 117.711982 -37.334952)
		(mid 117.844899 -37.279906)
		(end 117.899942 -37.146992)
		(stroke
			(width 0.06985)
			(type default)
		)
		(layer "In5.Cu")
	)
	(gr_arc
		(start 117.899942 -37.853112)
		(mid 117.84489 -37.720204)
		(end 117.711982 -37.665152)
		(stroke
			(width 0.06985)
			(type default)
		)
		(layer "In5.Cu")
	)
	(gr_line
		(start 117.899942 -37.853112)
		(end 117.899942 -38.200076)
		(stroke
			(width 0.06985)
			(type default)
		)
		(layer "In5.Cu")
	)
	(gr_line
		(start 117.899942 -36.800028)
		(end 117.899942 -37.146992)
		(stroke
			(width 0.06985)
			(type default)
		)
		(layer "In5.Cu")
	)
	(gr_arc
		(start 119.51208 -36.135056)
		(mid 119.644999 -36.080011)
		(end 119.70004 -35.947096)
		(stroke
			(width 0.06985)
			(type default)
		)
		(layer "In5.Cu")
	)
	(gr_arc
		(start 119.70004 -36.653216)
		(mid 119.644988 -36.520308)
		(end 119.51208 -36.465256)
		(stroke
			(width 0.06985)
			(type default)
		)
		(layer "In5.Cu")
	)
	(gr_line
		(start 119.70004 -36.653216)
		(end 119.70004 -37.00018)
		(stroke
			(width 0.06985)
			(type default)
		)
		(layer "In5.Cu")
	)
	(gr_line
		(start 119.70004 -35.600132)
		(end 119.70004 -35.947096)
		(stroke
			(width 0.06985)
			(type default)
		)
		(layer "In5.Cu")
	)
	(gr_arc
		(start 128.484122 -33.738058)
		(mid 128.636786 -33.674822)
		(end 128.700022 -33.522158)
		(stroke
			(width 0.06985)
			(type default)
		)
		(layer "In5.Cu")
	)
	(gr_arc
		(start 128.700022 -34.284158)
		(mid 128.636786 -34.131494)
		(end 128.484122 -34.068258)
		(stroke
			(width 0.06985)
			(type default)
		)
		(layer "In5.Cu")
	)
	(gr_line
		(start 128.700022 -34.284158)
		(end 128.700022 -34.600134)
		(stroke
			(width 0.06985)
			(type default)
		)
		(layer "In5.Cu")
	)
	(gr_line
		(start 128.700022 -33.200086)
		(end 128.700022 -33.522158)
		(stroke
			(width 0.06985)
			(type default)
		)
		(layer "In5.Cu")
	)
	(gr_arc
		(start 130.283966 -32.537908)
		(mid 130.43663 -32.474672)
		(end 130.499866 -32.322008)
		(stroke
			(width 0.06985)
			(type default)
		)
		(layer "In5.Cu")
	)
	(gr_line
		(start 130.494278 -26.05786)
		(end 130.57124 -25.980898)
		(stroke
			(width 0.06985)
			(type default)
		)
		(layer "In5.Cu")
	)
	(gr_line
		(start 130.496056 -26.526744)
		(end 130.74396 -26.526744)
		(stroke
			(width 0.06985)
			(type default)
		)
		(layer "In5.Cu")
	)
	(gr_arc
		(start 130.499866 -33.084008)
		(mid 130.436631 -32.93135)
		(end 130.283966 -32.868108)
		(stroke
			(width 0.06985)
			(type default)
		)
		(layer "In5.Cu")
	)
	(gr_line
		(start 130.499866 -33.084008)
		(end 130.499866 -33.399984)
		(stroke
			(width 0.06985)
			(type default)
		)
		(layer "In5.Cu")
	)
	(gr_line
		(start 130.499866 -32.00019)
		(end 130.499866 -32.322008)
		(stroke
			(width 0.06985)
			(type default)
		)
		(layer "In5.Cu")
	)
	(gr_line
		(start 130.74396 -26.526744)
		(end 131.040124 -26.23058)
		(stroke
			(width 0.06985)
			(type default)
		)
		(layer "In5.Cu")
	)
	(gr_line
		(start 131.040124 -25.982676)
		(end 131.040124 -26.23058)
		(stroke
			(width 0.06985)
			(type default)
		)
		(layer "In5.Cu")
	)
	(gr_line
		(start 131.33832 -25.213818)
		(end 131.415536 -25.136602)
		(stroke
			(width 0.06985)
			(type default)
		)
		(layer "In5.Cu")
	)
	(gr_line
		(start 131.340098 -25.682702)
		(end 131.588002 -25.682702)
		(stroke
			(width 0.06985)
			(type default)
		)
		(layer "In5.Cu")
	)
	(gr_line
		(start 131.588002 -25.682702)
		(end 131.88442 -25.386284)
		(stroke
			(width 0.06985)
			(type default)
		)
		(layer "In5.Cu")
	)
	(gr_line
		(start 131.88442 -25.13838)
		(end 131.88442 -25.386284)
		(stroke
			(width 0.06985)
			(type default)
		)
		(layer "In5.Cu")
	)
	(gr_arc
		(start 132.084064 -33.738058)
		(mid 132.236728 -33.674822)
		(end 132.299964 -33.522158)
		(stroke
			(width 0.06985)
			(type default)
		)
		(layer "In5.Cu")
	)
	(gr_arc
		(start 132.299964 -34.284158)
		(mid 132.236711 -34.131534)
		(end 132.084064 -34.068258)
		(stroke
			(width 0.06985)
			(type default)
		)
		(layer "In5.Cu")
	)
	(gr_line
		(start 132.299964 -34.284158)
		(end 132.299964 -34.600134)
		(stroke
			(width 0.06985)
			(type default)
		)
		(layer "In5.Cu")
	)
	(gr_line
		(start 132.299964 -33.200086)
		(end 132.299964 -33.522158)
		(stroke
			(width 0.06985)
			(type default)
		)
		(layer "In5.Cu")
	)
	(gr_line
		(start 132.300726 -26.20772)
		(end 132.377942 -26.130504)
		(stroke
			(width 0.06985)
			(type default)
		)
		(layer "In5.Cu")
	)
	(gr_line
		(start 132.302504 -26.676604)
		(end 132.550408 -26.676604)
		(stroke
			(width 0.06985)
			(type default)
		)
		(layer "In5.Cu")
	)
	(gr_line
		(start 132.550408 -26.676604)
		(end 132.846826 -26.380186)
		(stroke
			(width 0.06985)
			(type default)
		)
		(layer "In5.Cu")
	)
	(gr_line
		(start 132.846826 -26.132282)
		(end 132.846826 -26.380186)
		(stroke
			(width 0.06985)
			(type default)
		)
		(layer "In5.Cu")
	)
	(gr_line
		(start 133.145022 -25.363424)
		(end 133.221984 -25.286462)
		(stroke
			(width 0.06985)
			(type default)
		)
		(layer "In5.Cu")
	)
	(gr_line
		(start 133.1468 -25.832308)
		(end 133.394704 -25.832308)
		(stroke
			(width 0.06985)
			(type default)
		)
		(layer "In5.Cu")
	)
	(gr_line
		(start 133.394704 -25.832308)
		(end 133.690868 -25.536144)
		(stroke
			(width 0.06985)
			(type default)
		)
		(layer "In5.Cu")
	)
	(gr_line
		(start 133.690868 -25.28824)
		(end 133.690868 -25.536144)
		(stroke
			(width 0.06985)
			(type default)
		)
		(layer "In5.Cu")
	)
	(gr_arc
		(start 133.884162 -32.537908)
		(mid 134.036826 -32.474672)
		(end 134.100062 -32.322008)
		(stroke
			(width 0.06985)
			(type default)
		)
		(layer "In5.Cu")
	)
	(gr_arc
		(start 134.100062 -33.084008)
		(mid 134.036827 -32.931352)
		(end 133.884162 -32.868108)
		(stroke
			(width 0.06985)
			(type default)
		)
		(layer "In5.Cu")
	)
	(gr_line
		(start 134.100062 -33.084008)
		(end 134.100062 -33.399984)
		(stroke
			(width 0.06985)
			(type default)
		)
		(layer "In5.Cu")
	)
	(gr_line
		(start 134.100062 -32.00019)
		(end 134.100062 -32.322008)
		(stroke
			(width 0.06985)
			(type default)
		)
		(layer "In5.Cu")
	)
	(gr_arc
		(start 135.684006 -33.738058)
		(mid 135.836652 -33.674818)
		(end 135.899906 -33.522158)
		(stroke
			(width 0.06985)
			(type default)
		)
		(layer "In5.Cu")
	)
	(gr_arc
		(start 135.899906 -34.284158)
		(mid 135.836656 -34.131519)
		(end 135.684006 -34.068258)
		(stroke
			(width 0.06985)
			(type default)
		)
		(layer "In5.Cu")
	)
	(gr_line
		(start 135.899906 -34.284158)
		(end 135.899906 -34.600134)
		(stroke
			(width 0.06985)
			(type default)
		)
		(layer "In5.Cu")
	)
	(gr_line
		(start 135.899906 -33.200086)
		(end 135.899906 -33.522158)
		(stroke
			(width 0.06985)
			(type default)
		)
		(layer "In5.Cu")
	)
	(gr_arc
		(start 137.484104 -32.537908)
		(mid 137.636768 -32.474672)
		(end 137.700004 -32.322008)
		(stroke
			(width 0.06985)
			(type default)
		)
		(layer "In5.Cu")
	)
	(gr_arc
		(start 137.700004 -33.084008)
		(mid 137.636771 -32.931337)
		(end 137.484104 -32.868108)
		(stroke
			(width 0.06985)
			(type default)
		)
		(layer "In5.Cu")
	)
	(gr_line
		(start 137.700004 -33.084008)
		(end 137.700004 -33.399984)
		(stroke
			(width 0.06985)
			(type default)
		)
		(layer "In5.Cu")
	)
	(gr_line
		(start 137.700004 -32.00019)
		(end 137.700004 -32.322008)
		(stroke
			(width 0.06985)
			(type default)
		)
		(layer "In5.Cu")
	)
	(gr_arc
		(start 139.2682 -33.73501)
		(mid 139.432 -33.667162)
		(end 139.499848 -33.503362)
		(stroke
			(width 0.06985)
			(type default)
		)
		(layer "In5.Cu")
	)
	(gr_arc
		(start 139.499848 -34.296858)
		(mid 139.431985 -34.133085)
		(end 139.2682 -34.06521)
		(stroke
			(width 0.06985)
			(type default)
		)
		(layer "In5.Cu")
	)
	(gr_line
		(start 139.499848 -34.296858)
		(end 139.499848 -34.600134)
		(stroke
			(width 0.06985)
			(type default)
		)
		(layer "In5.Cu")
	)
	(gr_line
		(start 139.499848 -33.200086)
		(end 139.499848 -33.503362)
		(stroke
			(width 0.06985)
			(type default)
		)
		(layer "In5.Cu")
	)
	(gr_arc
		(start 141.068298 -32.535114)
		(mid 141.232098 -32.467266)
		(end 141.299946 -32.303466)
		(stroke
			(width 0.06985)
			(type default)
		)
		(layer "In5.Cu")
	)
	(gr_line
		(start 141.299946 -43.878246)
		(end 141.299946 -44.200064)
		(stroke
			(width 0.06985)
			(type default)
		)
		(layer "In5.Cu")
	)
	(gr_arc
		(start 141.299946 -43.116246)
		(mid 141.363182 -43.26891)
		(end 141.515846 -43.332146)
		(stroke
			(width 0.06985)
			(type default)
		)
		(layer "In5.Cu")
	)
	(gr_line
		(start 141.299946 -42.800016)
		(end 141.299946 -43.116246)
		(stroke
			(width 0.06985)
			(type default)
		)
		(layer "In5.Cu")
	)
	(gr_arc
		(start 141.299946 -33.096962)
		(mid 141.232084 -32.933187)
		(end 141.068298 -32.865314)
		(stroke
			(width 0.06985)
			(type default)
		)
		(layer "In5.Cu")
	)
	(gr_line
		(start 141.299946 -33.096962)
		(end 141.299946 -33.399984)
		(stroke
			(width 0.06985)
			(type default)
		)
		(layer "In5.Cu")
	)
	(gr_line
		(start 141.299946 -32.00019)
		(end 141.299946 -32.303466)
		(stroke
			(width 0.06985)
			(type default)
		)
		(layer "In5.Cu")
	)
	(gr_arc
		(start 141.515846 -43.662346)
		(mid 141.363182 -43.725582)
		(end 141.299946 -43.878246)
		(stroke
			(width 0.06985)
			(type default)
		)
		(layer "In5.Cu")
	)
	(gr_line
		(start 142.792196 -29.730954)
		(end 142.860268 -29.799026)
		(stroke
			(width 0.06985)
			(type default)
		)
		(layer "In5.Cu")
	)
	(gr_line
		(start 143.06804 -43.332146)
		(end 143.126714 -43.380406)
		(stroke
			(width 0.06985)
			(type default)
		)
		(layer "In5.Cu")
	)
	(gr_line
		(start 143.249396 -28.953968)
		(end 143.317468 -29.02204)
		(stroke
			(width 0.06985)
			(type default)
		)
		(layer "In5.Cu")
	)
	(gr_line
		(start 143.69415 -28.146756)
		(end 143.762222 -28.214828)
		(stroke
			(width 0.06985)
			(type default)
		)
		(layer "In5.Cu")
	)
	(gr_line
		(start 144.008856 -27.339036)
		(end 144.076928 -27.407108)
		(stroke
			(width 0.06985)
			(type default)
		)
		(layer "In5.Cu")
	)
	(gr_line
		(start 144.376648 -26.42489)
		(end 144.44472 -26.492962)
		(stroke
			(width 0.06985)
			(type default)
		)
		(layer "In5.Cu")
	)
	(gr_line
		(start 144.681448 -25.571958)
		(end 144.749774 -25.64003)
		(stroke
			(width 0.06985)
			(type default)
		)
		(layer "In5.Cu")
	)
	(gr_line
		(start 145.03019 -44.936664)
		(end 145.039334 -44.944284)
		(stroke
			(width 0.06985)
			(type default)
		)
		(layer "In5.Cu")
	)
	(gr_line
		(start 145.039334 -44.944284)
		(end 145.045938 -44.95419)
		(stroke
			(width 0.06985)
			(type default)
		)
		(layer "In5.Cu")
	)
	(gr_line
		(start 145.408904 -34.407094)
		(end 145.488914 -34.818574)
		(stroke
			(width 0.06985)
			(type default)
		)
		(layer "In5.Cu")
	)
	(gr_line
		(start 145.408904 -34.407094)
		(end 145.547588 -34.201608)
		(stroke
			(width 0.06985)
			(type default)
		)
		(layer "In5.Cu")
	)
	(gr_line
		(start 145.488914 -34.818574)
		(end 145.694654 -34.957258)
		(stroke
			(width 0.06985)
			(type default)
		)
		(layer "In5.Cu")
	)
	(gr_line
		(start 145.636742 -35.57905)
		(end 145.716752 -35.99053)
		(stroke
			(width 0.06985)
			(type default)
		)
		(layer "In5.Cu")
	)
	(gr_line
		(start 145.636742 -35.57905)
		(end 145.775426 -35.373564)
		(stroke
			(width 0.06985)
			(type default)
		)
		(layer "In5.Cu")
	)
	(gr_line
		(start 145.716752 -35.99053)
		(end 145.922492 -36.129214)
		(stroke
			(width 0.06985)
			(type default)
		)
		(layer "In5.Cu")
	)
	(gr_line
		(start 145.767044 -33.63849)
		(end 145.781268 -33.659318)
		(stroke
			(width 0.06985)
			(type default)
		)
		(layer "In5.Cu")
	)
	(gr_line
		(start 145.781268 -33.659318)
		(end 145.786348 -33.685226)
		(stroke
			(width 0.06985)
			(type default)
		)
		(layer "In5.Cu")
	)
	(gr_line
		(start 145.86458 -36.751006)
		(end 145.944336 -37.162232)
		(stroke
			(width 0.06985)
			(type default)
		)
		(layer "In5.Cu")
	)
	(gr_line
		(start 145.86458 -36.751006)
		(end 146.003264 -36.545266)
		(stroke
			(width 0.06985)
			(type default)
		)
		(layer "In5.Cu")
	)
	(gr_line
		(start 145.881598 -34.174684)
		(end 146.014186 -34.856928)
		(stroke
			(width 0.06985)
			(type default)
		)
		(layer "In5.Cu")
	)
	(gr_line
		(start 145.944336 -37.162232)
		(end 146.150076 -37.30117)
		(stroke
			(width 0.06985)
			(type default)
		)
		(layer "In5.Cu")
	)
	(gr_line
		(start 146.092164 -37.922708)
		(end 146.172174 -38.334188)
		(stroke
			(width 0.06985)
			(type default)
		)
		(layer "In5.Cu")
	)
	(gr_line
		(start 146.092164 -37.922708)
		(end 146.231102 -37.717222)
		(stroke
			(width 0.06985)
			(type default)
		)
		(layer "In5.Cu")
	)
	(gr_line
		(start 146.109436 -35.346894)
		(end 146.242278 -36.030662)
		(stroke
			(width 0.06985)
			(type default)
		)
		(layer "In5.Cu")
	)
	(gr_line
		(start 146.172174 -38.334188)
		(end 146.377914 -38.473126)
		(stroke
			(width 0.06985)
			(type default)
		)
		(layer "In5.Cu")
	)
	(gr_line
		(start 146.33702 -36.518596)
		(end 146.469608 -37.20084)
		(stroke
			(width 0.06985)
			(type default)
		)
		(layer "In5.Cu")
	)
	(gr_line
		(start 146.448272 -34.530538)
		(end 146.530314 -34.94151)
		(stroke
			(width 0.06985)
			(type default)
		)
		(layer "In5.Cu")
	)
	(gr_line
		(start 146.448272 -34.530538)
		(end 146.58594 -34.324036)
		(stroke
			(width 0.06985)
			(type default)
		)
		(layer "In5.Cu")
	)
	(gr_line
		(start 146.530314 -34.94151)
		(end 146.73707 -35.079178)
		(stroke
			(width 0.06985)
			(type default)
		)
		(layer "In5.Cu")
	)
	(gr_line
		(start 146.564858 -37.69106)
		(end 146.697446 -38.372796)
		(stroke
			(width 0.06985)
			(type default)
		)
		(layer "In5.Cu")
	)
	(gr_line
		(start 146.68246 -35.701224)
		(end 146.764502 -36.112196)
		(stroke
			(width 0.06985)
			(type default)
		)
		(layer "In5.Cu")
	)
	(gr_line
		(start 146.68246 -35.701224)
		(end 146.820128 -35.494722)
		(stroke
			(width 0.06985)
			(type default)
		)
		(layer "In5.Cu")
	)
	(gr_line
		(start 146.683476 -47.439072)
		(end 146.694906 -47.45609)
		(stroke
			(width 0.06985)
			(type default)
		)
		(layer "In5.Cu")
	)
	(gr_line
		(start 146.694906 -47.45609)
		(end 146.699478 -47.47641)
		(stroke
			(width 0.06985)
			(type default)
		)
		(layer "In5.Cu")
	)
	(gr_line
		(start 146.764502 -36.112196)
		(end 146.971004 -36.249864)
		(stroke
			(width 0.06985)
			(type default)
		)
		(layer "In5.Cu")
	)
	(gr_line
		(start 146.783552 -33.665922)
		(end 146.79803 -33.68802)
		(stroke
			(width 0.06985)
			(type default)
		)
		(layer "In5.Cu")
	)
	(gr_line
		(start 146.79803 -33.68802)
		(end 146.80311 -33.71342)
		(stroke
			(width 0.06985)
			(type default)
		)
		(layer "In5.Cu")
	)
	(gr_line
		(start 146.916394 -36.871656)
		(end 146.99869 -37.282628)
		(stroke
			(width 0.06985)
			(type default)
		)
		(layer "In5.Cu")
	)
	(gr_line
		(start 146.916394 -36.871656)
		(end 147.054316 -36.665408)
		(stroke
			(width 0.06985)
			(type default)
		)
		(layer "In5.Cu")
	)
	(gr_line
		(start 146.919442 -34.294064)
		(end 147.056602 -34.97961)
		(stroke
			(width 0.06985)
			(type default)
		)
		(layer "In5.Cu")
	)
	(gr_line
		(start 146.99869 -37.282628)
		(end 147.205192 -37.420296)
		(stroke
			(width 0.06985)
			(type default)
		)
		(layer "In5.Cu")
	)
	(gr_line
		(start 147.150582 -38.042342)
		(end 147.232878 -38.453314)
		(stroke
			(width 0.06985)
			(type default)
		)
		(layer "In5.Cu")
	)
	(gr_line
		(start 147.150582 -38.042342)
		(end 147.28825 -37.835586)
		(stroke
			(width 0.06985)
			(type default)
		)
		(layer "In5.Cu")
	)
	(gr_line
		(start 147.15363 -35.46475)
		(end 147.29079 -36.150296)
		(stroke
			(width 0.06985)
			(type default)
		)
		(layer "In5.Cu")
	)
	(gr_line
		(start 147.232878 -38.453314)
		(end 147.43938 -38.590982)
		(stroke
			(width 0.06985)
			(type default)
		)
		(layer "In5.Cu")
	)
	(gr_line
		(start 147.276566 -63.363348)
		(end 147.279614 -63.344806)
		(stroke
			(width 0.06985)
			(type default)
		)
		(layer "In5.Cu")
	)
	(gr_line
		(start 147.276566 -63.363348)
		(end 147.280122 -63.38189)
		(stroke
			(width 0.06985)
			(type default)
		)
		(layer "In5.Cu")
	)
	(gr_line
		(start 147.279614 -63.344552)
		(end 147.279614 -63.344806)
		(stroke
			(width 0.06985)
			(type default)
		)
		(layer "In5.Cu")
	)
	(gr_line
		(start 147.387818 -36.635436)
		(end 147.52447 -37.319458)
		(stroke
			(width 0.06985)
			(type default)
		)
		(layer "In5.Cu")
	)
	(gr_line
		(start 147.574762 -34.64306)
		(end 147.657058 -35.054032)
		(stroke
			(width 0.06985)
			(type default)
		)
		(layer "In5.Cu")
	)
	(gr_line
		(start 147.574762 -34.64306)
		(end 147.712684 -34.436558)
		(stroke
			(width 0.06985)
			(type default)
		)
		(layer "In5.Cu")
	)
	(gr_line
		(start 147.621498 -37.805106)
		(end 147.75815 -38.488366)
		(stroke
			(width 0.06985)
			(type default)
		)
		(layer "In5.Cu")
	)
	(gr_line
		(start 147.657058 -35.054032)
		(end 147.86356 -35.1917)
		(stroke
			(width 0.06985)
			(type default)
		)
		(layer "In5.Cu")
	)
	(gr_line
		(start 147.80895 -35.813492)
		(end 147.891246 -36.224464)
		(stroke
			(width 0.06985)
			(type default)
		)
		(layer "In5.Cu")
	)
	(gr_line
		(start 147.80895 -35.813492)
		(end 147.946618 -35.60699)
		(stroke
			(width 0.06985)
			(type default)
		)
		(layer "In5.Cu")
	)
	(gr_line
		(start 147.891246 -36.224464)
		(end 148.097748 -36.361878)
		(stroke
			(width 0.06985)
			(type default)
		)
		(layer "In5.Cu")
	)
	(gr_line
		(start 147.929092 -33.872932)
		(end 147.943316 -33.89376)
		(stroke
			(width 0.06985)
			(type default)
		)
		(layer "In5.Cu")
	)
	(gr_line
		(start 147.943316 -33.89376)
		(end 147.948396 -33.91916)
		(stroke
			(width 0.06985)
			(type default)
		)
		(layer "In5.Cu")
	)
	(gr_line
		(start 148.043138 -36.984178)
		(end 148.125434 -37.39515)
		(stroke
			(width 0.06985)
			(type default)
		)
		(layer "In5.Cu")
	)
	(gr_line
		(start 148.043138 -36.984178)
		(end 148.180806 -36.777676)
		(stroke
			(width 0.06985)
			(type default)
		)
		(layer "In5.Cu")
	)
	(gr_line
		(start 148.046186 -34.409126)
		(end 148.18233 -35.089338)
		(stroke
			(width 0.06985)
			(type default)
		)
		(layer "In5.Cu")
	)
	(gr_line
		(start 148.125434 -37.39515)
		(end 148.331682 -37.532818)
		(stroke
			(width 0.06985)
			(type default)
		)
		(layer "In5.Cu")
	)
	(gr_line
		(start 148.277326 -38.154864)
		(end 148.359368 -38.565836)
		(stroke
			(width 0.06985)
			(type default)
		)
		(layer "In5.Cu")
	)
	(gr_line
		(start 148.277326 -38.154864)
		(end 148.414994 -37.948362)
		(stroke
			(width 0.06985)
			(type default)
		)
		(layer "In5.Cu")
	)
	(gr_line
		(start 148.28012 -35.577018)
		(end 148.416518 -36.259516)
		(stroke
			(width 0.06985)
			(type default)
		)
		(layer "In5.Cu")
	)
	(gr_line
		(start 148.359368 -38.565836)
		(end 148.56587 -38.703504)
		(stroke
			(width 0.06985)
			(type default)
		)
		(layer "In5.Cu")
	)
	(gr_line
		(start 148.514308 -36.748974)
		(end 148.650706 -37.430964)
		(stroke
			(width 0.06985)
			(type default)
		)
		(layer "In5.Cu")
	)
	(gr_line
		(start 148.716746 -34.840672)
		(end 148.799042 -35.251644)
		(stroke
			(width 0.06985)
			(type default)
		)
		(layer "In5.Cu")
	)
	(gr_line
		(start 148.716746 -34.840672)
		(end 148.854414 -34.63417)
		(stroke
			(width 0.06985)
			(type default)
		)
		(layer "In5.Cu")
	)
	(gr_line
		(start 148.72081 -56.629046)
		(end 148.72589 -56.652414)
		(stroke
			(width 0.06985)
			(type default)
		)
		(layer "In5.Cu")
	)
	(gr_line
		(start 148.72208 -56.675782)
		(end 148.72589 -56.652414)
		(stroke
			(width 0.06985)
			(type default)
		)
		(layer "In5.Cu")
	)
	(gr_line
		(start 148.748496 -37.920422)
		(end 148.884894 -38.601904)
		(stroke
			(width 0.06985)
			(type default)
		)
		(layer "In5.Cu")
	)
	(gr_line
		(start 148.799042 -35.251644)
		(end 149.005544 -35.389312)
		(stroke
			(width 0.06985)
			(type default)
		)
		(layer "In5.Cu")
	)
	(gr_line
		(start 148.950934 -36.011104)
		(end 149.03323 -36.422076)
		(stroke
			(width 0.06985)
			(type default)
		)
		(layer "In5.Cu")
	)
	(gr_line
		(start 148.950934 -36.011104)
		(end 149.088602 -35.804602)
		(stroke
			(width 0.06985)
			(type default)
		)
		(layer "In5.Cu")
	)
	(gr_line
		(start 148.952458 -63.609982)
		(end 148.957538 -63.63462)
		(stroke
			(width 0.06985)
			(type default)
		)
		(layer "In5.Cu")
	)
	(gr_line
		(start 148.952458 -63.609982)
		(end 148.957538 -63.584836)
		(stroke
			(width 0.06985)
			(type default)
		)
		(layer "In5.Cu")
	)
	(gr_line
		(start 149.03323 -36.422076)
		(end 149.239478 -36.55949)
		(stroke
			(width 0.06985)
			(type default)
		)
		(layer "In5.Cu")
	)
	(gr_line
		(start 149.071076 -34.070544)
		(end 149.0853 -34.091372)
		(stroke
			(width 0.06985)
			(type default)
		)
		(layer "In5.Cu")
	)
	(gr_line
		(start 149.074124 -53.263546)
		(end 149.15388 -53.675026)
		(stroke
			(width 0.06985)
			(type default)
		)
		(layer "In5.Cu")
	)
	(gr_line
		(start 149.074124 -53.263546)
		(end 149.212808 -53.057806)
		(stroke
			(width 0.06985)
			(type default)
		)
		(layer "In5.Cu")
	)
	(gr_line
		(start 149.0853 -34.091372)
		(end 149.09038 -34.116772)
		(stroke
			(width 0.06985)
			(type default)
		)
		(layer "In5.Cu")
	)
	(gr_line
		(start 149.15388 -53.675026)
		(end 149.35962 -53.81371)
		(stroke
			(width 0.06985)
			(type default)
		)
		(layer "In5.Cu")
	)
	(gr_line
		(start 149.185122 -37.18179)
		(end 149.267418 -37.592762)
		(stroke
			(width 0.06985)
			(type default)
		)
		(layer "In5.Cu")
	)
	(gr_line
		(start 149.185122 -37.18179)
		(end 149.32279 -36.975288)
		(stroke
			(width 0.06985)
			(type default)
		)
		(layer "In5.Cu")
	)
	(gr_line
		(start 149.18817 -34.606738)
		(end 149.324314 -35.28695)
		(stroke
			(width 0.06985)
			(type default)
		)
		(layer "In5.Cu")
	)
	(gr_line
		(start 149.267418 -37.592762)
		(end 149.473666 -37.73043)
		(stroke
			(width 0.06985)
			(type default)
		)
		(layer "In5.Cu")
	)
	(gr_line
		(start 149.301708 -54.435502)
		(end 149.381718 -54.846728)
		(stroke
			(width 0.06985)
			(type default)
		)
		(layer "In5.Cu")
	)
	(gr_line
		(start 149.301708 -54.435502)
		(end 149.440646 -54.229762)
		(stroke
			(width 0.06985)
			(type default)
		)
		(layer "In5.Cu")
	)
	(gr_line
		(start 149.381718 -54.846728)
		(end 149.587458 -54.985666)
		(stroke
			(width 0.06985)
			(type default)
		)
		(layer "In5.Cu")
	)
	(gr_line
		(start 149.41931 -38.352476)
		(end 149.501352 -38.763448)
		(stroke
			(width 0.06985)
			(type default)
		)
		(layer "In5.Cu")
	)
	(gr_line
		(start 149.41931 -38.352476)
		(end 149.556978 -38.145974)
		(stroke
			(width 0.06985)
			(type default)
		)
		(layer "In5.Cu")
	)
	(gr_line
		(start 149.422104 -35.77463)
		(end 149.558502 -36.457128)
		(stroke
			(width 0.06985)
			(type default)
		)
		(layer "In5.Cu")
	)
	(gr_line
		(start 149.501352 -38.763448)
		(end 149.707854 -38.901116)
		(stroke
			(width 0.06985)
			(type default)
		)
		(layer "In5.Cu")
	)
	(gr_line
		(start 149.529546 -55.607204)
		(end 149.609556 -56.018684)
		(stroke
			(width 0.06985)
			(type default)
		)
		(layer "In5.Cu")
	)
	(gr_line
		(start 149.529546 -55.607204)
		(end 149.66823 -55.401718)
		(stroke
			(width 0.06985)
			(type default)
		)
		(layer "In5.Cu")
	)
	(gr_line
		(start 149.546564 -53.031898)
		(end 149.678644 -53.711602)
		(stroke
			(width 0.06985)
			(type default)
		)
		(layer "In5.Cu")
	)
	(gr_line
		(start 149.609556 -56.018684)
		(end 149.815296 -56.157622)
		(stroke
			(width 0.06985)
			(type default)
		)
		(layer "In5.Cu")
	)
	(gr_line
		(start 149.656292 -36.945062)
		(end 149.793198 -37.6301)
		(stroke
			(width 0.06985)
			(type default)
		)
		(layer "In5.Cu")
	)
	(gr_line
		(start 149.73427 -34.816288)
		(end 149.816312 -35.22726)
		(stroke
			(width 0.06985)
			(type default)
		)
		(layer "In5.Cu")
	)
	(gr_line
		(start 149.73427 -34.816288)
		(end 149.871938 -34.609786)
		(stroke
			(width 0.06985)
			(type default)
		)
		(layer "In5.Cu")
	)
	(gr_line
		(start 149.757384 -56.77916)
		(end 149.83714 -57.19064)
		(stroke
			(width 0.06985)
			(type default)
		)
		(layer "In5.Cu")
	)
	(gr_line
		(start 149.757384 -56.77916)
		(end 149.896068 -56.573166)
		(stroke
			(width 0.06985)
			(type default)
		)
		(layer "In5.Cu")
	)
	(gr_line
		(start 149.77237 -76.262738)
		(end 149.778466 -76.29398)
		(stroke
			(width 0.06985)
			(type default)
		)
		(layer "In5.Cu")
	)
	(gr_line
		(start 149.774402 -54.204108)
		(end 149.906482 -54.883812)
		(stroke
			(width 0.06985)
			(type default)
		)
		(layer "In5.Cu")
	)
	(gr_line
		(start 149.778466 -76.29398)
		(end 149.797008 -76.319888)
		(stroke
			(width 0.06985)
			(type default)
		)
		(layer "In5.Cu")
	)
	(gr_line
		(start 149.816312 -35.22726)
		(end 150.022814 -35.364928)
		(stroke
			(width 0.06985)
			(type default)
		)
		(layer "In5.Cu")
	)
	(gr_line
		(start 149.83714 -57.19064)
		(end 150.04288 -57.329324)
		(stroke
			(width 0.06985)
			(type default)
		)
		(layer "In5.Cu")
	)
	(gr_line
		(start 149.878542 -51.680364)
		(end 149.960838 -52.091082)
		(stroke
			(width 0.06985)
			(type default)
		)
		(layer "In5.Cu")
	)
	(gr_line
		(start 149.878542 -51.680364)
		(end 150.01621 -51.473862)
		(stroke
			(width 0.06985)
			(type default)
		)
		(layer "In5.Cu")
	)
	(gr_line
		(start 149.89048 -38.116256)
		(end 150.027132 -38.79977)
		(stroke
			(width 0.06985)
			(type default)
		)
		(layer "In5.Cu")
	)
	(gr_line
		(start 149.939756 -63.325248)
		(end 149.944836 -63.350394)
		(stroke
			(width 0.06985)
			(type default)
		)
		(layer "In5.Cu")
	)
	(gr_line
		(start 149.939756 -63.325248)
		(end 149.944836 -63.30061)
		(stroke
			(width 0.06985)
			(type default)
		)
		(layer "In5.Cu")
	)
	(gr_line
		(start 149.960838 -52.091082)
		(end 150.167086 -52.22875)
		(stroke
			(width 0.06985)
			(type default)
		)
		(layer "In5.Cu")
	)
	(gr_line
		(start 149.968204 -35.98672)
		(end 150.0505 -36.397692)
		(stroke
			(width 0.06985)
			(type default)
		)
		(layer "In5.Cu")
	)
	(gr_line
		(start 149.968204 -35.98672)
		(end 150.105872 -35.780472)
		(stroke
			(width 0.06985)
			(type default)
		)
		(layer "In5.Cu")
	)
	(gr_line
		(start 150.00224 -55.376318)
		(end 150.134574 -56.057292)
		(stroke
			(width 0.06985)
			(type default)
		)
		(layer "In5.Cu")
	)
	(gr_line
		(start 150.0505 -36.397692)
		(end 150.257002 -36.53536)
		(stroke
			(width 0.06985)
			(type default)
		)
		(layer "In5.Cu")
	)
	(gr_line
		(start 150.088346 -34.04616)
		(end 150.10257 -34.066988)
		(stroke
			(width 0.06985)
			(type default)
		)
		(layer "In5.Cu")
	)
	(gr_line
		(start 150.10257 -34.066988)
		(end 150.10765 -34.092388)
		(stroke
			(width 0.06985)
			(type default)
		)
		(layer "In5.Cu")
	)
	(gr_line
		(start 150.11273 -52.850796)
		(end 150.195026 -53.261768)
		(stroke
			(width 0.06985)
			(type default)
		)
		(layer "In5.Cu")
	)
	(gr_line
		(start 150.11273 -52.850796)
		(end 150.250398 -52.644548)
		(stroke
			(width 0.06985)
			(type default)
		)
		(layer "In5.Cu")
	)
	(gr_line
		(start 150.170134 -52.230782)
		(end 150.175976 -52.260246)
		(stroke
			(width 0.06985)
			(type default)
		)
		(layer "In5.Cu")
	)
	(gr_line
		(start 150.195026 -53.261768)
		(end 150.401274 -53.399436)
		(stroke
			(width 0.06985)
			(type default)
		)
		(layer "In5.Cu")
	)
	(gr_line
		(start 150.202392 -37.157406)
		(end 150.284688 -37.568378)
		(stroke
			(width 0.06985)
			(type default)
		)
		(layer "In5.Cu")
	)
	(gr_line
		(start 150.202392 -37.157406)
		(end 150.34006 -36.95065)
		(stroke
			(width 0.06985)
			(type default)
		)
		(layer "In5.Cu")
	)
	(gr_line
		(start 150.20544 -34.581592)
		(end 150.341838 -35.263074)
		(stroke
			(width 0.06985)
			(type default)
		)
		(layer "In5.Cu")
	)
	(gr_line
		(start 150.229824 -56.54675)
		(end 150.362412 -57.228994)
		(stroke
			(width 0.06985)
			(type default)
		)
		(layer "In5.Cu")
	)
	(gr_line
		(start 150.284688 -37.568378)
		(end 150.49119 -37.706046)
		(stroke
			(width 0.06985)
			(type default)
		)
		(layer "In5.Cu")
	)
	(gr_line
		(start 150.346918 -54.021482)
		(end 150.429214 -54.432454)
		(stroke
			(width 0.06985)
			(type default)
		)
		(layer "In5.Cu")
	)
	(gr_line
		(start 150.346918 -54.021482)
		(end 150.484332 -53.81498)
		(stroke
			(width 0.06985)
			(type default)
		)
		(layer "In5.Cu")
	)
	(gr_line
		(start 150.349712 -51.44516)
		(end 150.485856 -52.125626)
		(stroke
			(width 0.06985)
			(type default)
		)
		(layer "In5.Cu")
	)
	(gr_line
		(start 150.429214 -54.432454)
		(end 150.635462 -54.570122)
		(stroke
			(width 0.06985)
			(type default)
		)
		(layer "In5.Cu")
	)
	(gr_line
		(start 150.43658 -38.328092)
		(end 150.518876 -38.739064)
		(stroke
			(width 0.06985)
			(type default)
		)
		(layer "In5.Cu")
	)
	(gr_line
		(start 150.43658 -38.328092)
		(end 150.574248 -38.121336)
		(stroke
			(width 0.06985)
			(type default)
		)
		(layer "In5.Cu")
	)
	(gr_line
		(start 150.439628 -35.752532)
		(end 150.575772 -36.432744)
		(stroke
			(width 0.06985)
			(type default)
		)
		(layer "In5.Cu")
	)
	(gr_line
		(start 150.457408 -57.769252)
		(end 150.462488 -57.743598)
		(stroke
			(width 0.06985)
			(type default)
		)
		(layer "In5.Cu")
	)
	(gr_line
		(start 150.457408 -57.71769)
		(end 150.462488 -57.743598)
		(stroke
			(width 0.06985)
			(type default)
		)
		(layer "In5.Cu")
	)
	(gr_line
		(start 150.493476 -52.163472)
		(end 150.494492 -52.168806)
		(stroke
			(width 0.06985)
			(type default)
		)
		(layer "In5.Cu")
	)
	(gr_line
		(start 150.518876 -38.739064)
		(end 150.725378 -38.876478)
		(stroke
			(width 0.06985)
			(type default)
		)
		(layer "In5.Cu")
	)
	(gr_line
		(start 150.581106 -55.192168)
		(end 150.663148 -55.60314)
		(stroke
			(width 0.06985)
			(type default)
		)
		(layer "In5.Cu")
	)
	(gr_line
		(start 150.581106 -55.192168)
		(end 150.71852 -54.98592)
		(stroke
			(width 0.06985)
			(type default)
		)
		(layer "In5.Cu")
	)
	(gr_line
		(start 150.584154 -52.617878)
		(end 150.720044 -53.296566)
		(stroke
			(width 0.06985)
			(type default)
		)
		(layer "In5.Cu")
	)
	(gr_line
		(start 150.663148 -55.60314)
		(end 150.86965 -55.740554)
		(stroke
			(width 0.06985)
			(type default)
		)
		(layer "In5.Cu")
	)
	(gr_line
		(start 150.673562 -36.920678)
		(end 150.80996 -37.603176)
		(stroke
			(width 0.06985)
			(type default)
		)
		(layer "In5.Cu")
	)
	(gr_line
		(start 150.73503 -34.64433)
		(end 150.817326 -35.055302)
		(stroke
			(width 0.06985)
			(type default)
		)
		(layer "In5.Cu")
	)
	(gr_line
		(start 150.73503 -34.64433)
		(end 150.872698 -34.437828)
		(stroke
			(width 0.06985)
			(type default)
		)
		(layer "In5.Cu")
	)
	(gr_line
		(start 150.817326 -35.055302)
		(end 151.023828 -35.19297)
		(stroke
			(width 0.06985)
			(type default)
		)
		(layer "In5.Cu")
	)
	(gr_line
		(start 150.818342 -53.788564)
		(end 150.954232 -54.467252)
		(stroke
			(width 0.06985)
			(type default)
		)
		(layer "In5.Cu")
	)
	(gr_line
		(start 150.83663 -63.415672)
		(end 150.84171 -63.440818)
		(stroke
			(width 0.06985)
			(type default)
		)
		(layer "In5.Cu")
	)
	(gr_line
		(start 150.83663 -63.415672)
		(end 150.84171 -63.391034)
		(stroke
			(width 0.06985)
			(type default)
		)
		(layer "In5.Cu")
	)
	(gr_line
		(start 150.90775 -38.091364)
		(end 151.044148 -38.773862)
		(stroke
			(width 0.06985)
			(type default)
		)
		(layer "In5.Cu")
	)
	(gr_line
		(start 150.969218 -35.814762)
		(end 151.051514 -36.225734)
		(stroke
			(width 0.06985)
			(type default)
		)
		(layer "In5.Cu")
	)
	(gr_line
		(start 150.969218 -35.814762)
		(end 151.106886 -35.60826)
		(stroke
			(width 0.06985)
			(type default)
		)
		(layer "In5.Cu")
	)
	(gr_line
		(start 151.051514 -36.225734)
		(end 151.257762 -36.363402)
		(stroke
			(width 0.06985)
			(type default)
		)
		(layer "In5.Cu")
	)
	(gr_line
		(start 151.05253 -54.95925)
		(end 151.18842 -55.637938)
		(stroke
			(width 0.06985)
			(type default)
		)
		(layer "In5.Cu")
	)
	(gr_line
		(start 151.08936 -33.874202)
		(end 151.103584 -33.89503)
		(stroke
			(width 0.06985)
			(type default)
		)
		(layer "In5.Cu")
	)
	(gr_line
		(start 151.097996 -52.257452)
		(end 151.180038 -52.668424)
		(stroke
			(width 0.06985)
			(type default)
		)
		(layer "In5.Cu")
	)
	(gr_line
		(start 151.097996 -52.257452)
		(end 151.23541 -52.051204)
		(stroke
			(width 0.06985)
			(type default)
		)
		(layer "In5.Cu")
	)
	(gr_line
		(start 151.103584 -33.89503)
		(end 151.108664 -33.92043)
		(stroke
			(width 0.06985)
			(type default)
		)
		(layer "In5.Cu")
	)
	(gr_line
		(start 151.180038 -52.668424)
		(end 151.38654 -52.805838)
		(stroke
			(width 0.06985)
			(type default)
		)
		(layer "In5.Cu")
	)
	(gr_line
		(start 151.203406 -36.985448)
		(end 151.285448 -37.39642)
		(stroke
			(width 0.06985)
			(type default)
		)
		(layer "In5.Cu")
	)
	(gr_line
		(start 151.203406 -36.985448)
		(end 151.341074 -36.778946)
		(stroke
			(width 0.06985)
			(type default)
		)
		(layer "In5.Cu")
	)
	(gr_line
		(start 151.206454 -34.409126)
		(end 151.343106 -35.091878)
		(stroke
			(width 0.06985)
			(type default)
		)
		(layer "In5.Cu")
	)
	(gr_line
		(start 151.285448 -37.39642)
		(end 151.49195 -37.534088)
		(stroke
			(width 0.06985)
			(type default)
		)
		(layer "In5.Cu")
	)
	(gr_line
		(start 151.33193 -53.428138)
		(end 151.414226 -53.83911)
		(stroke
			(width 0.06985)
			(type default)
		)
		(layer "In5.Cu")
	)
	(gr_line
		(start 151.33193 -53.428138)
		(end 151.469598 -53.22189)
		(stroke
			(width 0.06985)
			(type default)
		)
		(layer "In5.Cu")
	)
	(gr_line
		(start 151.371554 -75.714606)
		(end 151.376634 -75.740006)
		(stroke
			(width 0.06985)
			(type default)
		)
		(layer "In5.Cu")
	)
	(gr_line
		(start 151.376634 -75.740006)
		(end 151.391366 -75.76185)
		(stroke
			(width 0.06985)
			(type default)
		)
		(layer "In5.Cu")
	)
	(gr_line
		(start 151.414226 -53.83911)
		(end 151.620474 -53.976524)
		(stroke
			(width 0.06985)
			(type default)
		)
		(layer "In5.Cu")
	)
	(gr_line
		(start 151.43734 -38.156134)
		(end 151.519636 -38.567106)
		(stroke
			(width 0.06985)
			(type default)
		)
		(layer "In5.Cu")
	)
	(gr_line
		(start 151.43734 -38.156134)
		(end 151.575008 -37.949632)
		(stroke
			(width 0.06985)
			(type default)
		)
		(layer "In5.Cu")
	)
	(gr_line
		(start 151.440134 -35.57778)
		(end 151.577548 -36.263834)
		(stroke
			(width 0.06985)
			(type default)
		)
		(layer "In5.Cu")
	)
	(gr_line
		(start 151.49576 -57.225438)
		(end 151.50084 -57.200292)
		(stroke
			(width 0.06985)
			(type default)
		)
		(layer "In5.Cu")
	)
	(gr_line
		(start 151.496014 -57.176162)
		(end 151.50084 -57.200292)
		(stroke
			(width 0.06985)
			(type default)
		)
		(layer "In5.Cu")
	)
	(gr_line
		(start 151.519636 -38.567106)
		(end 151.726138 -38.704774)
		(stroke
			(width 0.06985)
			(type default)
		)
		(layer "In5.Cu")
	)
	(gr_line
		(start 151.566118 -54.59857)
		(end 151.648414 -55.009542)
		(stroke
			(width 0.06985)
			(type default)
		)
		(layer "In5.Cu")
	)
	(gr_line
		(start 151.566118 -54.59857)
		(end 151.703786 -54.392322)
		(stroke
			(width 0.06985)
			(type default)
		)
		(layer "In5.Cu")
	)
	(gr_line
		(start 151.569166 -52.020724)
		(end 151.706072 -52.705762)
		(stroke
			(width 0.06985)
			(type default)
		)
		(layer "In5.Cu")
	)
	(gr_line
		(start 151.648414 -55.009542)
		(end 151.854662 -55.146956)
		(stroke
			(width 0.06985)
			(type default)
		)
		(layer "In5.Cu")
	)
	(gr_line
		(start 151.674576 -36.749482)
		(end 151.811228 -37.432996)
		(stroke
			(width 0.06985)
			(type default)
		)
		(layer "In5.Cu")
	)
	(gr_line
		(start 151.705564 -63.437516)
		(end 151.710644 -63.462154)
		(stroke
			(width 0.06985)
			(type default)
		)
		(layer "In5.Cu")
	)
	(gr_line
		(start 151.705564 -63.437516)
		(end 151.710644 -63.41237)
		(stroke
			(width 0.06985)
			(type default)
		)
		(layer "In5.Cu")
	)
	(gr_line
		(start 151.75611 -34.71926)
		(end 151.838406 -35.130232)
		(stroke
			(width 0.06985)
			(type default)
		)
		(layer "In5.Cu")
	)
	(gr_line
		(start 151.75611 -34.71926)
		(end 151.893778 -34.512758)
		(stroke
			(width 0.06985)
			(type default)
		)
		(layer "In5.Cu")
	)
	(gr_line
		(start 151.800306 -55.769256)
		(end 151.882602 -56.180228)
		(stroke
			(width 0.06985)
			(type default)
		)
		(layer "In5.Cu")
	)
	(gr_line
		(start 151.800306 -55.769256)
		(end 151.93772 -55.562754)
		(stroke
			(width 0.06985)
			(type default)
		)
		(layer "In5.Cu")
	)
	(gr_line
		(start 151.803354 -53.192934)
		(end 151.939752 -53.874924)
		(stroke
			(width 0.06985)
			(type default)
		)
		(layer "In5.Cu")
	)
	(gr_line
		(start 151.838406 -35.130232)
		(end 152.044908 -35.2679)
		(stroke
			(width 0.06985)
			(type default)
		)
		(layer "In5.Cu")
	)
	(gr_line
		(start 151.85771 -55.148988)
		(end 151.8793 -55.2577)
		(stroke
			(width 0.06985)
			(type default)
		)
		(layer "In5.Cu")
	)
	(gr_line
		(start 151.882602 -56.180228)
		(end 152.08885 -56.317896)
		(stroke
			(width 0.06985)
			(type default)
		)
		(layer "In5.Cu")
	)
	(gr_line
		(start 151.908764 -37.920676)
		(end 152.045162 -38.602666)
		(stroke
			(width 0.06985)
			(type default)
		)
		(layer "In5.Cu")
	)
	(gr_line
		(start 151.990298 -35.889692)
		(end 152.072594 -36.300664)
		(stroke
			(width 0.06985)
			(type default)
		)
		(layer "In5.Cu")
	)
	(gr_line
		(start 151.990298 -35.889692)
		(end 152.127966 -35.683444)
		(stroke
			(width 0.06985)
			(type default)
		)
		(layer "In5.Cu")
	)
	(gr_line
		(start 152.037288 -54.362858)
		(end 152.173432 -55.043832)
		(stroke
			(width 0.06985)
			(type default)
		)
		(layer "In5.Cu")
	)
	(gr_line
		(start 152.072594 -36.300664)
		(end 152.278842 -36.438332)
		(stroke
			(width 0.06985)
			(type default)
		)
		(layer "In5.Cu")
	)
	(gr_line
		(start 152.085548 -51.68392)
		(end 152.16759 -52.094892)
		(stroke
			(width 0.06985)
			(type default)
		)
		(layer "In5.Cu")
	)
	(gr_line
		(start 152.085548 -51.68392)
		(end 152.222962 -51.477418)
		(stroke
			(width 0.06985)
			(type default)
		)
		(layer "In5.Cu")
	)
	(gr_line
		(start 152.11044 -33.949132)
		(end 152.124664 -33.96996)
		(stroke
			(width 0.06985)
			(type default)
		)
		(layer "In5.Cu")
	)
	(gr_line
		(start 152.124664 -33.96996)
		(end 152.129744 -33.99536)
		(stroke
			(width 0.06985)
			(type default)
		)
		(layer "In5.Cu")
	)
	(gr_line
		(start 152.16759 -52.094892)
		(end 152.374092 -52.23256)
		(stroke
			(width 0.06985)
			(type default)
		)
		(layer "In5.Cu")
	)
	(gr_line
		(start 152.180544 -55.079138)
		(end 152.20315 -55.19293)
		(stroke
			(width 0.06985)
			(type default)
		)
		(layer "In5.Cu")
	)
	(gr_line
		(start 152.224486 -37.060378)
		(end 152.306528 -37.47135)
		(stroke
			(width 0.06985)
			(type default)
		)
		(layer "In5.Cu")
	)
	(gr_line
		(start 152.224486 -37.060378)
		(end 152.362154 -36.853876)
		(stroke
			(width 0.06985)
			(type default)
		)
		(layer "In5.Cu")
	)
	(gr_line
		(start 152.227534 -34.484818)
		(end 152.363678 -35.16503)
		(stroke
			(width 0.06985)
			(type default)
		)
		(layer "In5.Cu")
	)
	(gr_line
		(start 152.271476 -55.535322)
		(end 152.40762 -56.21528)
		(stroke
			(width 0.06985)
			(type default)
		)
		(layer "In5.Cu")
	)
	(gr_line
		(start 152.306528 -37.47135)
		(end 152.51303 -37.609018)
		(stroke
			(width 0.06985)
			(type default)
		)
		(layer "In5.Cu")
	)
	(gr_line
		(start 152.319736 -52.854606)
		(end 152.401778 -53.265324)
		(stroke
			(width 0.06985)
			(type default)
		)
		(layer "In5.Cu")
	)
	(gr_line
		(start 152.319736 -52.854606)
		(end 152.45715 -52.648358)
		(stroke
			(width 0.06985)
			(type default)
		)
		(layer "In5.Cu")
	)
	(gr_line
		(start 152.356058 -75.401932)
		(end 152.361138 -75.427332)
		(stroke
			(width 0.06985)
			(type default)
		)
		(layer "In5.Cu")
	)
	(gr_line
		(start 152.361138 -75.427332)
		(end 152.375362 -75.44816)
		(stroke
			(width 0.06985)
			(type default)
		)
		(layer "In5.Cu")
	)
	(gr_line
		(start 152.401778 -53.265324)
		(end 152.60828 -53.402992)
		(stroke
			(width 0.06985)
			(type default)
		)
		(layer "In5.Cu")
	)
	(gr_line
		(start 152.45842 -38.231064)
		(end 152.540716 -38.642036)
		(stroke
			(width 0.06985)
			(type default)
		)
		(layer "In5.Cu")
	)
	(gr_line
		(start 152.45842 -38.231064)
		(end 152.596088 -38.024816)
		(stroke
			(width 0.06985)
			(type default)
		)
		(layer "In5.Cu")
	)
	(gr_line
		(start 152.461468 -35.655504)
		(end 152.597358 -36.334954)
		(stroke
			(width 0.06985)
			(type default)
		)
		(layer "In5.Cu")
	)
	(gr_line
		(start 152.505664 -56.755284)
		(end 152.510744 -56.730646)
		(stroke
			(width 0.06985)
			(type default)
		)
		(layer "In5.Cu")
	)
	(gr_line
		(start 152.505664 -56.7055)
		(end 152.510744 -56.730646)
		(stroke
			(width 0.06985)
			(type default)
		)
		(layer "In5.Cu")
	)
	(gr_line
		(start 152.540716 -38.642036)
		(end 152.747218 -38.77945)
		(stroke
			(width 0.06985)
			(type default)
		)
		(layer "In5.Cu")
	)
	(gr_line
		(start 152.55367 -54.025038)
		(end 152.635966 -54.43601)
		(stroke
			(width 0.06985)
			(type default)
		)
		(layer "In5.Cu")
	)
	(gr_line
		(start 152.55367 -54.025038)
		(end 152.691338 -53.81879)
		(stroke
			(width 0.06985)
			(type default)
		)
		(layer "In5.Cu")
	)
	(gr_line
		(start 152.556718 -51.447954)
		(end 152.69337 -52.131468)
		(stroke
			(width 0.06985)
			(type default)
		)
		(layer "In5.Cu")
	)
	(gr_line
		(start 152.615646 -63.280544)
		(end 152.620726 -63.30569)
		(stroke
			(width 0.06985)
			(type default)
		)
		(layer "In5.Cu")
	)
	(gr_line
		(start 152.615646 -63.280544)
		(end 152.620726 -63.255906)
		(stroke
			(width 0.06985)
			(type default)
		)
		(layer "In5.Cu")
	)
	(gr_line
		(start 152.635966 -54.43601)
		(end 152.842214 -54.573424)
		(stroke
			(width 0.06985)
			(type default)
		)
		(layer "In5.Cu")
	)
	(gr_line
		(start 152.69591 -36.827968)
		(end 152.831292 -37.504878)
		(stroke
			(width 0.06985)
			(type default)
		)
		(layer "In5.Cu")
	)
	(gr_line
		(start 152.756108 -34.776918)
		(end 152.838404 -35.18789)
		(stroke
			(width 0.06985)
			(type default)
		)
		(layer "In5.Cu")
	)
	(gr_line
		(start 152.756108 -34.776918)
		(end 152.89403 -34.570416)
		(stroke
			(width 0.06985)
			(type default)
		)
		(layer "In5.Cu")
	)
	(gr_line
		(start 152.787858 -55.195724)
		(end 152.870154 -55.606696)
		(stroke
			(width 0.06985)
			(type default)
		)
		(layer "In5.Cu")
	)
	(gr_line
		(start 152.787858 -55.195724)
		(end 152.925526 -54.989222)
		(stroke
			(width 0.06985)
			(type default)
		)
		(layer "In5.Cu")
	)
	(gr_line
		(start 152.790906 -52.619402)
		(end 152.927304 -53.301392)
		(stroke
			(width 0.06985)
			(type default)
		)
		(layer "In5.Cu")
	)
	(gr_line
		(start 152.838404 -35.18789)
		(end 153.044906 -35.325558)
		(stroke
			(width 0.06985)
			(type default)
		)
		(layer "In5.Cu")
	)
	(gr_line
		(start 152.845262 -54.575456)
		(end 152.859232 -54.64556)
		(stroke
			(width 0.06985)
			(type default)
		)
		(layer "In5.Cu")
	)
	(gr_line
		(start 152.870154 -55.606696)
		(end 153.076402 -55.744364)
		(stroke
			(width 0.06985)
			(type default)
		)
		(layer "In5.Cu")
	)
	(gr_line
		(start 152.930098 -37.9984)
		(end 153.065734 -38.676072)
		(stroke
			(width 0.06985)
			(type default)
		)
		(layer "In5.Cu")
	)
	(gr_line
		(start 152.990296 -35.94735)
		(end 153.072592 -36.358322)
		(stroke
			(width 0.06985)
			(type default)
		)
		(layer "In5.Cu")
	)
	(gr_line
		(start 152.990296 -35.94735)
		(end 153.127964 -35.740848)
		(stroke
			(width 0.06985)
			(type default)
		)
		(layer "In5.Cu")
	)
	(gr_line
		(start 153.02484 -53.789326)
		(end 153.160984 -54.4703)
		(stroke
			(width 0.06985)
			(type default)
		)
		(layer "In5.Cu")
	)
	(gr_line
		(start 153.03627 -51.324002)
		(end 153.118566 -51.734974)
		(stroke
			(width 0.06985)
			(type default)
		)
		(layer "In5.Cu")
	)
	(gr_line
		(start 153.03627 -51.324002)
		(end 153.173938 -51.1175)
		(stroke
			(width 0.06985)
			(type default)
		)
		(layer "In5.Cu")
	)
	(gr_line
		(start 153.072592 -36.358322)
		(end 153.279094 -36.495736)
		(stroke
			(width 0.06985)
			(type default)
		)
		(layer "In5.Cu")
	)
	(gr_line
		(start 153.110438 -34.00679)
		(end 153.124662 -34.027618)
		(stroke
			(width 0.06985)
			(type default)
		)
		(layer "In5.Cu")
	)
	(gr_line
		(start 153.118566 -51.734974)
		(end 153.324814 -51.872388)
		(stroke
			(width 0.06985)
			(type default)
		)
		(layer "In5.Cu")
	)
	(gr_line
		(start 153.124662 -34.027618)
		(end 153.129742 -34.053018)
		(stroke
			(width 0.06985)
			(type default)
		)
		(layer "In5.Cu")
	)
	(gr_line
		(start 153.137108 -74.912982)
		(end 153.142188 -74.938382)
		(stroke
			(width 0.06985)
			(type default)
		)
		(layer "In5.Cu")
	)
	(gr_line
		(start 153.142188 -74.938382)
		(end 153.156666 -74.960226)
		(stroke
			(width 0.06985)
			(type default)
		)
		(layer "In5.Cu")
	)
	(gr_line
		(start 153.16835 -54.506622)
		(end 153.183082 -54.58079)
		(stroke
			(width 0.06985)
			(type default)
		)
		(layer "In5.Cu")
	)
	(gr_line
		(start 153.224484 -37.118036)
		(end 153.30678 -37.529008)
		(stroke
			(width 0.06985)
			(type default)
		)
		(layer "In5.Cu")
	)
	(gr_line
		(start 153.224484 -37.118036)
		(end 153.362152 -36.911534)
		(stroke
			(width 0.06985)
			(type default)
		)
		(layer "In5.Cu")
	)
	(gr_line
		(start 153.227532 -34.542476)
		(end 153.363676 -35.222942)
		(stroke
			(width 0.06985)
			(type default)
		)
		(layer "In5.Cu")
	)
	(gr_line
		(start 153.259028 -54.96179)
		(end 153.395172 -55.641748)
		(stroke
			(width 0.06985)
			(type default)
		)
		(layer "In5.Cu")
	)
	(gr_line
		(start 153.270458 -52.494688)
		(end 153.352754 -52.90566)
		(stroke
			(width 0.06985)
			(type default)
		)
		(layer "In5.Cu")
	)
	(gr_line
		(start 153.270458 -52.494688)
		(end 153.408126 -52.288186)
		(stroke
			(width 0.06985)
			(type default)
		)
		(layer "In5.Cu")
	)
	(gr_line
		(start 153.30678 -37.529008)
		(end 153.513028 -37.666676)
		(stroke
			(width 0.06985)
			(type default)
		)
		(layer "In5.Cu")
	)
	(gr_line
		(start 153.327862 -51.87442)
		(end 153.330656 -51.88839)
		(stroke
			(width 0.06985)
			(type default)
		)
		(layer "In5.Cu")
	)
	(gr_line
		(start 153.352754 -52.90566)
		(end 153.559002 -53.043074)
		(stroke
			(width 0.06985)
			(type default)
		)
		(layer "In5.Cu")
	)
	(gr_line
		(start 153.458672 -38.288722)
		(end 153.540714 -38.699694)
		(stroke
			(width 0.06985)
			(type default)
		)
		(layer "In5.Cu")
	)
	(gr_line
		(start 153.458672 -38.288722)
		(end 153.59634 -38.08222)
		(stroke
			(width 0.06985)
			(type default)
		)
		(layer "In5.Cu")
	)
	(gr_line
		(start 153.461466 -35.7124)
		(end 153.597356 -36.39185)
		(stroke
			(width 0.06985)
			(type default)
		)
		(layer "In5.Cu")
	)
	(gr_line
		(start 153.493216 -56.181752)
		(end 153.498296 -56.157114)
		(stroke
			(width 0.06985)
			(type default)
		)
		(layer "In5.Cu")
	)
	(gr_line
		(start 153.493216 -56.131968)
		(end 153.498296 -56.157114)
		(stroke
			(width 0.06985)
			(type default)
		)
		(layer "In5.Cu")
	)
	(gr_line
		(start 153.504646 -53.66512)
		(end 153.586942 -54.076092)
		(stroke
			(width 0.06985)
			(type default)
		)
		(layer "In5.Cu")
	)
	(gr_line
		(start 153.504646 -53.66512)
		(end 153.642314 -53.458872)
		(stroke
			(width 0.06985)
			(type default)
		)
		(layer "In5.Cu")
	)
	(gr_line
		(start 153.507694 -51.09083)
		(end 153.643076 -51.76774)
		(stroke
			(width 0.06985)
			(type default)
		)
		(layer "In5.Cu")
	)
	(gr_line
		(start 153.540714 -38.699694)
		(end 153.747216 -38.837362)
		(stroke
			(width 0.06985)
			(type default)
		)
		(layer "In5.Cu")
	)
	(gr_line
		(start 153.54427 -63.16091)
		(end 153.54935 -63.186056)
		(stroke
			(width 0.06985)
			(type default)
		)
		(layer "In5.Cu")
	)
	(gr_line
		(start 153.54427 -63.16091)
		(end 153.54935 -63.136272)
		(stroke
			(width 0.06985)
			(type default)
		)
		(layer "In5.Cu")
	)
	(gr_line
		(start 153.56205 -53.045106)
		(end 153.572464 -53.097176)
		(stroke
			(width 0.06985)
			(type default)
		)
		(layer "In5.Cu")
	)
	(gr_line
		(start 153.586942 -54.076092)
		(end 153.79319 -54.21376)
		(stroke
			(width 0.06985)
			(type default)
		)
		(layer "In5.Cu")
	)
	(gr_line
		(start 153.695654 -36.882832)
		(end 153.832052 -37.564822)
		(stroke
			(width 0.06985)
			(type default)
		)
		(layer "In5.Cu")
	)
	(gr_line
		(start 153.738834 -54.835806)
		(end 153.82113 -55.246778)
		(stroke
			(width 0.06985)
			(type default)
		)
		(layer "In5.Cu")
	)
	(gr_line
		(start 153.738834 -54.835806)
		(end 153.876248 -54.629304)
		(stroke
			(width 0.06985)
			(type default)
		)
		(layer "In5.Cu")
	)
	(gr_line
		(start 153.741882 -52.261516)
		(end 153.877264 -52.938426)
		(stroke
			(width 0.06985)
			(type default)
		)
		(layer "In5.Cu")
	)
	(gr_line
		(start 153.82113 -55.246778)
		(end 154.027378 -55.384446)
		(stroke
			(width 0.06985)
			(type default)
		)
		(layer "In5.Cu")
	)
	(gr_line
		(start 153.853388 -74.179938)
		(end 153.858468 -74.205084)
		(stroke
			(width 0.06985)
			(type default)
		)
		(layer "In5.Cu")
	)
	(gr_line
		(start 153.858468 -74.205084)
		(end 153.872184 -74.22515)
		(stroke
			(width 0.06985)
			(type default)
		)
		(layer "In5.Cu")
	)
	(gr_line
		(start 153.885138 -52.97678)
		(end 153.896314 -53.032406)
		(stroke
			(width 0.06985)
			(type default)
		)
		(layer "In5.Cu")
	)
	(gr_line
		(start 153.929842 -38.053518)
		(end 154.06624 -38.735508)
		(stroke
			(width 0.06985)
			(type default)
		)
		(layer "In5.Cu")
	)
	(gr_line
		(start 153.938986 -82.0674)
		(end 153.953718 -82.087974)
		(stroke
			(width 0.06985)
			(type default)
		)
		(layer "In5.Cu")
	)
	(gr_line
		(start 153.953718 -82.087974)
		(end 153.975816 -82.101944)
		(stroke
			(width 0.06985)
			(type default)
		)
		(layer "In5.Cu")
	)
	(gr_line
		(start 153.97607 -53.43271)
		(end 154.111706 -54.110382)
		(stroke
			(width 0.06985)
			(type default)
		)
		(layer "In5.Cu")
	)
	(gr_line
		(start 154.006042 -50.999898)
		(end 154.088338 -51.41087)
		(stroke
			(width 0.06985)
			(type default)
		)
		(layer "In5.Cu")
	)
	(gr_line
		(start 154.006042 -50.999898)
		(end 154.14371 -50.793396)
		(stroke
			(width 0.06985)
			(type default)
		)
		(layer "In5.Cu")
	)
	(gr_line
		(start 154.088338 -51.41087)
		(end 154.294586 -51.548538)
		(stroke
			(width 0.06985)
			(type default)
		)
		(layer "In5.Cu")
	)
	(gr_line
		(start 154.210258 -54.60238)
		(end 154.346148 -55.28183)
		(stroke
			(width 0.06985)
			(type default)
		)
		(layer "In5.Cu")
	)
	(gr_line
		(start 154.24023 -52.17033)
		(end 154.322272 -52.581302)
		(stroke
			(width 0.06985)
			(type default)
		)
		(layer "In5.Cu")
	)
	(gr_line
		(start 154.24023 -52.17033)
		(end 154.377644 -51.964082)
		(stroke
			(width 0.06985)
			(type default)
		)
		(layer "In5.Cu")
	)
	(gr_line
		(start 154.322272 -52.581302)
		(end 154.528774 -52.719224)
		(stroke
			(width 0.06985)
			(type default)
		)
		(layer "In5.Cu")
	)
	(gr_line
		(start 154.444192 -55.821834)
		(end 154.449272 -55.797196)
		(stroke
			(width 0.06985)
			(type default)
		)
		(layer "In5.Cu")
	)
	(gr_line
		(start 154.444192 -55.77205)
		(end 154.449272 -55.797196)
		(stroke
			(width 0.06985)
			(type default)
		)
		(layer "In5.Cu")
	)
	(gr_line
		(start 154.474418 -53.341016)
		(end 154.55646 -53.751988)
		(stroke
			(width 0.06985)
			(type default)
		)
		(layer "In5.Cu")
	)
	(gr_line
		(start 154.474418 -53.341016)
		(end 154.611832 -53.135022)
		(stroke
			(width 0.06985)
			(type default)
		)
		(layer "In5.Cu")
	)
	(gr_line
		(start 154.477212 -50.764694)
		(end 154.61361 -51.446684)
		(stroke
			(width 0.06985)
			(type default)
		)
		(layer "In5.Cu")
	)
	(gr_line
		(start 154.497024 -62.478412)
		(end 154.501596 -62.502542)
		(stroke
			(width 0.06985)
			(type default)
		)
		(layer "In5.Cu")
	)
	(gr_line
		(start 154.497024 -62.478412)
		(end 154.50185 -62.454282)
		(stroke
			(width 0.06985)
			(type default)
		)
		(layer "In5.Cu")
	)
	(gr_line
		(start 154.55646 -53.751988)
		(end 154.762708 -53.889402)
		(stroke
			(width 0.06985)
			(type default)
		)
		(layer "In5.Cu")
	)
	(gr_line
		(start 154.708352 -54.511702)
		(end 154.790648 -54.922674)
		(stroke
			(width 0.06985)
			(type default)
		)
		(layer "In5.Cu")
	)
	(gr_line
		(start 154.708352 -54.511702)
		(end 154.84602 -54.3052)
		(stroke
			(width 0.06985)
			(type default)
		)
		(layer "In5.Cu")
	)
	(gr_line
		(start 154.7114 -51.93665)
		(end 154.847544 -52.616608)
		(stroke
			(width 0.06985)
			(type default)
		)
		(layer "In5.Cu")
	)
	(gr_line
		(start 154.731974 -73.867772)
		(end 154.737054 -73.892918)
		(stroke
			(width 0.06985)
			(type default)
		)
		(layer "In5.Cu")
	)
	(gr_line
		(start 154.737054 -73.892918)
		(end 154.75077 -73.912984)
		(stroke
			(width 0.06985)
			(type default)
		)
		(layer "In5.Cu")
	)
	(gr_line
		(start 154.765756 -53.891434)
		(end 154.769058 -53.907944)
		(stroke
			(width 0.06985)
			(type default)
		)
		(layer "In5.Cu")
	)
	(gr_line
		(start 154.790648 -54.922674)
		(end 154.996896 -55.060342)
		(stroke
			(width 0.06985)
			(type default)
		)
		(layer "In5.Cu")
	)
	(gr_line
		(start 154.825954 -50.068988)
		(end 154.907996 -50.47996)
		(stroke
			(width 0.06985)
			(type default)
		)
		(layer "In5.Cu")
	)
	(gr_line
		(start 154.825954 -50.068988)
		(end 154.963368 -49.86274)
		(stroke
			(width 0.06985)
			(type default)
		)
		(layer "In5.Cu")
	)
	(gr_line
		(start 154.907996 -50.47996)
		(end 155.114244 -50.617374)
		(stroke
			(width 0.06985)
			(type default)
		)
		(layer "In5.Cu")
	)
	(gr_line
		(start 154.91587 -80.987138)
		(end 154.92984 -81.007712)
		(stroke
			(width 0.06985)
			(type default)
		)
		(layer "In5.Cu")
	)
	(gr_line
		(start 154.92984 -81.007712)
		(end 154.950414 -81.021682)
		(stroke
			(width 0.06985)
			(type default)
		)
		(layer "In5.Cu")
	)
	(gr_line
		(start 154.945842 -53.108098)
		(end 155.081478 -53.786278)
		(stroke
			(width 0.06985)
			(type default)
		)
		(layer "In5.Cu")
	)
	(gr_line
		(start 155.059888 -51.239674)
		(end 155.142184 -51.650646)
		(stroke
			(width 0.06985)
			(type default)
		)
		(layer "In5.Cu")
	)
	(gr_line
		(start 155.059888 -51.239674)
		(end 155.197556 -51.033426)
		(stroke
			(width 0.06985)
			(type default)
		)
		(layer "In5.Cu")
	)
	(gr_line
		(start 155.088082 -53.819298)
		(end 155.092908 -53.843428)
		(stroke
			(width 0.06985)
			(type default)
		)
		(layer "In5.Cu")
	)
	(gr_line
		(start 155.142184 -51.650646)
		(end 155.348432 -51.78806)
		(stroke
			(width 0.06985)
			(type default)
		)
		(layer "In5.Cu")
	)
	(gr_line
		(start 155.14701 -50.768504)
		(end 155.199588 -51.030378)
		(stroke
			(width 0.06985)
			(type default)
		)
		(layer "In5.Cu")
	)
	(gr_line
		(start 155.179522 -54.277768)
		(end 155.315666 -54.957726)
		(stroke
			(width 0.06985)
			(type default)
		)
		(layer "In5.Cu")
	)
	(gr_line
		(start 155.294076 -52.410106)
		(end 155.376372 -52.821078)
		(stroke
			(width 0.06985)
			(type default)
		)
		(layer "In5.Cu")
	)
	(gr_line
		(start 155.294076 -52.410106)
		(end 155.43149 -52.203858)
		(stroke
			(width 0.06985)
			(type default)
		)
		(layer "In5.Cu")
	)
	(gr_line
		(start 155.297378 -49.835816)
		(end 155.433268 -50.514758)
		(stroke
			(width 0.06985)
			(type default)
		)
		(layer "In5.Cu")
	)
	(gr_line
		(start 155.324556 -62.330584)
		(end 155.329636 -62.355984)
		(stroke
			(width 0.06985)
			(type default)
		)
		(layer "In5.Cu")
	)
	(gr_line
		(start 155.324556 -62.330584)
		(end 155.329636 -62.305946)
		(stroke
			(width 0.06985)
			(type default)
		)
		(layer "In5.Cu")
	)
	(gr_line
		(start 155.35148 -51.790092)
		(end 155.37688 -51.9176)
		(stroke
			(width 0.06985)
			(type default)
		)
		(layer "In5.Cu")
	)
	(gr_line
		(start 155.376372 -52.821078)
		(end 155.58262 -52.958492)
		(stroke
			(width 0.06985)
			(type default)
		)
		(layer "In5.Cu")
	)
	(gr_line
		(start 155.41371 -55.49773)
		(end 155.41879 -55.473092)
		(stroke
			(width 0.06985)
			(type default)
		)
		(layer "In5.Cu")
	)
	(gr_line
		(start 155.41371 -55.447946)
		(end 155.41879 -55.473092)
		(stroke
			(width 0.06985)
			(type default)
		)
		(layer "In5.Cu")
	)
	(gr_line
		(start 155.47086 -50.703734)
		(end 155.524708 -50.972466)
		(stroke
			(width 0.06985)
			(type default)
		)
		(layer "In5.Cu")
	)
	(gr_line
		(start 155.528264 -53.580792)
		(end 155.610306 -53.991764)
		(stroke
			(width 0.06985)
			(type default)
		)
		(layer "In5.Cu")
	)
	(gr_line
		(start 155.528264 -53.580792)
		(end 155.665678 -53.374544)
		(stroke
			(width 0.06985)
			(type default)
		)
		(layer "In5.Cu")
	)
	(gr_line
		(start 155.531566 -51.00701)
		(end 155.667202 -51.684682)
		(stroke
			(width 0.06985)
			(type default)
		)
		(layer "In5.Cu")
	)
	(gr_line
		(start 155.595066 -73.412096)
		(end 155.600146 -73.437496)
		(stroke
			(width 0.06985)
			(type default)
		)
		(layer "In5.Cu")
	)
	(gr_line
		(start 155.600146 -73.437496)
		(end 155.61437 -73.458324)
		(stroke
			(width 0.06985)
			(type default)
		)
		(layer "In5.Cu")
	)
	(gr_line
		(start 155.610306 -53.991764)
		(end 155.816554 -54.129178)
		(stroke
			(width 0.06985)
			(type default)
		)
		(layer "In5.Cu")
	)
	(gr_line
		(start 155.63977 -53.231542)
		(end 155.66771 -53.371496)
		(stroke
			(width 0.06985)
			(type default)
		)
		(layer "In5.Cu")
	)
	(gr_line
		(start 155.673806 -51.717956)
		(end 155.69692 -51.833526)
		(stroke
			(width 0.06985)
			(type default)
		)
		(layer "In5.Cu")
	)
	(gr_line
		(start 155.761182 -80.525366)
		(end 155.775914 -80.547464)
		(stroke
			(width 0.06985)
			(type default)
		)
		(layer "In5.Cu")
	)
	(gr_line
		(start 155.765246 -52.174902)
		(end 155.901644 -52.856892)
		(stroke
			(width 0.06985)
			(type default)
		)
		(layer "In5.Cu")
	)
	(gr_line
		(start 155.775914 -80.547464)
		(end 155.798012 -80.562196)
		(stroke
			(width 0.06985)
			(type default)
		)
		(layer "In5.Cu")
	)
	(gr_line
		(start 155.810458 -50.047144)
		(end 155.8925 -50.458116)
		(stroke
			(width 0.06985)
			(type default)
		)
		(layer "In5.Cu")
	)
	(gr_line
		(start 155.810458 -50.047144)
		(end 155.947872 -49.840642)
		(stroke
			(width 0.06985)
			(type default)
		)
		(layer "In5.Cu")
	)
	(gr_line
		(start 155.819602 -54.13121)
		(end 155.841954 -54.242716)
		(stroke
			(width 0.06985)
			(type default)
		)
		(layer "In5.Cu")
	)
	(gr_line
		(start 155.8925 -50.458116)
		(end 156.099002 -50.595784)
		(stroke
			(width 0.06985)
			(type default)
		)
		(layer "In5.Cu")
	)
	(gr_line
		(start 155.987242 -53.285644)
		(end 155.99283 -53.314092)
		(stroke
			(width 0.06985)
			(type default)
		)
		(layer "In5.Cu")
	)
	(gr_line
		(start 155.999688 -53.347366)
		(end 156.135578 -54.026562)
		(stroke
			(width 0.06985)
			(type default)
		)
		(layer "In5.Cu")
	)
	(gr_line
		(start 156.044646 -51.21783)
		(end 156.126688 -51.628548)
		(stroke
			(width 0.06985)
			(type default)
		)
		(layer "In5.Cu")
	)
	(gr_line
		(start 156.044646 -51.21783)
		(end 156.18206 -51.011582)
		(stroke
			(width 0.06985)
			(type default)
		)
		(layer "In5.Cu")
	)
	(gr_line
		(start 156.126688 -51.628548)
		(end 156.33319 -51.766216)
		(stroke
			(width 0.06985)
			(type default)
		)
		(layer "In5.Cu")
	)
	(gr_line
		(start 156.141166 -54.055772)
		(end 156.144722 -54.07279)
		(stroke
			(width 0.06985)
			(type default)
		)
		(layer "In5.Cu")
	)
	(gr_line
		(start 156.27858 -52.388262)
		(end 156.360876 -52.799234)
		(stroke
			(width 0.06985)
			(type default)
		)
		(layer "In5.Cu")
	)
	(gr_line
		(start 156.27858 -52.388262)
		(end 156.416248 -52.182014)
		(stroke
			(width 0.06985)
			(type default)
		)
		(layer "In5.Cu")
	)
	(gr_line
		(start 156.281628 -49.81321)
		(end 156.417518 -50.492406)
		(stroke
			(width 0.06985)
			(type default)
		)
		(layer "In5.Cu")
	)
	(gr_line
		(start 156.324554 -55.023004)
		(end 156.329634 -54.997858)
		(stroke
			(width 0.06985)
			(type default)
		)
		(layer "In5.Cu")
	)
	(gr_line
		(start 156.324554 -54.97322)
		(end 156.329634 -54.997858)
		(stroke
			(width 0.06985)
			(type default)
		)
		(layer "In5.Cu")
	)
	(gr_line
		(start 156.360876 -52.799234)
		(end 156.567124 -52.936648)
		(stroke
			(width 0.06985)
			(type default)
		)
		(layer "In5.Cu")
	)
	(gr_line
		(start 156.457904 -72.838818)
		(end 156.463238 -72.866504)
		(stroke
			(width 0.06985)
			(type default)
		)
		(layer "In5.Cu")
	)
	(gr_line
		(start 156.463238 -72.866504)
		(end 156.478478 -72.888856)
		(stroke
			(width 0.06985)
			(type default)
		)
		(layer "In5.Cu")
	)
	(gr_line
		(start 156.512768 -53.558948)
		(end 156.595064 -53.96992)
		(stroke
			(width 0.06985)
			(type default)
		)
		(layer "In5.Cu")
	)
	(gr_line
		(start 156.512768 -53.558948)
		(end 156.650436 -53.352446)
		(stroke
			(width 0.06985)
			(type default)
		)
		(layer "In5.Cu")
	)
	(gr_line
		(start 156.51607 -50.985674)
		(end 156.651452 -51.66233)
		(stroke
			(width 0.06985)
			(type default)
		)
		(layer "In5.Cu")
	)
	(gr_line
		(start 156.51861 -79.99222)
		(end 156.532072 -80.01254)
		(stroke
			(width 0.06985)
			(type default)
		)
		(layer "In5.Cu")
	)
	(gr_line
		(start 156.532072 -80.01254)
		(end 156.552646 -80.026256)
		(stroke
			(width 0.06985)
			(type default)
		)
		(layer "In5.Cu")
	)
	(gr_line
		(start 156.570172 -52.93868)
		(end 156.589984 -53.037994)
		(stroke
			(width 0.06985)
			(type default)
		)
		(layer "In5.Cu")
	)
	(gr_line
		(start 156.595064 -53.96992)
		(end 156.801312 -54.107588)
		(stroke
			(width 0.06985)
			(type default)
		)
		(layer "In5.Cu")
	)
	(gr_line
		(start 156.74975 -52.153312)
		(end 156.88564 -52.832762)
		(stroke
			(width 0.06985)
			(type default)
		)
		(layer "In5.Cu")
	)
	(gr_line
		(start 156.893006 -52.869084)
		(end 156.95803 -53.194712)
		(stroke
			(width 0.06985)
			(type default)
		)
		(layer "In5.Cu")
	)
	(gr_line
		(start 156.983938 -53.324252)
		(end 157.120336 -54.00548)
		(stroke
			(width 0.06985)
			(type default)
		)
		(layer "In5.Cu")
	)
	(gr_line
		(start 157.218126 -54.545484)
		(end 157.223206 -54.520338)
		(stroke
			(width 0.06985)
			(type default)
		)
		(layer "In5.Cu")
	)
	(gr_line
		(start 157.21838 -54.496208)
		(end 157.223206 -54.520338)
		(stroke
			(width 0.06985)
			(type default)
		)
		(layer "In5.Cu")
	)
	(gr_line
		(start 157.310582 -79.384144)
		(end 157.325314 -79.406242)
		(stroke
			(width 0.06985)
			(type default)
		)
		(layer "In5.Cu")
	)
	(gr_line
		(start 157.325314 -79.406242)
		(end 157.347412 -79.420974)
		(stroke
			(width 0.06985)
			(type default)
		)
		(layer "In5.Cu")
	)
	(gr_line
		(start 157.363414 -72.526906)
		(end 157.368494 -72.552052)
		(stroke
			(width 0.06985)
			(type default)
		)
		(layer "In5.Cu")
	)
	(gr_line
		(start 157.368494 -72.552052)
		(end 157.38221 -72.572118)
		(stroke
			(width 0.06985)
			(type default)
		)
		(layer "In5.Cu")
	)
	(gr_line
		(start 157.923992 -78.673198)
		(end 157.938724 -78.695296)
		(stroke
			(width 0.06985)
			(type default)
		)
		(layer "In5.Cu")
	)
	(gr_line
		(start 157.938724 -78.695296)
		(end 157.960822 -78.710028)
		(stroke
			(width 0.06985)
			(type default)
		)
		(layer "In5.Cu")
	)
	(gr_line
		(start 158.338266 -84.459318)
		(end 158.384494 -84.488274)
		(stroke
			(width 0.06985)
			(type default)
		)
		(layer "In5.Cu")
	)
	(gr_line
		(start 158.384494 -84.488274)
		(end 158.408878 -84.537804)
		(stroke
			(width 0.06985)
			(type default)
		)
		(layer "In5.Cu")
	)
	(gr_line
		(start 158.83636 -78.291182)
		(end 158.851092 -78.31328)
		(stroke
			(width 0.06985)
			(type default)
		)
		(layer "In5.Cu")
	)
	(gr_line
		(start 158.851092 -78.31328)
		(end 158.87319 -78.328012)
		(stroke
			(width 0.06985)
			(type default)
		)
		(layer "In5.Cu")
	)
	(gr_line
		(start 159.22625 -86.948264)
		(end 159.251142 -86.999064)
		(stroke
			(width 0.06985)
			(type default)
		)
		(layer "In5.Cu")
	)
	(gr_line
		(start 159.250126 -30.500066)
		(end 159.505142 -30.023816)
		(stroke
			(width 0.0508)
			(type default)
		)
		(layer "In5.Cu")
	)
	(gr_line
		(start 159.250126 -26.699972)
		(end 159.505142 -26.223722)
		(stroke
			(width 0.0508)
			(type default)
		)
		(layer "In5.Cu")
	)
	(gr_line
		(start 159.251142 -86.999064)
		(end 159.300164 -87.028782)
		(stroke
			(width 0.06985)
			(type default)
		)
		(layer "In5.Cu")
	)
	(gr_line
		(start 159.505142 -30.023816)
		(end 159.639254 -29.98343)
		(stroke
			(width 0.0508)
			(type default)
		)
		(layer "In5.Cu")
	)
	(gr_line
		(start 159.505142 -26.223722)
		(end 159.639254 -26.183336)
		(stroke
			(width 0.0508)
			(type default)
		)
		(layer "In5.Cu")
	)
	(gr_line
		(start 159.744664 -29.576268)
		(end 159.785558 -29.71038)
		(stroke
			(width 0.0508)
			(type default)
		)
		(layer "In5.Cu")
	)
	(gr_line
		(start 159.744664 -29.576268)
		(end 159.999934 -29.100018)
		(stroke
			(width 0.0508)
			(type default)
		)
		(layer "In5.Cu")
	)
	(gr_line
		(start 159.744664 -25.776174)
		(end 159.785558 -25.910286)
		(stroke
			(width 0.0508)
			(type default)
		)
		(layer "In5.Cu")
	)
	(gr_line
		(start 159.744664 -25.776174)
		(end 159.999934 -25.299924)
		(stroke
			(width 0.0508)
			(type default)
		)
		(layer "In5.Cu")
	)
	(gr_line
		(start 159.795972 -77.865478)
		(end 159.810704 -77.887576)
		(stroke
			(width 0.06985)
			(type default)
		)
		(layer "In5.Cu")
	)
	(gr_line
		(start 159.810704 -77.887576)
		(end 159.832802 -77.902308)
		(stroke
			(width 0.06985)
			(type default)
		)
		(layer "In5.Cu")
	)
	(gr_line
		(start 159.86887 -29.757624)
		(end 159.876236 -29.761688)
		(stroke
			(width 0.0508)
			(type default)
		)
		(layer "In5.Cu")
	)
	(gr_line
		(start 159.876236 -29.761688)
		(end 159.882332 -29.767784)
		(stroke
			(width 0.0508)
			(type default)
		)
		(layer "In5.Cu")
	)
	(gr_line
		(start 159.876236 -25.961594)
		(end 159.88284 -25.968198)
		(stroke
			(width 0.0508)
			(type default)
		)
		(layer "In5.Cu")
	)
	(gr_line
		(start 159.88919 -30.697424)
		(end 159.916876 -30.740096)
		(stroke
			(width 0.0508)
			(type default)
		)
		(layer "In5.Cu")
	)
	(gr_line
		(start 159.93999 -26.930604)
		(end 160.00222 -26.992834)
		(stroke
			(width 0.0508)
			(type default)
		)
		(layer "In5.Cu")
	)
	(gr_line
		(start 160.13176 -30.017212)
		(end 160.19399 -30.079442)
		(stroke
			(width 0.0508)
			(type default)
		)
		(layer "In5.Cu")
	)
	(gr_line
		(start 160.18256 -26.267918)
		(end 160.24479 -26.330148)
		(stroke
			(width 0.0508)
			(type default)
		)
		(layer "In5.Cu")
	)
	(gr_line
		(start 160.425892 -77.138784)
		(end 160.440624 -77.160882)
		(stroke
			(width 0.06985)
			(type default)
		)
		(layer "In5.Cu")
	)
	(gr_line
		(start 160.440624 -77.160882)
		(end 160.462722 -77.175614)
		(stroke
			(width 0.06985)
			(type default)
		)
		(layer "In5.Cu")
	)
	(gr_line
		(start 160.580324 -84.821776)
		(end 160.627822 -85.065362)
		(stroke
			(width 0.06985)
			(type default)
		)
		(layer "In5.Cu")
	)
	(gr_line
		(start 160.627822 -85.065362)
		(end 160.975294 -85.299804)
		(stroke
			(width 0.06985)
			(type default)
		)
		(layer "In5.Cu")
	)
	(gr_line
		(start 160.796732 -84.566252)
		(end 161.37382 -84.955634)
		(stroke
			(width 0.06985)
			(type default)
		)
		(layer "In5.Cu")
	)
	(gr_line
		(start 160.82264 -27.813508)
		(end 160.876996 -27.824176)
		(stroke
			(width 0.0508)
			(type default)
		)
		(layer "In5.Cu")
	)
	(gr_line
		(start 160.875218 -32.215328)
		(end 160.88995 -32.237934)
		(stroke
			(width 0.0508)
			(type default)
		)
		(layer "In5.Cu")
	)
	(gr_line
		(start 160.88995 -32.237934)
		(end 160.912556 -32.252666)
		(stroke
			(width 0.0508)
			(type default)
		)
		(layer "In5.Cu")
	)
	(gr_line
		(start 160.975294 -85.299804)
		(end 161.21888 -85.25256)
		(stroke
			(width 0.06985)
			(type default)
		)
		(layer "In5.Cu")
	)
	(gr_line
		(start 161.500058 -30.500066)
		(end 161.755328 -30.023562)
		(stroke
			(width 0.0508)
			(type default)
		)
		(layer "In5.Cu")
	)
	(gr_line
		(start 161.500058 -26.699972)
		(end 161.755328 -26.223468)
		(stroke
			(width 0.0508)
			(type default)
		)
		(layer "In5.Cu")
	)
	(gr_line
		(start 161.527998 -88.376252)
		(end 161.531808 -88.378538)
		(stroke
			(width 0.06985)
			(type default)
		)
		(layer "In5.Cu")
	)
	(gr_line
		(start 161.531808 -88.378538)
		(end 161.536126 -88.379808)
		(stroke
			(width 0.06985)
			(type default)
		)
		(layer "In5.Cu")
	)
	(gr_line
		(start 161.570162 -85.489288)
		(end 161.617406 -85.732874)
		(stroke
			(width 0.06985)
			(type default)
		)
		(layer "In5.Cu")
	)
	(gr_line
		(start 161.617406 -85.732874)
		(end 161.964878 -85.967316)
		(stroke
			(width 0.06985)
			(type default)
		)
		(layer "In5.Cu")
	)
	(gr_line
		(start 161.755328 -30.023562)
		(end 161.889186 -29.983176)
		(stroke
			(width 0.0508)
			(type default)
		)
		(layer "In5.Cu")
	)
	(gr_line
		(start 161.755328 -26.223468)
		(end 161.889694 -26.183082)
		(stroke
			(width 0.0508)
			(type default)
		)
		(layer "In5.Cu")
	)
	(gr_line
		(start 161.787078 -85.234272)
		(end 162.363912 -85.6234)
		(stroke
			(width 0.06985)
			(type default)
		)
		(layer "In5.Cu")
	)
	(gr_line
		(start 161.892742 -29.98216)
		(end 161.894012 -29.982922)
		(stroke
			(width 0.0508)
			(type default)
		)
		(layer "In5.Cu")
	)
	(gr_line
		(start 161.894012 -29.982922)
		(end 161.895536 -29.983684)
		(stroke
			(width 0.0508)
			(type default)
		)
		(layer "In5.Cu")
	)
	(gr_line
		(start 161.895536 -29.983684)
		(end 161.896298 -29.984192)
		(stroke
			(width 0.0508)
			(type default)
		)
		(layer "In5.Cu")
	)
	(gr_line
		(start 161.896298 -29.984192)
		(end 161.897568 -29.984954)
		(stroke
			(width 0.0508)
			(type default)
		)
		(layer "In5.Cu")
	)
	(gr_line
		(start 161.897568 -29.984954)
		(end 161.899092 -29.985716)
		(stroke
			(width 0.0508)
			(type default)
		)
		(layer "In5.Cu")
	)
	(gr_line
		(start 161.899092 -29.985716)
		(end 161.900362 -29.986478)
		(stroke
			(width 0.0508)
			(type default)
		)
		(layer "In5.Cu")
	)
	(gr_line
		(start 161.900362 -29.986478)
		(end 161.902394 -29.987494)
		(stroke
			(width 0.0508)
			(type default)
		)
		(layer "In5.Cu")
	)
	(gr_line
		(start 161.906458 -29.98978)
		(end 161.912554 -29.992828)
		(stroke
			(width 0.0508)
			(type default)
		)
		(layer "In5.Cu")
	)
	(gr_line
		(start 161.91484 -29.994098)
		(end 161.916872 -29.995114)
		(stroke
			(width 0.0508)
			(type default)
		)
		(layer "In5.Cu")
	)
	(gr_line
		(start 161.916872 -29.995114)
		(end 161.917126 -29.995368)
		(stroke
			(width 0.0508)
			(type default)
		)
		(layer "In5.Cu")
	)
	(gr_line
		(start 161.917634 -29.995622)
		(end 161.918904 -29.996384)
		(stroke
			(width 0.0508)
			(type default)
		)
		(layer "In5.Cu")
	)
	(gr_line
		(start 161.924238 -29.999178)
		(end 161.925 -29.999686)
		(stroke
			(width 0.0508)
			(type default)
		)
		(layer "In5.Cu")
	)
	(gr_line
		(start 161.964878 -85.967316)
		(end 162.208464 -85.920072)
		(stroke
			(width 0.06985)
			(type default)
		)
		(layer "In5.Cu")
	)
	(gr_line
		(start 161.995104 -29.576014)
		(end 162.03676 -29.710634)
		(stroke
			(width 0.0508)
			(type default)
		)
		(layer "In5.Cu")
	)
	(gr_line
		(start 161.995104 -29.576014)
		(end 162.25012 -29.100018)
		(stroke
			(width 0.0508)
			(type default)
		)
		(layer "In5.Cu")
	)
	(gr_line
		(start 161.995104 -25.77592)
		(end 162.035998 -25.910032)
		(stroke
			(width 0.0508)
			(type default)
		)
		(layer "In5.Cu")
	)
	(gr_line
		(start 161.995104 -25.77592)
		(end 162.25012 -25.299924)
		(stroke
			(width 0.0508)
			(type default)
		)
		(layer "In5.Cu")
	)
	(gr_line
		(start 162.037014 -29.713428)
		(end 162.038284 -29.71419)
		(stroke
			(width 0.0508)
			(type default)
		)
		(layer "In5.Cu")
	)
	(gr_line
		(start 162.038284 -29.71419)
		(end 162.039808 -29.715206)
		(stroke
			(width 0.0508)
			(type default)
		)
		(layer "In5.Cu")
	)
	(gr_line
		(start 162.039808 -29.715206)
		(end 162.047936 -29.71927)
		(stroke
			(width 0.0508)
			(type default)
		)
		(layer "In5.Cu")
	)
	(gr_line
		(start 162.047936 -29.71927)
		(end 162.048698 -29.719778)
		(stroke
			(width 0.0508)
			(type default)
		)
		(layer "In5.Cu")
	)
	(gr_line
		(start 162.050984 -29.720794)
		(end 162.054032 -29.722318)
		(stroke
			(width 0.0508)
			(type default)
		)
		(layer "In5.Cu")
	)
	(gr_line
		(start 162.058096 -29.724604)
		(end 162.059366 -29.725366)
		(stroke
			(width 0.0508)
			(type default)
		)
		(layer "In5.Cu")
	)
	(gr_line
		(start 162.06216 -29.727144)
		(end 162.06343 -29.727906)
		(stroke
			(width 0.0508)
			(type default)
		)
		(layer "In5.Cu")
	)
	(gr_line
		(start 162.06343 -29.727906)
		(end 162.066224 -29.72943)
		(stroke
			(width 0.0508)
			(type default)
		)
		(layer "In5.Cu")
	)
	(gr_line
		(start 162.161728 -29.780484)
		(end 162.168078 -29.78404)
		(stroke
			(width 0.0508)
			(type default)
		)
		(layer "In5.Cu")
	)
	(gr_line
		(start 162.168078 -29.78404)
		(end 162.173158 -29.78912)
		(stroke
			(width 0.0508)
			(type default)
		)
		(layer "In5.Cu")
	)
	(gr_line
		(start 162.317938 -26.063448)
		(end 162.353244 -26.082244)
		(stroke
			(width 0.0508)
			(type default)
		)
		(layer "In5.Cu")
	)
	(gr_line
		(start 162.353244 -26.082244)
		(end 162.375596 -26.115772)
		(stroke
			(width 0.0508)
			(type default)
		)
		(layer "In5.Cu")
	)
	(gr_line
		(start 162.486594 -26.832814)
		(end 162.536124 -26.907236)
		(stroke
			(width 0.0508)
			(type default)
		)
		(layer "In5.Cu")
	)
	(gr_line
		(start 162.536124 -26.907236)
		(end 162.6235 -26.924762)
		(stroke
			(width 0.0508)
			(type default)
		)
		(layer "In5.Cu")
	)
	(gr_line
		(start 162.847274 -30.791658)
		(end 162.866578 -30.804866)
		(stroke
			(width 0.0508)
			(type default)
		)
		(layer "In5.Cu")
	)
	(gr_line
		(start 162.866578 -30.804866)
		(end 162.889946 -30.809438)
		(stroke
			(width 0.0508)
			(type default)
		)
		(layer "In5.Cu")
	)
	(gr_line
		(start 163.167568 -30.865826)
		(end 163.316412 -31.086298)
		(stroke
			(width 0.0508)
			(type default)
		)
		(layer "In5.Cu")
	)
	(gr_line
		(start 163.261802 -30.570932)
		(end 163.858956 -30.687264)
		(stroke
			(width 0.0508)
			(type default)
		)
		(layer "In5.Cu")
	)
	(gr_line
		(start 163.316412 -31.086298)
		(end 163.615624 -31.144464)
		(stroke
			(width 0.0508)
			(type default)
		)
		(layer "In5.Cu")
	)
	(gr_line
		(start 163.615624 -31.144464)
		(end 163.836096 -30.995874)
		(stroke
			(width 0.0508)
			(type default)
		)
		(layer "In5.Cu")
	)
	(gr_line
		(start 163.632388 -27.128978)
		(end 163.780216 -27.350466)
		(stroke
			(width 0.0508)
			(type default)
		)
		(layer "In5.Cu")
	)
	(gr_line
		(start 163.727892 -26.834592)
		(end 164.326824 -26.95448)
		(stroke
			(width 0.0508)
			(type default)
		)
		(layer "In5.Cu")
	)
	(gr_line
		(start 163.780216 -27.350466)
		(end 164.07892 -27.410156)
		(stroke
			(width 0.0508)
			(type default)
		)
		(layer "In5.Cu")
	)
	(gr_line
		(start 164.07892 -27.410156)
		(end 164.300662 -27.262582)
		(stroke
			(width 0.0508)
			(type default)
		)
		(layer "In5.Cu")
	)
	(gr_line
		(start 164.140134 -31.054802)
		(end 164.288724 -31.275528)
		(stroke
			(width 0.0508)
			(type default)
		)
		(layer "In5.Cu")
	)
	(gr_line
		(start 164.234876 -30.760162)
		(end 164.831014 -30.87624)
		(stroke
			(width 0.0508)
			(type default)
		)
		(layer "In5.Cu")
	)
	(gr_line
		(start 164.288724 -31.275528)
		(end 164.587936 -31.333694)
		(stroke
			(width 0.0508)
			(type default)
		)
		(layer "In5.Cu")
	)
	(gr_line
		(start 164.587936 -31.333694)
		(end 164.808662 -31.18485)
		(stroke
			(width 0.0508)
			(type default)
		)
		(layer "In5.Cu")
	)
	(gr_line
		(start 164.603938 -27.323288)
		(end 164.751512 -27.544776)
		(stroke
			(width 0.0508)
			(type default)
		)
		(layer "In5.Cu")
	)
	(gr_line
		(start 164.699442 -27.028902)
		(end 165.297358 -27.148536)
		(stroke
			(width 0.0508)
			(type default)
		)
		(layer "In5.Cu")
	)
	(gr_line
		(start 164.751512 -27.544776)
		(end 165.05047 -27.604466)
		(stroke
			(width 0.0508)
			(type default)
		)
		(layer "In5.Cu")
	)
	(gr_line
		(start 164.804852 -88.954102)
		(end 164.81806 -88.957912)
		(stroke
			(width 0.06985)
			(type default)
		)
		(layer "In5.Cu")
	)
	(gr_line
		(start 164.81806 -88.957912)
		(end 164.82949 -88.965532)
		(stroke
			(width 0.06985)
			(type default)
		)
		(layer "In5.Cu")
	)
	(gr_line
		(start 164.871146 -34.8234)
		(end 164.888926 -34.835084)
		(stroke
			(width 0.0508)
			(type default)
		)
		(layer "In5.Cu")
	)
	(gr_line
		(start 164.888926 -34.835084)
		(end 164.88918 -34.835084)
		(stroke
			(width 0.0508)
			(type default)
		)
		(layer "In5.Cu")
	)
	(gr_line
		(start 164.88918 -34.835084)
		(end 164.9095 -34.839148)
		(stroke
			(width 0.0508)
			(type default)
		)
		(layer "In5.Cu")
	)
	(gr_line
		(start 165.05047 -27.604466)
		(end 165.271958 -27.456892)
		(stroke
			(width 0.0508)
			(type default)
		)
		(layer "In5.Cu")
	)
	(gr_line
		(start 165.112446 -31.244032)
		(end 165.26129 -31.464504)
		(stroke
			(width 0.0508)
			(type default)
		)
		(layer "In5.Cu")
	)
	(gr_line
		(start 165.207188 -30.949392)
		(end 165.803834 -31.06547)
		(stroke
			(width 0.0508)
			(type default)
		)
		(layer "In5.Cu")
	)
	(gr_line
		(start 165.26129 -31.464504)
		(end 165.560502 -31.52267)
		(stroke
			(width 0.0508)
			(type default)
		)
		(layer "In5.Cu")
	)
	(gr_line
		(start 165.560502 -31.52267)
		(end 165.780974 -31.373826)
		(stroke
			(width 0.0508)
			(type default)
		)
		(layer "In5.Cu")
	)
	(gr_line
		(start 165.575234 -27.517598)
		(end 165.722808 -27.739086)
		(stroke
			(width 0.0508)
			(type default)
		)
		(layer "In5.Cu")
	)
	(gr_line
		(start 165.67023 -27.223212)
		(end 166.270686 -27.3431)
		(stroke
			(width 0.0508)
			(type default)
		)
		(layer "In5.Cu")
	)
	(gr_line
		(start 165.722808 -27.739086)
		(end 166.021766 -27.798776)
		(stroke
			(width 0.0508)
			(type default)
		)
		(layer "In5.Cu")
	)
	(gr_line
		(start 165.97249 -28.532074)
		(end 165.993826 -28.536138)
		(stroke
			(width 0.0508)
			(type default)
		)
		(layer "In5.Cu")
	)
	(gr_line
		(start 165.993826 -28.536138)
		(end 166.01186 -28.54833)
		(stroke
			(width 0.0508)
			(type default)
		)
		(layer "In5.Cu")
	)
	(gr_line
		(start 166.021766 -27.798776)
		(end 166.243254 -27.651202)
		(stroke
			(width 0.0508)
			(type default)
		)
		(layer "In5.Cu")
	)
	(gr_line
		(start 166.084758 -31.433008)
		(end 166.233602 -31.65348)
		(stroke
			(width 0.0508)
			(type default)
		)
		(layer "In5.Cu")
	)
	(gr_line
		(start 166.128954 -28.995624)
		(end 166.181532 -29.256736)
		(stroke
			(width 0.0508)
			(type default)
		)
		(layer "In5.Cu")
	)
	(gr_line
		(start 166.161212 -35.091116)
		(end 166.308786 -35.312604)
		(stroke
			(width 0.0508)
			(type default)
		)
		(layer "In5.Cu")
	)
	(gr_line
		(start 166.178738 -31.138114)
		(end 166.775638 -31.254192)
		(stroke
			(width 0.0508)
			(type default)
		)
		(layer "In5.Cu")
	)
	(gr_line
		(start 166.181532 -29.256736)
		(end 166.435024 -29.425646)
		(stroke
			(width 0.0508)
			(type default)
		)
		(layer "In5.Cu")
	)
	(gr_line
		(start 166.233602 -31.65348)
		(end 166.532814 -31.711646)
		(stroke
			(width 0.0508)
			(type default)
		)
		(layer "In5.Cu")
	)
	(gr_line
		(start 166.255954 -34.796476)
		(end 166.857172 -34.916364)
		(stroke
			(width 0.0508)
			(type default)
		)
		(layer "In5.Cu")
	)
	(gr_line
		(start 166.308786 -35.312604)
		(end 166.607744 -35.37204)
		(stroke
			(width 0.0508)
			(type default)
		)
		(layer "In5.Cu")
	)
	(gr_line
		(start 166.329868 -28.76042)
		(end 166.834566 -29.09697)
		(stroke
			(width 0.0508)
			(type default)
		)
		(layer "In5.Cu")
	)
	(gr_line
		(start 166.435024 -29.425646)
		(end 166.695882 -29.373576)
		(stroke
			(width 0.0508)
			(type default)
		)
		(layer "In5.Cu")
	)
	(gr_line
		(start 166.532814 -31.711646)
		(end 166.753286 -31.562802)
		(stroke
			(width 0.0508)
			(type default)
		)
		(layer "In5.Cu")
	)
	(gr_line
		(start 166.607744 -35.37204)
		(end 166.829232 -35.224466)
		(stroke
			(width 0.0508)
			(type default)
		)
		(layer "In5.Cu")
	)
	(gr_line
		(start 166.641272 -27.417268)
		(end 166.663878 -27.42184)
		(stroke
			(width 0.0508)
			(type default)
		)
		(layer "In5.Cu")
	)
	(gr_line
		(start 166.663878 -27.42184)
		(end 166.682674 -27.43454)
		(stroke
			(width 0.0508)
			(type default)
		)
		(layer "In5.Cu")
	)
	(gr_line
		(start 166.953692 -29.54528)
		(end 167.005762 -29.806138)
		(stroke
			(width 0.0508)
			(type default)
		)
		(layer "In5.Cu")
	)
	(gr_line
		(start 167.005762 -29.806138)
		(end 167.259254 -29.975302)
		(stroke
			(width 0.0508)
			(type default)
		)
		(layer "In5.Cu")
	)
	(gr_line
		(start 167.132508 -35.284918)
		(end 167.280336 -35.506152)
		(stroke
			(width 0.0508)
			(type default)
		)
		(layer "In5.Cu")
	)
	(gr_line
		(start 167.22725 -34.990278)
		(end 167.825674 -35.109658)
		(stroke
			(width 0.0508)
			(type default)
		)
		(layer "In5.Cu")
	)
	(gr_line
		(start 167.259254 -29.975302)
		(end 167.520366 -29.922978)
		(stroke
			(width 0.0508)
			(type default)
		)
		(layer "In5.Cu")
	)
	(gr_line
		(start 167.280336 -35.506152)
		(end 167.579294 -35.565842)
		(stroke
			(width 0.0508)
			(type default)
		)
		(layer "In5.Cu")
	)
	(gr_line
		(start 167.377618 -29.45892)
		(end 167.659558 -29.64688)
		(stroke
			(width 0.0508)
			(type default)
		)
		(layer "In5.Cu")
	)
	(gr_line
		(start 167.579294 -35.565842)
		(end 167.800528 -35.418014)
		(stroke
			(width 0.0508)
			(type default)
		)
		(layer "In5.Cu")
	)
	(gr_line
		(start 167.777922 -30.094936)
		(end 167.829992 -30.35554)
		(stroke
			(width 0.0508)
			(type default)
		)
		(layer "In5.Cu")
	)
	(gr_line
		(start 167.829992 -30.35554)
		(end 168.083484 -30.524704)
		(stroke
			(width 0.0508)
			(type default)
		)
		(layer "In5.Cu")
	)
	(gr_line
		(start 167.980868 -29.861256)
		(end 168.483534 -30.196282)
		(stroke
			(width 0.0508)
			(type default)
		)
		(layer "In5.Cu")
	)
	(gr_line
		(start 168.083484 -30.524704)
		(end 168.344342 -30.472634)
		(stroke
			(width 0.0508)
			(type default)
		)
		(layer "In5.Cu")
	)
	(gr_line
		(start 168.104058 -35.478466)
		(end 168.251886 -35.699954)
		(stroke
			(width 0.0508)
			(type default)
		)
		(layer "In5.Cu")
	)
	(gr_line
		(start 168.197276 -35.183572)
		(end 168.79824 -35.30346)
		(stroke
			(width 0.0508)
			(type default)
		)
		(layer "In5.Cu")
	)
	(gr_line
		(start 168.251886 -35.699954)
		(end 168.550844 -35.759644)
		(stroke
			(width 0.0508)
			(type default)
		)
		(layer "In5.Cu")
	)
	(gr_line
		(start 168.314878 -31.553404)
		(end 168.338246 -31.557976)
		(stroke
			(width 0.0508)
			(type default)
		)
		(layer "In5.Cu")
	)
	(gr_line
		(start 168.338246 -31.557976)
		(end 168.35755 -31.571184)
		(stroke
			(width 0.0508)
			(type default)
		)
		(layer "In5.Cu")
	)
	(gr_line
		(start 168.447466 -28.980384)
		(end 168.499536 -29.241242)
		(stroke
			(width 0.0508)
			(type default)
		)
		(layer "In5.Cu")
	)
	(gr_line
		(start 168.499536 -29.241242)
		(end 168.753282 -29.410406)
		(stroke
			(width 0.0508)
			(type default)
		)
		(layer "In5.Cu")
	)
	(gr_line
		(start 168.550844 -35.759644)
		(end 168.772078 -35.611816)
		(stroke
			(width 0.0508)
			(type default)
		)
		(layer "In5.Cu")
	)
	(gr_line
		(start 168.599104 -30.639258)
		(end 168.60139 -30.640782)
		(stroke
			(width 0.0508)
			(type default)
		)
		(layer "In5.Cu")
	)
	(gr_line
		(start 168.602152 -30.644338)
		(end 168.654222 -30.904942)
		(stroke
			(width 0.0508)
			(type default)
		)
		(layer "In5.Cu")
	)
	(gr_line
		(start 168.648126 -28.744926)
		(end 169.154602 -29.082492)
		(stroke
			(width 0.0508)
			(type default)
		)
		(layer "In5.Cu")
	)
	(gr_line
		(start 168.654222 -30.904942)
		(end 168.907714 -31.074106)
		(stroke
			(width 0.0508)
			(type default)
		)
		(layer "In5.Cu")
	)
	(gr_line
		(start 168.72077 -88.138254)
		(end 168.74236 -88.152986)
		(stroke
			(width 0.06985)
			(type default)
		)
		(layer "In5.Cu")
	)
	(gr_line
		(start 168.74236 -88.152986)
		(end 168.768268 -88.157812)
		(stroke
			(width 0.06985)
			(type default)
		)
		(layer "In5.Cu")
	)
	(gr_line
		(start 168.753282 -29.410406)
		(end 169.01414 -29.358336)
		(stroke
			(width 0.0508)
			(type default)
		)
		(layer "In5.Cu")
	)
	(gr_line
		(start 168.769538 -30.386528)
		(end 168.774872 -30.390084)
		(stroke
			(width 0.0508)
			(type default)
		)
		(layer "In5.Cu")
	)
	(gr_line
		(start 168.80459 -30.41015)
		(end 169.307002 -30.745176)
		(stroke
			(width 0.0508)
			(type default)
		)
		(layer "In5.Cu")
	)
	(gr_line
		(start 168.907714 -31.074106)
		(end 169.168572 -31.022036)
		(stroke
			(width 0.0508)
			(type default)
		)
		(layer "In5.Cu")
	)
	(gr_line
		(start 169.161714 -87.296244)
		(end 169.182542 -87.310468)
		(stroke
			(width 0.06985)
			(type default)
		)
		(layer "In5.Cu")
	)
	(gr_line
		(start 169.182542 -87.310468)
		(end 169.20845 -87.315548)
		(stroke
			(width 0.06985)
			(type default)
		)
		(layer "In5.Cu")
	)
	(gr_line
		(start 169.271442 -29.529786)
		(end 169.323766 -29.790898)
		(stroke
			(width 0.0508)
			(type default)
		)
		(layer "In5.Cu")
	)
	(gr_line
		(start 169.323766 -29.790898)
		(end 169.577512 -29.960062)
		(stroke
			(width 0.0508)
			(type default)
		)
		(layer "In5.Cu")
	)
	(gr_line
		(start 169.327068 -32.59582)
		(end 169.377868 -32.856932)
		(stroke
			(width 0.0508)
			(type default)
		)
		(layer "In5.Cu")
	)
	(gr_line
		(start 169.377868 -32.856932)
		(end 169.630598 -33.027366)
		(stroke
			(width 0.0508)
			(type default)
		)
		(layer "In5.Cu")
	)
	(gr_line
		(start 169.471594 -29.29382)
		(end 169.979594 -29.632656)
		(stroke
			(width 0.0508)
			(type default)
		)
		(layer "In5.Cu")
	)
	(gr_line
		(start 169.528744 -32.36087)
		(end 170.034204 -32.701992)
		(stroke
			(width 0.0508)
			(type default)
		)
		(layer "In5.Cu")
	)
	(gr_line
		(start 169.577512 -29.960062)
		(end 169.838624 -29.907738)
		(stroke
			(width 0.0508)
			(type default)
		)
		(layer "In5.Cu")
	)
	(gr_line
		(start 169.630598 -33.027366)
		(end 169.891964 -32.976566)
		(stroke
			(width 0.0508)
			(type default)
		)
		(layer "In5.Cu")
	)
	(gr_line
		(start 169.637456 -86.494366)
		(end 169.658284 -86.50859)
		(stroke
			(width 0.06985)
			(type default)
		)
		(layer "In5.Cu")
	)
	(gr_line
		(start 169.658284 -86.50859)
		(end 169.684192 -86.51367)
		(stroke
			(width 0.06985)
			(type default)
		)
		(layer "In5.Cu")
	)
	(gr_line
		(start 169.872406 -85.66023)
		(end 169.892472 -85.673946)
		(stroke
			(width 0.06985)
			(type default)
		)
		(layer "In5.Cu")
	)
	(gr_line
		(start 169.892472 -85.673946)
		(end 169.916602 -85.678518)
		(stroke
			(width 0.06985)
			(type default)
		)
		(layer "In5.Cu")
	)
	(gr_line
		(start 169.920412 -88.04529)
		(end 169.946574 -88.05037)
		(stroke
			(width 0.06985)
			(type default)
		)
		(layer "In5.Cu")
	)
	(gr_line
		(start 169.946574 -88.05037)
		(end 169.968164 -88.065102)
		(stroke
			(width 0.06985)
			(type default)
		)
		(layer "In5.Cu")
	)
	(gr_line
		(start 170.14825 -33.14954)
		(end 170.19905 -33.410906)
		(stroke
			(width 0.0508)
			(type default)
		)
		(layer "In5.Cu")
	)
	(gr_line
		(start 170.19905 -33.410906)
		(end 170.45178 -33.58134)
		(stroke
			(width 0.0508)
			(type default)
		)
		(layer "In5.Cu")
	)
	(gr_line
		(start 170.317922 -84.89188)
		(end 170.337988 -84.905596)
		(stroke
			(width 0.06985)
			(type default)
		)
		(layer "In5.Cu")
	)
	(gr_line
		(start 170.337988 -84.905596)
		(end 170.363134 -84.910676)
		(stroke
			(width 0.06985)
			(type default)
		)
		(layer "In5.Cu")
	)
	(gr_line
		(start 170.349418 -32.91459)
		(end 170.85437 -33.255204)
		(stroke
			(width 0.0508)
			(type default)
		)
		(layer "In5.Cu")
	)
	(gr_line
		(start 170.45178 -33.58134)
		(end 170.712892 -33.53054)
		(stroke
			(width 0.0508)
			(type default)
		)
		(layer "In5.Cu")
	)
	(gr_line
		(start 170.769026 -84.046314)
		(end 170.789854 -84.060538)
		(stroke
			(width 0.06985)
			(type default)
		)
		(layer "In5.Cu")
	)
	(gr_line
		(start 170.789854 -84.060538)
		(end 170.815254 -84.065618)
		(stroke
			(width 0.06985)
			(type default)
		)
		(layer "In5.Cu")
	)
	(gr_line
		(start 170.969686 -33.703514)
		(end 171.020486 -33.96488)
		(stroke
			(width 0.0508)
			(type default)
		)
		(layer "In5.Cu")
	)
	(gr_line
		(start 171.020486 -33.96488)
		(end 171.272962 -34.135314)
		(stroke
			(width 0.0508)
			(type default)
		)
		(layer "In5.Cu")
	)
	(gr_line
		(start 171.160948 -87.358728)
		(end 171.186602 -87.363554)
		(stroke
			(width 0.06985)
			(type default)
		)
		(layer "In5.Cu")
	)
	(gr_line
		(start 171.171616 -33.469072)
		(end 171.675298 -33.808924)
		(stroke
			(width 0.0508)
			(type default)
		)
		(layer "In5.Cu")
	)
	(gr_line
		(start 171.186602 -87.363554)
		(end 171.208192 -87.378286)
		(stroke
			(width 0.06985)
			(type default)
		)
		(layer "In5.Cu")
	)
	(gr_line
		(start 171.272962 -34.135314)
		(end 171.534328 -34.084514)
		(stroke
			(width 0.0508)
			(type default)
		)
		(layer "In5.Cu")
	)
	(gr_line
		(start 171.296838 -89.362534)
		(end 171.344082 -89.605866)
		(stroke
			(width 0.06985)
			(type default)
		)
		(layer "In5.Cu")
	)
	(gr_line
		(start 171.316142 -32.45358)
		(end 171.368212 -32.714438)
		(stroke
			(width 0.0508)
			(type default)
		)
		(layer "In5.Cu")
	)
	(gr_line
		(start 171.344082 -89.605866)
		(end 171.691554 -89.840308)
		(stroke
			(width 0.06985)
			(type default)
		)
		(layer "In5.Cu")
	)
	(gr_line
		(start 171.368212 -32.714438)
		(end 171.621704 -32.883602)
		(stroke
			(width 0.0508)
			(type default)
		)
		(layer "In5.Cu")
	)
	(gr_line
		(start 171.515024 -89.10828)
		(end 172.088302 -89.495122)
		(stroke
			(width 0.06985)
			(type default)
		)
		(layer "In5.Cu")
	)
	(gr_line
		(start 171.518834 -32.2199)
		(end 172.020484 -32.554418)
		(stroke
			(width 0.0508)
			(type default)
		)
		(layer "In5.Cu")
	)
	(gr_line
		(start 171.621704 -32.883602)
		(end 171.882816 -32.831278)
		(stroke
			(width 0.0508)
			(type default)
		)
		(layer "In5.Cu")
	)
	(gr_line
		(start 171.691554 -89.840308)
		(end 171.934886 -89.793064)
		(stroke
			(width 0.06985)
			(type default)
		)
		(layer "In5.Cu")
	)
	(gr_line
		(start 171.791122 -34.257742)
		(end 171.841668 -34.5186)
		(stroke
			(width 0.0508)
			(type default)
		)
		(layer "In5.Cu")
	)
	(gr_line
		(start 171.841668 -34.5186)
		(end 172.094398 -34.689034)
		(stroke
			(width 0.0508)
			(type default)
		)
		(layer "In5.Cu")
	)
	(gr_line
		(start 171.955714 -88.283542)
		(end 172.002958 -88.527128)
		(stroke
			(width 0.06985)
			(type default)
		)
		(layer "In5.Cu")
	)
	(gr_line
		(start 171.994068 -34.024062)
		(end 172.496988 -34.363152)
		(stroke
			(width 0.0508)
			(type default)
		)
		(layer "In5.Cu")
	)
	(gr_line
		(start 172.002958 -88.527128)
		(end 172.35043 -88.761316)
		(stroke
			(width 0.06985)
			(type default)
		)
		(layer "In5.Cu")
	)
	(gr_line
		(start 172.094398 -34.689034)
		(end 172.35551 -34.638488)
		(stroke
			(width 0.0508)
			(type default)
		)
		(layer "In5.Cu")
	)
	(gr_line
		(start 172.140372 -33.002982)
		(end 172.192442 -33.26384)
		(stroke
			(width 0.0508)
			(type default)
		)
		(layer "In5.Cu")
	)
	(gr_line
		(start 172.173646 -88.029542)
		(end 172.749464 -88.417654)
		(stroke
			(width 0.06985)
			(type default)
		)
		(layer "In5.Cu")
	)
	(gr_line
		(start 172.192442 -33.26384)
		(end 172.445934 -33.433004)
		(stroke
			(width 0.0508)
			(type default)
		)
		(layer "In5.Cu")
	)
	(gr_line
		(start 172.286168 -90.030046)
		(end 172.333666 -90.273378)
		(stroke
			(width 0.06985)
			(type default)
		)
		(layer "In5.Cu")
	)
	(gr_line
		(start 172.333666 -90.273378)
		(end 172.681138 -90.50782)
		(stroke
			(width 0.06985)
			(type default)
		)
		(layer "In5.Cu")
	)
	(gr_line
		(start 172.343318 -32.769556)
		(end 172.845476 -33.104328)
		(stroke
			(width 0.0508)
			(type default)
		)
		(layer "In5.Cu")
	)
	(gr_line
		(start 172.35043 -88.761316)
		(end 172.594016 -88.714072)
		(stroke
			(width 0.06985)
			(type default)
		)
		(layer "In5.Cu")
	)
	(gr_line
		(start 172.445934 -33.433004)
		(end 172.707046 -33.38068)
		(stroke
			(width 0.0508)
			(type default)
		)
		(layer "In5.Cu")
	)
	(gr_line
		(start 172.491146 -94.562422)
		(end 172.51299 -94.577408)
		(stroke
			(width 0.06985)
			(type default)
		)
		(layer "In5.Cu")
	)
	(gr_line
		(start 172.503846 -89.775538)
		(end 173.078394 -90.163142)
		(stroke
			(width 0.06985)
			(type default)
		)
		(layer "In5.Cu")
	)
	(gr_line
		(start 172.51299 -94.577408)
		(end 172.539406 -94.582234)
		(stroke
			(width 0.06985)
			(type default)
		)
		(layer "In5.Cu")
	)
	(gr_line
		(start 172.591476 -31.743142)
		(end 172.643546 -32.004254)
		(stroke
			(width 0.0508)
			(type default)
		)
		(layer "In5.Cu")
	)
	(gr_line
		(start 172.612304 -34.811462)
		(end 172.66285 -35.072574)
		(stroke
			(width 0.0508)
			(type default)
		)
		(layer "In5.Cu")
	)
	(gr_line
		(start 172.643546 -32.004254)
		(end 172.897292 -32.173164)
		(stroke
			(width 0.0508)
			(type default)
		)
		(layer "In5.Cu")
	)
	(gr_line
		(start 172.65396 -86.754462)
		(end 172.679614 -86.759288)
		(stroke
			(width 0.06985)
			(type default)
		)
		(layer "In5.Cu")
	)
	(gr_line
		(start 172.66285 -35.072574)
		(end 172.91558 -35.243008)
		(stroke
			(width 0.0508)
			(type default)
		)
		(layer "In5.Cu")
	)
	(gr_line
		(start 172.679614 -86.759288)
		(end 172.701204 -86.77402)
		(stroke
			(width 0.06985)
			(type default)
		)
		(layer "In5.Cu")
	)
	(gr_line
		(start 172.681138 -90.50782)
		(end 172.92447 -90.460576)
		(stroke
			(width 0.06985)
			(type default)
		)
		(layer "In5.Cu")
	)
	(gr_line
		(start 172.79239 -31.507938)
		(end 173.297596 -31.844742)
		(stroke
			(width 0.0508)
			(type default)
		)
		(layer "In5.Cu")
	)
	(gr_line
		(start 172.814234 -34.57702)
		(end 173.31944 -34.917888)
		(stroke
			(width 0.0508)
			(type default)
		)
		(layer "In5.Cu")
	)
	(gr_line
		(start 172.897292 -32.173164)
		(end 173.15815 -32.121094)
		(stroke
			(width 0.0508)
			(type default)
		)
		(layer "In5.Cu")
	)
	(gr_line
		(start 172.91558 -35.243008)
		(end 173.176692 -35.192208)
		(stroke
			(width 0.0508)
			(type default)
		)
		(layer "In5.Cu")
	)
	(gr_line
		(start 172.945552 -88.951308)
		(end 172.992542 -89.19464)
		(stroke
			(width 0.06985)
			(type default)
		)
		(layer "In5.Cu")
	)
	(gr_line
		(start 172.964602 -33.552384)
		(end 173.016672 -33.813496)
		(stroke
			(width 0.0508)
			(type default)
		)
		(layer "In5.Cu")
	)
	(gr_line
		(start 172.992542 -89.19464)
		(end 173.340014 -89.429082)
		(stroke
			(width 0.06985)
			(type default)
		)
		(layer "In5.Cu")
	)
	(gr_line
		(start 173.016672 -33.813496)
		(end 173.270164 -33.982406)
		(stroke
			(width 0.0508)
			(type default)
		)
		(layer "In5.Cu")
	)
	(gr_line
		(start 173.162976 -88.696546)
		(end 173.738794 -89.084912)
		(stroke
			(width 0.06985)
			(type default)
		)
		(layer "In5.Cu")
	)
	(gr_line
		(start 173.167548 -33.318958)
		(end 173.669706 -33.65373)
		(stroke
			(width 0.0508)
			(type default)
		)
		(layer "In5.Cu")
	)
	(gr_line
		(start 173.270164 -33.982406)
		(end 173.531022 -33.930336)
		(stroke
			(width 0.0508)
			(type default)
		)
		(layer "In5.Cu")
	)
	(gr_line
		(start 173.308264 -93.403674)
		(end 173.329854 -93.418406)
		(stroke
			(width 0.06985)
			(type default)
		)
		(layer "In5.Cu")
	)
	(gr_line
		(start 173.329854 -93.418406)
		(end 173.355508 -93.423232)
		(stroke
			(width 0.06985)
			(type default)
		)
		(layer "In5.Cu")
	)
	(gr_line
		(start 173.340014 -89.429082)
		(end 173.5836 -89.381584)
		(stroke
			(width 0.06985)
			(type default)
		)
		(layer "In5.Cu")
	)
	(gr_line
		(start 173.41342 -35.34918)
		(end 173.432724 -35.362134)
		(stroke
			(width 0.0508)
			(type default)
		)
		(layer "In5.Cu")
	)
	(gr_line
		(start 173.415452 -32.292544)
		(end 173.467776 -32.553656)
		(stroke
			(width 0.0508)
			(type default)
		)
		(layer "In5.Cu")
	)
	(gr_line
		(start 173.432724 -35.362134)
		(end 173.45533 -35.366706)
		(stroke
			(width 0.0508)
			(type default)
		)
		(layer "In5.Cu")
	)
	(gr_line
		(start 173.467776 -32.553656)
		(end 173.721522 -32.72282)
		(stroke
			(width 0.0508)
			(type default)
		)
		(layer "In5.Cu")
	)
	(gr_line
		(start 173.571154 -87.76208)
		(end 173.618144 -88.005412)
		(stroke
			(width 0.06985)
			(type default)
		)
		(layer "In5.Cu")
	)
	(gr_line
		(start 173.616366 -32.05734)
		(end 174.122588 -32.394906)
		(stroke
			(width 0.0508)
			(type default)
		)
		(layer "In5.Cu")
	)
	(gr_line
		(start 173.618144 -88.005412)
		(end 173.965616 -88.2396)
		(stroke
			(width 0.06985)
			(type default)
		)
		(layer "In5.Cu")
	)
	(gr_line
		(start 173.721522 -32.72282)
		(end 173.98238 -32.67075)
		(stroke
			(width 0.0508)
			(type default)
		)
		(layer "In5.Cu")
	)
	(gr_line
		(start 173.788832 -34.10204)
		(end 173.840902 -34.362898)
		(stroke
			(width 0.0508)
			(type default)
		)
		(layer "In5.Cu")
	)
	(gr_line
		(start 173.789594 -87.50808)
		(end 174.364142 -87.895684)
		(stroke
			(width 0.06985)
			(type default)
		)
		(layer "In5.Cu")
	)
	(gr_line
		(start 173.840902 -34.362898)
		(end 174.094394 -34.531808)
		(stroke
			(width 0.0508)
			(type default)
		)
		(layer "In5.Cu")
	)
	(gr_line
		(start 173.91634 -92.640658)
		(end 173.93793 -92.65539)
		(stroke
			(width 0.06985)
			(type default)
		)
		(layer "In5.Cu")
	)
	(gr_line
		(start 173.93793 -92.65539)
		(end 173.963838 -92.660216)
		(stroke
			(width 0.06985)
			(type default)
		)
		(layer "In5.Cu")
	)
	(gr_line
		(start 173.965616 -88.2396)
		(end 174.209202 -88.192356)
		(stroke
			(width 0.06985)
			(type default)
		)
		(layer "In5.Cu")
	)
	(gr_line
		(start 174.094394 -34.531808)
		(end 174.355252 -34.479738)
		(stroke
			(width 0.0508)
			(type default)
		)
		(layer "In5.Cu")
	)
	(gr_line
		(start 174.212758 -34.01568)
		(end 174.49419 -34.203132)
		(stroke
			(width 0.0508)
			(type default)
		)
		(layer "In5.Cu")
	)
	(gr_line
		(start 174.239936 -32.8422)
		(end 174.292006 -33.103058)
		(stroke
			(width 0.0508)
			(type default)
		)
		(layer "In5.Cu")
	)
	(gr_line
		(start 174.292006 -33.103058)
		(end 174.545752 -33.272222)
		(stroke
			(width 0.0508)
			(type default)
		)
		(layer "In5.Cu")
	)
	(gr_line
		(start 174.44085 -32.606996)
		(end 174.946056 -32.9438)
		(stroke
			(width 0.0508)
			(type default)
		)
		(layer "In5.Cu")
	)
	(gr_line
		(start 174.452026 -86.57336)
		(end 174.590456 -86.779354)
		(stroke
			(width 0.06985)
			(type default)
		)
		(layer "In5.Cu")
	)
	(gr_line
		(start 174.545752 -33.272222)
		(end 174.80661 -33.220152)
		(stroke
			(width 0.0508)
			(type default)
		)
		(layer "In5.Cu")
	)
	(gr_line
		(start 174.551848 -86.253574)
		(end 175.234346 -86.38794)
		(stroke
			(width 0.06985)
			(type default)
		)
		(layer "In5.Cu")
	)
	(gr_line
		(start 174.560738 -88.429592)
		(end 174.607982 -88.672924)
		(stroke
			(width 0.06985)
			(type default)
		)
		(layer "In5.Cu")
	)
	(gr_line
		(start 174.590456 -86.779354)
		(end 175.001682 -86.860126)
		(stroke
			(width 0.06985)
			(type default)
		)
		(layer "In5.Cu")
	)
	(gr_line
		(start 174.594266 -34.635948)
		(end 174.6123 -34.64814)
		(stroke
			(width 0.0508)
			(type default)
		)
		(layer "In5.Cu")
	)
	(gr_line
		(start 174.607982 -88.672924)
		(end 174.955454 -88.907366)
		(stroke
			(width 0.06985)
			(type default)
		)
		(layer "In5.Cu")
	)
	(gr_line
		(start 174.6123 -34.64814)
		(end 174.633636 -34.652204)
		(stroke
			(width 0.0508)
			(type default)
		)
		(layer "In5.Cu")
	)
	(gr_line
		(start 174.622968 -90.07983)
		(end 174.645574 -90.09507)
		(stroke
			(width 0.06985)
			(type default)
		)
		(layer "In5.Cu")
	)
	(gr_line
		(start 174.645574 -90.09507)
		(end 174.672244 -90.100404)
		(stroke
			(width 0.06985)
			(type default)
		)
		(layer "In5.Cu")
	)
	(gr_line
		(start 174.779432 -88.175846)
		(end 175.35271 -88.562688)
		(stroke
			(width 0.06985)
			(type default)
		)
		(layer "In5.Cu")
	)
	(gr_line
		(start 174.955454 -88.907366)
		(end 175.198786 -88.860122)
		(stroke
			(width 0.06985)
			(type default)
		)
		(layer "In5.Cu")
	)
	(gr_line
		(start 174.957486 -91.82862)
		(end 174.978314 -91.842844)
		(stroke
			(width 0.06985)
			(type default)
		)
		(layer "In5.Cu")
	)
	(gr_line
		(start 174.978314 -91.842844)
		(end 175.003968 -91.847924)
		(stroke
			(width 0.06985)
			(type default)
		)
		(layer "In5.Cu")
	)
	(gr_line
		(start 175.001682 -86.860126)
		(end 175.207422 -86.72195)
		(stroke
			(width 0.06985)
			(type default)
		)
		(layer "In5.Cu")
	)
	(gr_line
		(start 175.063912 -33.391602)
		(end 175.116236 -33.652714)
		(stroke
			(width 0.0508)
			(type default)
		)
		(layer "In5.Cu")
	)
	(gr_line
		(start 175.116236 -33.652714)
		(end 175.369728 -33.821624)
		(stroke
			(width 0.0508)
			(type default)
		)
		(layer "In5.Cu")
	)
	(gr_line
		(start 175.26508 -33.156652)
		(end 175.769524 -33.492948)
		(stroke
			(width 0.0508)
			(type default)
		)
		(layer "In5.Cu")
	)
	(gr_line
		(start 175.369728 -33.821624)
		(end 175.630586 -33.769554)
		(stroke
			(width 0.0508)
			(type default)
		)
		(layer "In5.Cu")
	)
	(gr_line
		(start 175.623474 -86.803738)
		(end 175.76165 -87.009732)
		(stroke
			(width 0.06985)
			(type default)
		)
		(layer "In5.Cu")
	)
	(gr_line
		(start 175.724058 -86.484206)
		(end 176.405286 -86.618318)
		(stroke
			(width 0.06985)
			(type default)
		)
		(layer "In5.Cu")
	)
	(gr_line
		(start 175.76165 -87.009732)
		(end 176.172876 -87.090504)
		(stroke
			(width 0.06985)
			(type default)
		)
		(layer "In5.Cu")
	)
	(gr_line
		(start 175.8696 -33.925764)
		(end 175.887634 -33.937956)
		(stroke
			(width 0.0508)
			(type default)
		)
		(layer "In5.Cu")
	)
	(gr_line
		(start 175.887634 -33.937956)
		(end 175.90897 -33.94202)
		(stroke
			(width 0.0508)
			(type default)
		)
		(layer "In5.Cu")
	)
	(gr_line
		(start 176.172876 -87.090504)
		(end 176.378616 -86.952328)
		(stroke
			(width 0.06985)
			(type default)
		)
		(layer "In5.Cu")
	)
	(gr_line
		(start 176.250854 -89.566496)
		(end 176.271682 -89.58072)
		(stroke
			(width 0.06985)
			(type default)
		)
		(layer "In5.Cu")
	)
	(gr_line
		(start 176.271682 -89.58072)
		(end 176.297336 -89.5858)
		(stroke
			(width 0.06985)
			(type default)
		)
		(layer "In5.Cu")
	)
	(gr_line
		(start 179.250086 -30.500066)
		(end 179.505356 -30.023816)
		(stroke
			(width 0.0508)
			(type default)
		)
		(layer "In5.Cu")
	)
	(gr_line
		(start 179.250086 -26.699972)
		(end 179.505356 -26.223722)
		(stroke
			(width 0.0508)
			(type default)
		)
		(layer "In5.Cu")
	)
	(gr_line
		(start 179.505356 -30.023816)
		(end 179.639468 -29.98343)
		(stroke
			(width 0.0508)
			(type default)
		)
		(layer "In5.Cu")
	)
	(gr_line
		(start 179.505356 -26.223722)
		(end 179.639468 -26.183336)
		(stroke
			(width 0.0508)
			(type default)
		)
		(layer "In5.Cu")
	)
	(gr_line
		(start 179.744878 -29.576268)
		(end 179.785772 -29.71038)
		(stroke
			(width 0.0508)
			(type default)
		)
		(layer "In5.Cu")
	)
	(gr_line
		(start 179.744878 -29.576268)
		(end 179.999894 -29.100018)
		(stroke
			(width 0.0508)
			(type default)
		)
		(layer "In5.Cu")
	)
	(gr_line
		(start 179.744878 -25.776174)
		(end 179.785772 -25.910286)
		(stroke
			(width 0.0508)
			(type default)
		)
		(layer "In5.Cu")
	)
	(gr_line
		(start 179.744878 -25.776174)
		(end 179.999894 -25.299924)
		(stroke
			(width 0.0508)
			(type default)
		)
		(layer "In5.Cu")
	)
	(gr_line
		(start 179.909216 -29.779214)
		(end 179.916328 -29.78277)
		(stroke
			(width 0.0508)
			(type default)
		)
		(layer "In5.Cu")
	)
	(gr_line
		(start 179.909724 -25.97912)
		(end 179.916328 -25.982676)
		(stroke
			(width 0.0508)
			(type default)
		)
		(layer "In5.Cu")
	)
	(gr_line
		(start 179.916328 -29.78277)
		(end 179.922678 -29.78912)
		(stroke
			(width 0.0508)
			(type default)
		)
		(layer "In5.Cu")
	)
	(gr_line
		(start 179.916328 -25.982676)
		(end 179.92217 -25.988518)
		(stroke
			(width 0.0508)
			(type default)
		)
		(layer "In5.Cu")
	)
	(gr_line
		(start 180.14696 -30.013402)
		(end 180.20919 -30.075632)
		(stroke
			(width 0.0508)
			(type default)
		)
		(layer "In5.Cu")
	)
	(gr_line
		(start 180.764434 -31.732474)
		(end 180.98008 -31.94812)
		(stroke
			(width 0.0508)
			(type default)
		)
		(layer "In5.Cu")
	)
	(gr_line
		(start 180.764434 -31.466282)
		(end 180.764434 -31.732474)
		(stroke
			(width 0.0508)
			(type default)
		)
		(layer "In5.Cu")
	)
	(gr_line
		(start 180.98008 -31.94812)
		(end 181.246272 -31.94812)
		(stroke
			(width 0.0508)
			(type default)
		)
		(layer "In5.Cu")
	)
	(gr_line
		(start 181.197504 -31.464758)
		(end 181.439312 -31.706566)
		(stroke
			(width 0.0508)
			(type default)
		)
		(layer "In5.Cu")
	)
	(gr_line
		(start 181.29631 -28.13431)
		(end 181.349396 -28.144978)
		(stroke
			(width 0.0508)
			(type default)
		)
		(layer "In5.Cu")
	)
	(gr_line
		(start 181.464966 -32.433006)
		(end 181.680358 -32.648398)
		(stroke
			(width 0.0508)
			(type default)
		)
		(layer "In5.Cu")
	)
	(gr_line
		(start 181.464966 -32.166814)
		(end 181.464966 -32.433006)
		(stroke
			(width 0.0508)
			(type default)
		)
		(layer "In5.Cu")
	)
	(gr_line
		(start 181.500018 -30.500066)
		(end 181.755288 -30.023562)
		(stroke
			(width 0.0508)
			(type default)
		)
		(layer "In5.Cu")
	)
	(gr_line
		(start 181.500018 -26.699972)
		(end 181.755288 -26.223468)
		(stroke
			(width 0.0508)
			(type default)
		)
		(layer "In5.Cu")
	)
	(gr_line
		(start 181.680358 -32.648398)
		(end 181.94655 -32.648398)
		(stroke
			(width 0.0508)
			(type default)
		)
		(layer "In5.Cu")
	)
	(gr_line
		(start 181.707536 -31.97479)
		(end 182.138574 -32.405828)
		(stroke
			(width 0.0508)
			(type default)
		)
		(layer "In5.Cu")
	)
	(gr_line
		(start 181.755288 -30.023562)
		(end 181.889654 -29.983176)
		(stroke
			(width 0.0508)
			(type default)
		)
		(layer "In5.Cu")
	)
	(gr_line
		(start 181.755288 -26.223468)
		(end 181.889654 -26.183082)
		(stroke
			(width 0.0508)
			(type default)
		)
		(layer "In5.Cu")
	)
	(gr_line
		(start 181.962044 -30.019244)
		(end 181.96306 -30.019752)
		(stroke
			(width 0.0508)
			(type default)
		)
		(layer "In5.Cu")
	)
	(gr_line
		(start 181.96306 -30.019752)
		(end 181.97703 -30.027118)
		(stroke
			(width 0.0508)
			(type default)
		)
		(layer "In5.Cu")
	)
	(gr_line
		(start 181.97703 -30.027118)
		(end 181.977792 -30.027626)
		(stroke
			(width 0.0508)
			(type default)
		)
		(layer "In5.Cu")
	)
	(gr_line
		(start 181.995064 -29.576014)
		(end 182.035958 -29.710126)
		(stroke
			(width 0.0508)
			(type default)
		)
		(layer "In5.Cu")
	)
	(gr_line
		(start 181.995064 -29.576014)
		(end 182.25008 -29.100018)
		(stroke
			(width 0.0508)
			(type default)
		)
		(layer "In5.Cu")
	)
	(gr_line
		(start 181.995064 -25.77592)
		(end 182.035958 -25.910032)
		(stroke
			(width 0.0508)
			(type default)
		)
		(layer "In5.Cu")
	)
	(gr_line
		(start 181.995064 -25.77592)
		(end 182.25008 -25.299924)
		(stroke
			(width 0.0508)
			(type default)
		)
		(layer "In5.Cu")
	)
	(gr_line
		(start 182.106062 -29.750512)
		(end 182.106824 -29.75102)
		(stroke
			(width 0.0508)
			(type default)
		)
		(layer "In5.Cu")
	)
	(gr_line
		(start 182.106824 -29.75102)
		(end 182.110888 -29.753052)
		(stroke
			(width 0.0508)
			(type default)
		)
		(layer "In5.Cu")
	)
	(gr_line
		(start 182.11419 -29.75483)
		(end 182.125366 -29.760672)
		(stroke
			(width 0.0508)
			(type default)
		)
		(layer "In5.Cu")
	)
	(gr_line
		(start 182.15864 -29.778452)
		(end 182.16626 -29.782516)
		(stroke
			(width 0.0508)
			(type default)
		)
		(layer "In5.Cu")
	)
	(gr_line
		(start 182.158894 -25.978612)
		(end 182.16626 -25.982422)
		(stroke
			(width 0.0508)
			(type default)
		)
		(layer "In5.Cu")
	)
	(gr_line
		(start 182.16626 -29.782516)
		(end 182.17261 -29.788866)
		(stroke
			(width 0.0508)
			(type default)
		)
		(layer "In5.Cu")
	)
	(gr_line
		(start 182.16626 -25.982422)
		(end 182.172356 -25.988518)
		(stroke
			(width 0.0508)
			(type default)
		)
		(layer "In5.Cu")
	)
	(gr_line
		(start 182.959502 -28.155646)
		(end 182.981092 -28.159964)
		(stroke
			(width 0.0508)
			(type default)
		)
		(layer "In5.Cu")
	)
	(gr_line
		(start 182.975758 -90.902028)
		(end 183.000396 -90.906854)
		(stroke
			(width 0.06985)
			(type default)
		)
		(layer "In5.Cu")
	)
	(gr_line
		(start 182.981092 -28.159964)
		(end 182.999126 -28.172156)
		(stroke
			(width 0.0508)
			(type default)
		)
		(layer "In5.Cu")
	)
	(gr_line
		(start 183.000396 -90.906854)
		(end 183.025796 -90.901774)
		(stroke
			(width 0.06985)
			(type default)
		)
		(layer "In5.Cu")
	)
	(gr_line
		(start 183.02732 -91.755468)
		(end 183.051704 -91.760294)
		(stroke
			(width 0.06985)
			(type default)
		)
		(layer "In5.Cu")
	)
	(gr_line
		(start 183.051704 -91.760294)
		(end 183.076596 -91.755214)
		(stroke
			(width 0.06985)
			(type default)
		)
		(layer "In5.Cu")
	)
	(gr_line
		(start 183.586882 -34.285682)
		(end 183.641492 -34.296604)
		(stroke
			(width 0.0508)
			(type default)
		)
		(layer "In5.Cu")
	)
	(gr_line
		(start 183.715406 -31.443676)
		(end 183.767476 -31.704534)
		(stroke
			(width 0.0508)
			(type default)
		)
		(layer "In5.Cu")
	)
	(gr_line
		(start 183.767476 -31.704534)
		(end 184.021222 -31.873444)
		(stroke
			(width 0.0508)
			(type default)
		)
		(layer "In5.Cu")
	)
	(gr_line
		(start 183.91632 -31.208472)
		(end 184.421272 -31.545022)
		(stroke
			(width 0.0508)
			(type default)
		)
		(layer "In5.Cu")
	)
	(gr_line
		(start 184.021222 -31.873444)
		(end 184.281826 -31.821374)
		(stroke
			(width 0.0508)
			(type default)
		)
		(layer "In5.Cu")
	)
	(gr_line
		(start 184.34304 -34.439098)
		(end 184.490614 -34.660586)
		(stroke
			(width 0.0508)
			(type default)
		)
		(layer "In5.Cu")
	)
	(gr_line
		(start 184.438544 -34.144712)
		(end 185.036714 -34.264346)
		(stroke
			(width 0.0508)
			(type default)
		)
		(layer "In5.Cu")
	)
	(gr_line
		(start 184.490614 -34.660586)
		(end 184.789572 -34.720276)
		(stroke
			(width 0.0508)
			(type default)
		)
		(layer "In5.Cu")
	)
	(gr_line
		(start 184.789572 -34.720276)
		(end 185.011314 -34.572702)
		(stroke
			(width 0.0508)
			(type default)
		)
		(layer "In5.Cu")
	)
	(gr_line
		(start 185.110628 -94.83217)
		(end 185.13552 -94.836996)
		(stroke
			(width 0.06985)
			(type default)
		)
		(layer "In5.Cu")
	)
	(gr_line
		(start 185.13552 -94.836996)
		(end 185.161174 -94.831916)
		(stroke
			(width 0.06985)
			(type default)
		)
		(layer "In5.Cu")
	)
	(gr_line
		(start 185.188606 -93.858842)
		(end 185.21299 -93.863668)
		(stroke
			(width 0.06985)
			(type default)
		)
		(layer "In5.Cu")
	)
	(gr_line
		(start 185.21299 -93.863668)
		(end 185.23839 -93.858588)
		(stroke
			(width 0.06985)
			(type default)
		)
		(layer "In5.Cu")
	)
	(gr_line
		(start 185.241946 -97.001584)
		(end 185.259726 -97.00514)
		(stroke
			(width 0.06985)
			(type default)
		)
		(layer "In5.Cu")
	)
	(gr_line
		(start 185.259726 -97.005394)
		(end 185.262774 -97.005902)
		(stroke
			(width 0.06985)
			(type default)
		)
		(layer "In5.Cu")
	)
	(gr_line
		(start 185.259726 -97.00514)
		(end 185.259726 -97.005394)
		(stroke
			(width 0.06985)
			(type default)
		)
		(layer "In5.Cu")
	)
	(gr_line
		(start 185.262774 -97.005902)
		(end 185.285634 -97.001584)
		(stroke
			(width 0.06985)
			(type default)
		)
		(layer "In5.Cu")
	)
	(gr_line
		(start 185.264298 -95.738442)
		(end 185.28919 -95.743268)
		(stroke
			(width 0.06985)
			(type default)
		)
		(layer "In5.Cu")
	)
	(gr_line
		(start 185.277506 -38.903656)
		(end 185.42508 -39.12489)
		(stroke
			(width 0.0508)
			(type default)
		)
		(layer "In5.Cu")
	)
	(gr_line
		(start 185.28919 -95.743268)
		(end 185.314844 -95.738188)
		(stroke
			(width 0.06985)
			(type default)
		)
		(layer "In5.Cu")
	)
	(gr_line
		(start 185.314336 -34.633408)
		(end 185.462164 -34.854642)
		(stroke
			(width 0.0508)
			(type default)
		)
		(layer "In5.Cu")
	)
	(gr_line
		(start 185.370724 -38.608508)
		(end 185.97118 -38.728396)
		(stroke
			(width 0.0508)
			(type default)
		)
		(layer "In5.Cu")
	)
	(gr_line
		(start 185.410094 -34.339022)
		(end 186.006232 -34.458402)
		(stroke
			(width 0.0508)
			(type default)
		)
		(layer "In5.Cu")
	)
	(gr_line
		(start 185.42508 -39.12489)
		(end 185.724038 -39.18458)
		(stroke
			(width 0.0508)
			(type default)
		)
		(layer "In5.Cu")
	)
	(gr_line
		(start 185.462164 -34.854642)
		(end 185.760868 -34.914586)
		(stroke
			(width 0.0508)
			(type default)
		)
		(layer "In5.Cu")
	)
	(gr_line
		(start 185.724038 -39.18458)
		(end 185.945018 -39.037006)
		(stroke
			(width 0.0508)
			(type default)
		)
		(layer "In5.Cu")
	)
	(gr_line
		(start 185.760868 -34.914586)
		(end 185.982356 -34.767012)
		(stroke
			(width 0.0508)
			(type default)
		)
		(layer "In5.Cu")
	)
	(gr_line
		(start 186.135772 -87.129366)
		(end 186.16041 -87.134446)
		(stroke
			(width 0.06985)
			(type default)
		)
		(layer "In5.Cu")
	)
	(gr_line
		(start 186.144154 -90.805)
		(end 186.168792 -90.79992)
		(stroke
			(width 0.06985)
			(type default)
		)
		(layer "In5.Cu")
	)
	(gr_line
		(start 186.144662 -89.941146)
		(end 186.1693 -89.936066)
		(stroke
			(width 0.06985)
			(type default)
		)
		(layer "In5.Cu")
	)
	(gr_line
		(start 186.16041 -87.134446)
		(end 186.185048 -87.129366)
		(stroke
			(width 0.06985)
			(type default)
		)
		(layer "In5.Cu")
	)
	(gr_line
		(start 186.168792 -90.79992)
		(end 186.19343 -90.805)
		(stroke
			(width 0.06985)
			(type default)
		)
		(layer "In5.Cu")
	)
	(gr_line
		(start 186.249056 -39.097458)
		(end 186.39663 -39.318692)
		(stroke
			(width 0.0508)
			(type default)
		)
		(layer "In5.Cu")
	)
	(gr_line
		(start 186.285886 -34.827718)
		(end 186.43346 -35.048952)
		(stroke
			(width 0.0508)
			(type default)
		)
		(layer "In5.Cu")
	)
	(gr_line
		(start 186.342274 -38.80231)
		(end 186.94273 -38.922198)
		(stroke
			(width 0.0508)
			(type default)
		)
		(layer "In5.Cu")
	)
	(gr_line
		(start 186.380628 -34.533078)
		(end 186.978798 -34.652712)
		(stroke
			(width 0.0508)
			(type default)
		)
		(layer "In5.Cu")
	)
	(gr_line
		(start 186.39663 -39.318692)
		(end 186.695334 -39.378382)
		(stroke
			(width 0.0508)
			(type default)
		)
		(layer "In5.Cu")
	)
	(gr_line
		(start 186.43346 -35.048952)
		(end 186.732418 -35.108896)
		(stroke
			(width 0.0508)
			(type default)
		)
		(layer "In5.Cu")
	)
	(gr_line
		(start 186.695334 -39.378382)
		(end 186.916822 -39.230808)
		(stroke
			(width 0.0508)
			(type default)
		)
		(layer "In5.Cu")
	)
	(gr_line
		(start 186.732418 -35.108896)
		(end 186.953652 -34.961068)
		(stroke
			(width 0.0508)
			(type default)
		)
		(layer "In5.Cu")
	)
	(gr_line
		(start 187.220098 -39.29126)
		(end 187.367926 -39.512494)
		(stroke
			(width 0.0508)
			(type default)
		)
		(layer "In5.Cu")
	)
	(gr_line
		(start 187.31484 -38.99662)
		(end 187.913264 -39.116)
		(stroke
			(width 0.0508)
			(type default)
		)
		(layer "In5.Cu")
	)
	(gr_line
		(start 187.367926 -39.512494)
		(end 187.666884 -39.572184)
		(stroke
			(width 0.0508)
			(type default)
		)
		(layer "In5.Cu")
	)
	(gr_line
		(start 187.666884 -39.572184)
		(end 187.888118 -39.424356)
		(stroke
			(width 0.0508)
			(type default)
		)
		(layer "In5.Cu")
	)
	(gr_line
		(start 187.736226 -34.12109)
		(end 187.75426 -34.133282)
		(stroke
			(width 0.0508)
			(type default)
		)
		(layer "In5.Cu")
	)
	(gr_line
		(start 187.75426 -34.133282)
		(end 187.77585 -34.1376)
		(stroke
			(width 0.0508)
			(type default)
		)
		(layer "In5.Cu")
	)
	(gr_line
		(start 188.054996 -34.195766)
		(end 188.20257 -34.417254)
		(stroke
			(width 0.0508)
			(type default)
		)
		(layer "In5.Cu")
	)
	(gr_line
		(start 188.1505 -33.90138)
		(end 188.74867 -34.021014)
		(stroke
			(width 0.0508)
			(type default)
		)
		(layer "In5.Cu")
	)
	(gr_line
		(start 188.20257 -34.417254)
		(end 188.501528 -34.476944)
		(stroke
			(width 0.0508)
			(type default)
		)
		(layer "In5.Cu")
	)
	(gr_line
		(start 188.501528 -34.476944)
		(end 188.722762 -34.32937)
		(stroke
			(width 0.0508)
			(type default)
		)
		(layer "In5.Cu")
	)
	(gr_line
		(start 189.026292 -34.390076)
		(end 189.173866 -34.611564)
		(stroke
			(width 0.0508)
			(type default)
		)
		(layer "In5.Cu")
	)
	(gr_line
		(start 189.122812 -34.096198)
		(end 189.720728 -34.215578)
		(stroke
			(width 0.0508)
			(type default)
		)
		(layer "In5.Cu")
	)
	(gr_line
		(start 189.173866 -34.611564)
		(end 189.472824 -34.671254)
		(stroke
			(width 0.0508)
			(type default)
		)
		(layer "In5.Cu")
	)
	(gr_line
		(start 189.472824 -34.671254)
		(end 189.694566 -34.52368)
		(stroke
			(width 0.0508)
			(type default)
		)
		(layer "In5.Cu")
	)
	(gr_line
		(start 189.68212 -86.42985)
		(end 189.74054 -86.418166)
		(stroke
			(width 0.06985)
			(type default)
		)
		(layer "In5.Cu")
	)
	(gr_arc
		(start 189.945264 -84.515198)
		(mid 189.74807 -84.433555)
		(end 189.550802 -84.515198)
		(stroke
			(width 0.06985)
			(type default)
		)
		(layer "In5.Cu")
	)
	(gr_line
		(start 189.997588 -34.584386)
		(end 190.145416 -34.80562)
		(stroke
			(width 0.0508)
			(type default)
		)
		(layer "In5.Cu")
	)
	(gr_line
		(start 190.09233 -34.289746)
		(end 190.690246 -34.40938)
		(stroke
			(width 0.0508)
			(type default)
		)
		(layer "In5.Cu")
	)
	(gr_line
		(start 190.145416 -34.80562)
		(end 190.44412 -34.865564)
		(stroke
			(width 0.0508)
			(type default)
		)
		(layer "In5.Cu")
	)
	(gr_arc
		(start 190.179198 -83.886802)
		(mid 190.097344 -84.084414)
		(end 190.179198 -84.282026)
		(stroke
			(width 0.06985)
			(type default)
		)
		(layer "In5.Cu")
	)
	(gr_line
		(start 190.421006 -91.98737)
		(end 190.445644 -91.99245)
		(stroke
			(width 0.06985)
			(type default)
		)
		(layer "In5.Cu")
	)
	(gr_line
		(start 190.44412 -34.865564)
		(end 190.665608 -34.71799)
		(stroke
			(width 0.0508)
			(type default)
		)
		(layer "In5.Cu")
	)
	(gr_line
		(start 190.445644 -91.99245)
		(end 190.470282 -91.98737)
		(stroke
			(width 0.06985)
			(type default)
		)
		(layer "In5.Cu")
	)
	(gr_line
		(start 190.523876 -33.554924)
		(end 190.542672 -33.567624)
		(stroke
			(width 0.0508)
			(type default)
		)
		(layer "In5.Cu")
	)
	(gr_line
		(start 190.542672 -33.567624)
		(end 190.565278 -33.572196)
		(stroke
			(width 0.0508)
			(type default)
		)
		(layer "In5.Cu")
	)
	(gr_line
		(start 190.55461 -91.149932)
		(end 190.579248 -91.144852)
		(stroke
			(width 0.06985)
			(type default)
		)
		(layer "In5.Cu")
	)
	(gr_line
		(start 190.686436 -32.525462)
		(end 190.70447 -32.537654)
		(stroke
			(width 0.0508)
			(type default)
		)
		(layer "In5.Cu")
	)
	(gr_line
		(start 190.70447 -32.537654)
		(end 190.72606 -32.541972)
		(stroke
			(width 0.0508)
			(type default)
		)
		(layer "In5.Cu")
	)
	(gr_line
		(start 190.843408 -33.630108)
		(end 190.990982 -33.851596)
		(stroke
			(width 0.0508)
			(type default)
		)
		(layer "In5.Cu")
	)
	(gr_line
		(start 190.939928 -33.33623)
		(end 191.536066 -33.455356)
		(stroke
			(width 0.0508)
			(type default)
		)
		(layer "In5.Cu")
	)
	(gr_line
		(start 190.969138 -34.778696)
		(end 191.116712 -34.99993)
		(stroke
			(width 0.0508)
			(type default)
		)
		(layer "In5.Cu")
	)
	(gr_line
		(start 190.990982 -33.851596)
		(end 191.28994 -33.91154)
		(stroke
			(width 0.0508)
			(type default)
		)
		(layer "In5.Cu")
	)
	(gr_line
		(start 191.005206 -32.600138)
		(end 191.15278 -32.821626)
		(stroke
			(width 0.0508)
			(type default)
		)
		(layer "In5.Cu")
	)
	(gr_line
		(start 191.063372 -34.483802)
		(end 191.662304 -34.60369)
		(stroke
			(width 0.0508)
			(type default)
		)
		(layer "In5.Cu")
	)
	(gr_line
		(start 191.101472 -32.306006)
		(end 191.69888 -32.425386)
		(stroke
			(width 0.0508)
			(type default)
		)
		(layer "In5.Cu")
	)
	(gr_line
		(start 191.116712 -34.99993)
		(end 191.41567 -35.059874)
		(stroke
			(width 0.0508)
			(type default)
		)
		(layer "In5.Cu")
	)
	(gr_line
		(start 191.15278 -32.821626)
		(end 191.451738 -32.881316)
		(stroke
			(width 0.0508)
			(type default)
		)
		(layer "In5.Cu")
	)
	(gr_line
		(start 191.28994 -33.91154)
		(end 191.511174 -33.763712)
		(stroke
			(width 0.0508)
			(type default)
		)
		(layer "In5.Cu")
	)
	(gr_line
		(start 191.41567 -35.059874)
		(end 191.636904 -34.912046)
		(stroke
			(width 0.0508)
			(type default)
		)
		(layer "In5.Cu")
	)
	(gr_line
		(start 191.451738 -32.881316)
		(end 191.672972 -32.733742)
		(stroke
			(width 0.0508)
			(type default)
		)
		(layer "In5.Cu")
	)
	(gr_arc
		(start 191.49441 -87.309198)
		(mid 191.297306 -87.22748)
		(end 191.100202 -87.309198)
		(stroke
			(width 0.06985)
			(type default)
		)
		(layer "In5.Cu")
	)
	(gr_arc
		(start 191.728598 -86.680802)
		(mid 191.646744 -86.878414)
		(end 191.728598 -87.076026)
		(stroke
			(width 0.06985)
			(type default)
		)
		(layer "In5.Cu")
	)
	(gr_line
		(start 191.814704 -33.824418)
		(end 191.962278 -34.045906)
		(stroke
			(width 0.0508)
			(type default)
		)
		(layer "In5.Cu")
	)
	(gr_line
		(start 191.89446 -87.241888)
		(end 191.962786 -87.310468)
		(stroke
			(width 0.06985)
			(type default)
		)
		(layer "In5.Cu")
	)
	(gr_line
		(start 191.909446 -33.530032)
		(end 192.508378 -33.64992)
		(stroke
			(width 0.0508)
			(type default)
		)
		(layer "In5.Cu")
	)
	(gr_line
		(start 191.962278 -34.045906)
		(end 192.261236 -34.10585)
		(stroke
			(width 0.0508)
			(type default)
		)
		(layer "In5.Cu")
	)
	(gr_line
		(start 191.976502 -32.794448)
		(end 192.124076 -33.015936)
		(stroke
			(width 0.0508)
			(type default)
		)
		(layer "In5.Cu")
	)
	(gr_line
		(start 192.07226 -32.500316)
		(end 192.669414 -32.619696)
		(stroke
			(width 0.0508)
			(type default)
		)
		(layer "In5.Cu")
	)
	(gr_line
		(start 192.124076 -33.015936)
		(end 192.423034 -33.075626)
		(stroke
			(width 0.0508)
			(type default)
		)
		(layer "In5.Cu")
	)
	(gr_line
		(start 192.261236 -34.10585)
		(end 192.482724 -33.958276)
		(stroke
			(width 0.0508)
			(type default)
		)
		(layer "In5.Cu")
	)
	(gr_line
		(start 192.423034 -33.075626)
		(end 192.644522 -32.928052)
		(stroke
			(width 0.0508)
			(type default)
		)
		(layer "In5.Cu")
	)
	(gr_line
		(start 192.786 -34.018728)
		(end 192.933574 -34.24047)
		(stroke
			(width 0.0508)
			(type default)
		)
		(layer "In5.Cu")
	)
	(gr_line
		(start 192.880996 -33.724596)
		(end 193.479928 -33.84423)
		(stroke
			(width 0.0508)
			(type default)
		)
		(layer "In5.Cu")
	)
	(gr_line
		(start 192.933574 -34.24047)
		(end 193.232532 -34.30016)
		(stroke
			(width 0.0508)
			(type default)
		)
		(layer "In5.Cu")
	)
	(gr_line
		(start 192.947798 -32.988758)
		(end 193.095626 -33.210246)
		(stroke
			(width 0.0508)
			(type default)
		)
		(layer "In5.Cu")
	)
	(gr_line
		(start 193.044826 -32.69488)
		(end 193.64071 -32.814006)
		(stroke
			(width 0.0508)
			(type default)
		)
		(layer "In5.Cu")
	)
	(gr_line
		(start 193.095626 -33.210246)
		(end 193.39433 -33.269936)
		(stroke
			(width 0.0508)
			(type default)
		)
		(layer "In5.Cu")
	)
	(gr_line
		(start 193.232532 -34.30016)
		(end 193.454274 -34.152586)
		(stroke
			(width 0.0508)
			(type default)
		)
		(layer "In5.Cu")
	)
	(gr_line
		(start 193.39433 -33.269936)
		(end 193.616072 -33.122362)
		(stroke
			(width 0.0508)
			(type default)
		)
		(layer "In5.Cu")
	)
	(gr_line
		(start 193.757296 -34.213292)
		(end 193.90487 -34.43478)
		(stroke
			(width 0.0508)
			(type default)
		)
		(layer "In5.Cu")
	)
	(gr_line
		(start 193.8528 -33.918906)
		(end 194.451732 -34.038794)
		(stroke
			(width 0.0508)
			(type default)
		)
		(layer "In5.Cu")
	)
	(gr_line
		(start 193.90487 -34.43478)
		(end 194.203828 -34.49447)
		(stroke
			(width 0.0508)
			(type default)
		)
		(layer "In5.Cu")
	)
	(gr_line
		(start 193.919094 -33.182814)
		(end 194.066922 -33.404302)
		(stroke
			(width 0.0508)
			(type default)
		)
		(layer "In5.Cu")
	)
	(gr_line
		(start 193.998342 -90.461338)
		(end 194.055746 -90.449908)
		(stroke
			(width 0.06985)
			(type default)
		)
		(layer "In5.Cu")
	)
	(gr_line
		(start 194.016122 -32.88919)
		(end 194.609212 -33.007808)
		(stroke
			(width 0.0508)
			(type default)
		)
		(layer "In5.Cu")
	)
	(gr_line
		(start 194.055746 -90.449908)
		(end 194.085718 -90.42019)
		(stroke
			(width 0.06985)
			(type default)
		)
		(layer "In5.Cu")
	)
	(gr_line
		(start 194.066922 -33.404302)
		(end 194.36588 -33.464246)
		(stroke
			(width 0.0508)
			(type default)
		)
		(layer "In5.Cu")
	)
	(gr_line
		(start 194.203828 -34.49447)
		(end 194.425316 -34.346896)
		(stroke
			(width 0.0508)
			(type default)
		)
		(layer "In5.Cu")
	)
	(gr_arc
		(start 194.217798 -89.010998)
		(mid 194.020186 -88.929144)
		(end 193.822574 -89.010998)
		(stroke
			(width 0.06985)
			(type default)
		)
		(layer "In5.Cu")
	)
	(gr_line
		(start 194.314826 -90.881708)
		(end 194.31508 -90.881708)
		(stroke
			(width 0.06985)
			(type default)
		)
		(layer "In5.Cu")
	)
	(gr_line
		(start 194.36588 -33.464246)
		(end 194.587114 -33.316418)
		(stroke
			(width 0.0508)
			(type default)
		)
		(layer "In5.Cu")
	)
	(gr_line
		(start 194.419474 -91.197684)
		(end 194.47764 -91.186)
		(stroke
			(width 0.06985)
			(type default)
		)
		(layer "In5.Cu")
	)
	(gr_arc
		(start 194.44081 -84.286598)
		(mid 194.243706 -84.20488)
		(end 194.046602 -84.286598)
		(stroke
			(width 0.06985)
			(type default)
		)
		(layer "In5.Cu")
	)
	(gr_arc
		(start 194.45097 -88.382602)
		(mid 194.369327 -88.579706)
		(end 194.45097 -88.77681)
		(stroke
			(width 0.06985)
			(type default)
		)
		(layer "In5.Cu")
	)
	(gr_line
		(start 194.47764 -91.186)
		(end 194.507612 -91.156282)
		(stroke
			(width 0.06985)
			(type default)
		)
		(layer "In5.Cu")
	)
	(gr_line
		(start 194.507612 -91.156536)
		(end 194.521328 -91.14282)
		(stroke
			(width 0.06985)
			(type default)
		)
		(layer "In5.Cu")
	)
	(gr_line
		(start 194.507612 -91.156282)
		(end 194.507612 -91.156536)
		(stroke
			(width 0.06985)
			(type default)
		)
		(layer "In5.Cu")
	)
	(gr_arc
		(start 194.674998 -83.658202)
		(mid 194.593219 -83.855455)
		(end 194.67449 -84.052918)
		(stroke
			(width 0.06985)
			(type default)
		)
		(layer "In5.Cu")
	)
	(gr_line
		(start 196.767704 -91.552522)
		(end 196.79285 -91.547442)
		(stroke
			(width 0.06985)
			(type default)
		)
		(layer "In5.Cu")
	)
	(gr_line
		(start 196.79285 -91.547442)
		(end 196.812916 -91.533726)
		(stroke
			(width 0.06985)
			(type default)
		)
		(layer "In5.Cu")
	)
	(gr_arc
		(start 197.290182 -85.962998)
		(mid 197.093078 -85.88128)
		(end 196.895974 -85.962998)
		(stroke
			(width 0.06985)
			(type default)
		)
		(layer "In5.Cu")
	)
	(gr_line
		(start 197.372986 -92.390214)
		(end 197.398132 -92.385134)
		(stroke
			(width 0.06985)
			(type default)
		)
		(layer "In5.Cu")
	)
	(gr_line
		(start 197.398132 -92.385134)
		(end 197.418198 -92.371418)
		(stroke
			(width 0.06985)
			(type default)
		)
		(layer "In5.Cu")
	)
	(gr_arc
		(start 197.52437 -85.334602)
		(mid 197.44259 -85.531851)
		(end 197.523862 -85.729318)
		(stroke
			(width 0.06985)
			(type default)
		)
		(layer "In5.Cu")
	)
	(gr_line
		(start 198.051928 -87.612474)
		(end 198.12 -87.544402)
		(stroke
			(width 0.06985)
			(type default)
		)
		(layer "In5.Cu")
	)
	(gr_line
		(start 198.12127 -91.505786)
		(end 198.701152 -91.119198)
		(stroke
			(width 0.06985)
			(type default)
		)
		(layer "In5.Cu")
	)
	(gr_line
		(start 198.275956 -91.802966)
		(end 198.519034 -91.85148)
		(stroke
			(width 0.06985)
			(type default)
		)
		(layer "In5.Cu")
	)
	(gr_line
		(start 198.519034 -91.85148)
		(end 198.867776 -91.61907)
		(stroke
			(width 0.06985)
			(type default)
		)
		(layer "In5.Cu")
	)
	(gr_arc
		(start 198.582026 -89.087198)
		(mid 198.384414 -89.005344)
		(end 198.186802 -89.087198)
		(stroke
			(width 0.06985)
			(type default)
		)
		(layer "In5.Cu")
	)
	(gr_line
		(start 198.746872 -89.252044)
		(end 198.746872 -89.307416)
		(stroke
			(width 0.06985)
			(type default)
		)
		(layer "In5.Cu")
	)
	(gr_arc
		(start 198.815198 -88.458802)
		(mid 198.733555 -88.655906)
		(end 198.815198 -88.85301)
		(stroke
			(width 0.06985)
			(type default)
		)
		(layer "In5.Cu")
	)
	(gr_line
		(start 198.867776 -91.61907)
		(end 198.91629 -91.375738)
		(stroke
			(width 0.06985)
			(type default)
		)
		(layer "In5.Cu")
	)
	(gr_line
		(start 198.93915 -88.977216)
		(end 198.939404 -88.977216)
		(stroke
			(width 0.06985)
			(type default)
		)
		(layer "In5.Cu")
	)
	(gr_line
		(start 199.009 -89.9668)
		(end 199.077072 -89.898728)
		(stroke
			(width 0.06985)
			(type default)
		)
		(layer "In5.Cu")
	)
	(gr_line
		(start 199.114918 -90.843354)
		(end 199.694038 -90.457528)
		(stroke
			(width 0.06985)
			(type default)
		)
		(layer "In5.Cu")
	)
	(gr_line
		(start 199.269096 -91.140788)
		(end 199.512428 -91.189302)
		(stroke
			(width 0.06985)
			(type default)
		)
		(layer "In5.Cu")
	)
	(gr_line
		(start 199.512428 -91.189302)
		(end 199.86117 -90.956892)
		(stroke
			(width 0.06985)
			(type default)
		)
		(layer "In5.Cu")
	)
	(gr_line
		(start 199.86117 -90.956892)
		(end 199.909684 -90.71356)
		(stroke
			(width 0.06985)
			(type default)
		)
		(layer "In5.Cu")
	)
	(gr_line
		(start 201.47661 -92.506546)
		(end 201.53503 -92.494862)
		(stroke
			(width 0.06985)
			(type default)
		)
		(layer "In5.Cu")
	)
	(gr_line
		(start 201.53503 -92.494862)
		(end 201.577194 -92.452698)
		(stroke
			(width 0.06985)
			(type default)
		)
		(layer "In5.Cu")
	)
	(gr_arc
		(start 201.60361 -86.089998)
		(mid 201.406506 -86.00828)
		(end 201.209402 -86.089998)
		(stroke
			(width 0.06985)
			(type default)
		)
		(layer "In5.Cu")
	)
	(gr_arc
		(start 201.837798 -85.461602)
		(mid 201.755839 -85.659378)
		(end 201.837798 -85.85708)
		(stroke
			(width 0.06985)
			(type default)
		)
		(layer "In5.Cu")
	)
	(gr_line
		(start 202.931522 -93.663008)
		(end 202.955398 -93.658436)
		(stroke
			(width 0.06985)
			(type default)
		)
		(layer "In5.Cu")
	)
	(gr_line
		(start 202.955398 -93.658436)
		(end 202.957176 -93.65742)
		(stroke
			(width 0.06985)
			(type default)
		)
		(layer "In5.Cu")
	)
	(gr_line
		(start 202.957176 -93.657166)
		(end 202.957176 -93.65742)
		(stroke
			(width 0.06985)
			(type default)
		)
		(layer "In5.Cu")
	)
	(gr_line
		(start 202.957176 -93.657166)
		(end 202.97521 -93.645482)
		(stroke
			(width 0.06985)
			(type default)
		)
		(layer "In5.Cu")
	)
	(gr_line
		(start 202.968606 -42.432224)
		(end 203.116434 -42.653458)
		(stroke
			(width 0.0508)
			(type default)
		)
		(layer "In5.Cu")
	)
	(gr_line
		(start 202.972924 -34.99358)
		(end 203.120752 -35.215068)
		(stroke
			(width 0.0508)
			(type default)
		)
		(layer "In5.Cu")
	)
	(gr_line
		(start 203.06411 -42.137838)
		(end 203.661264 -42.256964)
		(stroke
			(width 0.0508)
			(type default)
		)
		(layer "In5.Cu")
	)
	(gr_line
		(start 203.067666 -34.699194)
		(end 203.66609 -34.818828)
		(stroke
			(width 0.0508)
			(type default)
		)
		(layer "In5.Cu")
	)
	(gr_line
		(start 203.116434 -42.653458)
		(end 203.415392 -42.713148)
		(stroke
			(width 0.0508)
			(type default)
		)
		(layer "In5.Cu")
	)
	(gr_line
		(start 203.120752 -35.215068)
		(end 203.419456 -35.275012)
		(stroke
			(width 0.0508)
			(type default)
		)
		(layer "In5.Cu")
	)
	(gr_line
		(start 203.129896 -36.088828)
		(end 203.277724 -36.310316)
		(stroke
			(width 0.0508)
			(type default)
		)
		(layer "In5.Cu")
	)
	(gr_line
		(start 203.221844 -35.793426)
		(end 203.827126 -35.91433)
		(stroke
			(width 0.0508)
			(type default)
		)
		(layer "In5.Cu")
	)
	(gr_line
		(start 203.277724 -36.310316)
		(end 203.576428 -36.370006)
		(stroke
			(width 0.0508)
			(type default)
		)
		(layer "In5.Cu")
	)
	(gr_line
		(start 203.3397 -37.252656)
		(end 203.487274 -37.47389)
		(stroke
			(width 0.0508)
			(type default)
		)
		(layer "In5.Cu")
	)
	(gr_line
		(start 203.347066 -38.239446)
		(end 203.49464 -38.460934)
		(stroke
			(width 0.0508)
			(type default)
		)
		(layer "In5.Cu")
	)
	(gr_line
		(start 203.415392 -42.713148)
		(end 203.636626 -42.56532)
		(stroke
			(width 0.0508)
			(type default)
		)
		(layer "In5.Cu")
	)
	(gr_line
		(start 203.419456 -35.275012)
		(end 203.640944 -35.127184)
		(stroke
			(width 0.0508)
			(type default)
		)
		(layer "In5.Cu")
	)
	(gr_line
		(start 203.432918 -36.957508)
		(end 204.033374 -37.07765)
		(stroke
			(width 0.0508)
			(type default)
		)
		(layer "In5.Cu")
	)
	(gr_line
		(start 203.441046 -37.944806)
		(end 204.040232 -38.064694)
		(stroke
			(width 0.0508)
			(type default)
		)
		(layer "In5.Cu")
	)
	(gr_line
		(start 203.487274 -37.47389)
		(end 203.786232 -37.533834)
		(stroke
			(width 0.0508)
			(type default)
		)
		(layer "In5.Cu")
	)
	(gr_line
		(start 203.49464 -38.460934)
		(end 203.793598 -38.520878)
		(stroke
			(width 0.0508)
			(type default)
		)
		(layer "In5.Cu")
	)
	(gr_line
		(start 203.576428 -36.370006)
		(end 203.79817 -36.222432)
		(stroke
			(width 0.0508)
			(type default)
		)
		(layer "In5.Cu")
	)
	(gr_line
		(start 203.786232 -37.533834)
		(end 204.007466 -37.386006)
		(stroke
			(width 0.0508)
			(type default)
		)
		(layer "In5.Cu")
	)
	(gr_line
		(start 203.793598 -38.520878)
		(end 204.014832 -38.37305)
		(stroke
			(width 0.0508)
			(type default)
		)
		(layer "In5.Cu")
	)
	(gr_line
		(start 203.940156 -42.626026)
		(end 204.087984 -42.84726)
		(stroke
			(width 0.0508)
			(type default)
		)
		(layer "In5.Cu")
	)
	(gr_line
		(start 203.944474 -35.18789)
		(end 204.092048 -35.409378)
		(stroke
			(width 0.0508)
			(type default)
		)
		(layer "In5.Cu")
	)
	(gr_line
		(start 204.029056 -92.963238)
		(end 204.051662 -92.948506)
		(stroke
			(width 0.06985)
			(type default)
		)
		(layer "In5.Cu")
	)
	(gr_line
		(start 204.03439 -42.331132)
		(end 204.633576 -42.450766)
		(stroke
			(width 0.0508)
			(type default)
		)
		(layer "In5.Cu")
	)
	(gr_line
		(start 204.038454 -34.89325)
		(end 204.637894 -35.013138)
		(stroke
			(width 0.0508)
			(type default)
		)
		(layer "In5.Cu")
	)
	(gr_line
		(start 204.051662 -92.948506)
		(end 204.066394 -92.926916)
		(stroke
			(width 0.06985)
			(type default)
		)
		(layer "In5.Cu")
	)
	(gr_line
		(start 204.087984 -42.84726)
		(end 204.386942 -42.90695)
		(stroke
			(width 0.0508)
			(type default)
		)
		(layer "In5.Cu")
	)
	(gr_line
		(start 204.092048 -35.409378)
		(end 204.391006 -35.469068)
		(stroke
			(width 0.0508)
			(type default)
		)
		(layer "In5.Cu")
	)
	(gr_line
		(start 204.101192 -36.283138)
		(end 204.24902 -36.504626)
		(stroke
			(width 0.0508)
			(type default)
		)
		(layer "In5.Cu")
	)
	(gr_arc
		(start 204.19441 -85.505798)
		(mid 203.997306 -85.42408)
		(end 203.800202 -85.505798)
		(stroke
			(width 0.06985)
			(type default)
		)
		(layer "In5.Cu")
	)
	(gr_line
		(start 204.194664 -35.988244)
		(end 204.797406 -36.10864)
		(stroke
			(width 0.0508)
			(type default)
		)
		(layer "In5.Cu")
	)
	(gr_line
		(start 204.24902 -36.504626)
		(end 204.547724 -36.564316)
		(stroke
			(width 0.0508)
			(type default)
		)
		(layer "In5.Cu")
	)
	(gr_line
		(start 204.310996 -37.446712)
		(end 204.458824 -37.6682)
		(stroke
			(width 0.0508)
			(type default)
		)
		(layer "In5.Cu")
	)
	(gr_line
		(start 204.318362 -38.433756)
		(end 204.46619 -38.655244)
		(stroke
			(width 0.0508)
			(type default)
		)
		(layer "In5.Cu")
	)
	(gr_line
		(start 204.386942 -42.90695)
		(end 204.608176 -42.759122)
		(stroke
			(width 0.0508)
			(type default)
		)
		(layer "In5.Cu")
	)
	(gr_line
		(start 204.391006 -35.469068)
		(end 204.61224 -35.321494)
		(stroke
			(width 0.0508)
			(type default)
		)
		(layer "In5.Cu")
	)
	(gr_line
		(start 204.404214 -37.151818)
		(end 205.00467 -37.27196)
		(stroke
			(width 0.0508)
			(type default)
		)
		(layer "In5.Cu")
	)
	(gr_line
		(start 204.412342 -38.139116)
		(end 205.013052 -38.259258)
		(stroke
			(width 0.0508)
			(type default)
		)
		(layer "In5.Cu")
	)
	(gr_arc
		(start 204.428598 -84.877402)
		(mid 204.346639 -85.075178)
		(end 204.428598 -85.27288)
		(stroke
			(width 0.06985)
			(type default)
		)
		(layer "In5.Cu")
	)
	(gr_line
		(start 204.458824 -37.6682)
		(end 204.757528 -37.72789)
		(stroke
			(width 0.0508)
			(type default)
		)
		(layer "In5.Cu")
	)
	(gr_line
		(start 204.46619 -38.655244)
		(end 204.764894 -38.714934)
		(stroke
			(width 0.0508)
			(type default)
		)
		(layer "In5.Cu")
	)
	(gr_line
		(start 204.547724 -36.564316)
		(end 204.769212 -36.416742)
		(stroke
			(width 0.0508)
			(type default)
		)
		(layer "In5.Cu")
	)
	(gr_line
		(start 204.706728 -89.324942)
		(end 204.7748 -89.25687)
		(stroke
			(width 0.06985)
			(type default)
		)
		(layer "In5.Cu")
	)
	(gr_line
		(start 204.757528 -37.72789)
		(end 204.979016 -37.580316)
		(stroke
			(width 0.0508)
			(type default)
		)
		(layer "In5.Cu")
	)
	(gr_line
		(start 204.764894 -38.714934)
		(end 204.986382 -38.56736)
		(stroke
			(width 0.0508)
			(type default)
		)
		(layer "In5.Cu")
	)
	(gr_line
		(start 204.911706 -42.819828)
		(end 205.05928 -43.041062)
		(stroke
			(width 0.0508)
			(type default)
		)
		(layer "In5.Cu")
	)
	(gr_line
		(start 204.91577 -35.3822)
		(end 205.063344 -35.603688)
		(stroke
			(width 0.0508)
			(type default)
		)
		(layer "In5.Cu")
	)
	(gr_line
		(start 205.005686 -42.524934)
		(end 205.60538 -42.644568)
		(stroke
			(width 0.0508)
			(type default)
		)
		(layer "In5.Cu")
	)
	(gr_line
		(start 205.011274 -35.087814)
		(end 205.608936 -35.207448)
		(stroke
			(width 0.0508)
			(type default)
		)
		(layer "In5.Cu")
	)
	(gr_line
		(start 205.05928 -43.041062)
		(end 205.358238 -43.100752)
		(stroke
			(width 0.0508)
			(type default)
		)
		(layer "In5.Cu")
	)
	(gr_line
		(start 205.063344 -35.603688)
		(end 205.362302 -35.663378)
		(stroke
			(width 0.0508)
			(type default)
		)
		(layer "In5.Cu")
	)
	(gr_line
		(start 205.072742 -36.477448)
		(end 205.220316 -36.698936)
		(stroke
			(width 0.0508)
			(type default)
		)
		(layer "In5.Cu")
	)
	(gr_line
		(start 205.167484 -36.182808)
		(end 205.766416 -36.302696)
		(stroke
			(width 0.0508)
			(type default)
		)
		(layer "In5.Cu")
	)
	(gr_line
		(start 205.220316 -36.698936)
		(end 205.519274 -36.75888)
		(stroke
			(width 0.0508)
			(type default)
		)
		(layer "In5.Cu")
	)
	(gr_line
		(start 205.282292 -37.641022)
		(end 205.43012 -37.86251)
		(stroke
			(width 0.0508)
			(type default)
		)
		(layer "In5.Cu")
	)
	(gr_line
		(start 205.289658 -38.628066)
		(end 205.437486 -38.849554)
		(stroke
			(width 0.0508)
			(type default)
		)
		(layer "In5.Cu")
	)
	(gr_line
		(start 205.358238 -43.100752)
		(end 205.579726 -42.952924)
		(stroke
			(width 0.0508)
			(type default)
		)
		(layer "In5.Cu")
	)
	(gr_line
		(start 205.362302 -35.663378)
		(end 205.58379 -35.515804)
		(stroke
			(width 0.0508)
			(type default)
		)
		(layer "In5.Cu")
	)
	(gr_line
		(start 205.377796 -37.346636)
		(end 205.975966 -37.46627)
		(stroke
			(width 0.0508)
			(type default)
		)
		(layer "In5.Cu")
	)
	(gr_line
		(start 205.3844 -38.333426)
		(end 205.983586 -38.453314)
		(stroke
			(width 0.0508)
			(type default)
		)
		(layer "In5.Cu")
	)
	(gr_line
		(start 205.43012 -37.86251)
		(end 205.729078 -37.9222)
		(stroke
			(width 0.0508)
			(type default)
		)
		(layer "In5.Cu")
	)
	(gr_line
		(start 205.437486 -38.849554)
		(end 205.736444 -38.909244)
		(stroke
			(width 0.0508)
			(type default)
		)
		(layer "In5.Cu")
	)
	(gr_line
		(start 205.444598 -90.924126)
		(end 205.457806 -90.904822)
		(stroke
			(width 0.06985)
			(type default)
		)
		(layer "In5.Cu")
	)
	(gr_line
		(start 205.457806 -90.904822)
		(end 205.46314 -90.882216)
		(stroke
			(width 0.06985)
			(type default)
		)
		(layer "In5.Cu")
	)
	(gr_line
		(start 205.519274 -36.75888)
		(end 205.740508 -36.611052)
		(stroke
			(width 0.0508)
			(type default)
		)
		(layer "In5.Cu")
	)
	(gr_line
		(start 205.729078 -37.9222)
		(end 205.950312 -37.774626)
		(stroke
			(width 0.0508)
			(type default)
		)
		(layer "In5.Cu")
	)
	(gr_line
		(start 205.736444 -38.909244)
		(end 205.957932 -38.76167)
		(stroke
			(width 0.0508)
			(type default)
		)
		(layer "In5.Cu")
	)
	(gr_line
		(start 205.756256 -85.152992)
		(end 205.778862 -85.22462)
		(stroke
			(width 0.06985)
			(type default)
		)
		(layer "In5.Cu")
	)
	(gr_line
		(start 205.756256 -85.152992)
		(end 205.78191 -85.084666)
		(stroke
			(width 0.06985)
			(type default)
		)
		(layer "In5.Cu")
	)
	(gr_line
		(start 205.778608 -85.223858)
		(end 205.778608 -85.224112)
		(stroke
			(width 0.06985)
			(type default)
		)
		(layer "In5.Cu")
	)
	(gr_line
		(start 205.887066 -35.57651)
		(end 206.034894 -35.797998)
		(stroke
			(width 0.0508)
			(type default)
		)
		(layer "In5.Cu")
	)
	(gr_line
		(start 205.982824 -35.282378)
		(end 206.58074 -35.401758)
		(stroke
			(width 0.0508)
			(type default)
		)
		(layer "In5.Cu")
	)
	(gr_line
		(start 206.034894 -35.797998)
		(end 206.333598 -35.857688)
		(stroke
			(width 0.0508)
			(type default)
		)
		(layer "In5.Cu")
	)
	(gr_line
		(start 206.044038 -36.671758)
		(end 206.191612 -36.893246)
		(stroke
			(width 0.0508)
			(type default)
		)
		(layer "In5.Cu")
	)
	(gr_line
		(start 206.137256 -36.376864)
		(end 206.739998 -36.497514)
		(stroke
			(width 0.0508)
			(type default)
		)
		(layer "In5.Cu")
	)
	(gr_line
		(start 206.191612 -36.893246)
		(end 206.49057 -36.95319)
		(stroke
			(width 0.0508)
			(type default)
		)
		(layer "In5.Cu")
	)
	(gr_line
		(start 206.197708 -83.96478)
		(end 206.208376 -83.935824)
		(stroke
			(width 0.06985)
			(type default)
		)
		(layer "In5.Cu")
	)
	(gr_line
		(start 206.253842 -37.835332)
		(end 206.401416 -38.05682)
		(stroke
			(width 0.0508)
			(type default)
		)
		(layer "In5.Cu")
	)
	(gr_line
		(start 206.261208 -38.822376)
		(end 206.408782 -39.043864)
		(stroke
			(width 0.0508)
			(type default)
		)
		(layer "In5.Cu")
	)
	(gr_line
		(start 206.333598 -35.857688)
		(end 206.55534 -35.710114)
		(stroke
			(width 0.0508)
			(type default)
		)
		(layer "In5.Cu")
	)
	(gr_line
		(start 206.350108 -37.5412)
		(end 206.948278 -37.660834)
		(stroke
			(width 0.0508)
			(type default)
		)
		(layer "In5.Cu")
	)
	(gr_line
		(start 206.35595 -38.527736)
		(end 206.95666 -38.647878)
		(stroke
			(width 0.0508)
			(type default)
		)
		(layer "In5.Cu")
	)
	(gr_line
		(start 206.401416 -38.05682)
		(end 206.700374 -38.11651)
		(stroke
			(width 0.0508)
			(type default)
		)
		(layer "In5.Cu")
	)
	(gr_line
		(start 206.408782 -39.043864)
		(end 206.70774 -39.103554)
		(stroke
			(width 0.0508)
			(type default)
		)
		(layer "In5.Cu")
	)
	(gr_line
		(start 206.49057 -36.95319)
		(end 206.712058 -36.805616)
		(stroke
			(width 0.0508)
			(type default)
		)
		(layer "In5.Cu")
	)
	(gr_line
		(start 206.495904 -86.399116)
		(end 206.511144 -86.447122)
		(stroke
			(width 0.06985)
			(type default)
		)
		(layer "In5.Cu")
	)
	(gr_line
		(start 206.49946 -86.496398)
		(end 206.511144 -86.447122)
		(stroke
			(width 0.06985)
			(type default)
		)
		(layer "In5.Cu")
	)
	(gr_line
		(start 206.700374 -38.11651)
		(end 206.921862 -37.968936)
		(stroke
			(width 0.0508)
			(type default)
		)
		(layer "In5.Cu")
	)
	(gr_line
		(start 206.70774 -39.103554)
		(end 206.929228 -38.95598)
		(stroke
			(width 0.0508)
			(type default)
		)
		(layer "In5.Cu")
	)
	(gr_line
		(start 206.77886 -42.878756)
		(end 206.80045 -42.883074)
		(stroke
			(width 0.0508)
			(type default)
		)
		(layer "In5.Cu")
	)
	(gr_line
		(start 206.80045 -42.883074)
		(end 206.818484 -42.895266)
		(stroke
			(width 0.0508)
			(type default)
		)
		(layer "In5.Cu")
	)
	(gr_line
		(start 206.939642 -41.753028)
		(end 206.959708 -41.756838)
		(stroke
			(width 0.0508)
			(type default)
		)
		(layer "In5.Cu")
	)
	(gr_line
		(start 206.959708 -41.756838)
		(end 206.97698 -41.768522)
		(stroke
			(width 0.0508)
			(type default)
		)
		(layer "In5.Cu")
	)
	(gr_line
		(start 207.080104 -35.501834)
		(end 207.10144 -35.505898)
		(stroke
			(width 0.0508)
			(type default)
		)
		(layer "In5.Cu")
	)
	(gr_line
		(start 207.10144 -35.505898)
		(end 207.119474 -35.51809)
		(stroke
			(width 0.0508)
			(type default)
		)
		(layer "In5.Cu")
	)
	(gr_line
		(start 207.110076 -36.571682)
		(end 207.132682 -36.576254)
		(stroke
			(width 0.0508)
			(type default)
		)
		(layer "In5.Cu")
	)
	(gr_line
		(start 207.132682 -36.576254)
		(end 207.151478 -36.588954)
		(stroke
			(width 0.0508)
			(type default)
		)
		(layer "In5.Cu")
	)
	(gr_line
		(start 207.320896 -37.73551)
		(end 207.342232 -37.739574)
		(stroke
			(width 0.0508)
			(type default)
		)
		(layer "In5.Cu")
	)
	(gr_line
		(start 207.327246 -38.722046)
		(end 207.349852 -38.726618)
		(stroke
			(width 0.0508)
			(type default)
		)
		(layer "In5.Cu")
	)
	(gr_line
		(start 207.342232 -37.739574)
		(end 207.360266 -37.751766)
		(stroke
			(width 0.0508)
			(type default)
		)
		(layer "In5.Cu")
	)
	(gr_line
		(start 207.349852 -38.726618)
		(end 207.368648 -38.739318)
		(stroke
			(width 0.0508)
			(type default)
		)
		(layer "In5.Cu")
	)
	(gr_line
		(start 207.669892 -40.948864)
		(end 207.689958 -40.952674)
		(stroke
			(width 0.0508)
			(type default)
		)
		(layer "In5.Cu")
	)
	(gr_line
		(start 207.689958 -40.952674)
		(end 207.707738 -40.964358)
		(stroke
			(width 0.0508)
			(type default)
		)
		(layer "In5.Cu")
	)
	(gr_line
		(start 207.70342 -39.986204)
		(end 207.724756 -39.990268)
		(stroke
			(width 0.0508)
			(type default)
		)
		(layer "In5.Cu")
	)
	(gr_line
		(start 207.724756 -39.990268)
		(end 207.74279 -40.00246)
		(stroke
			(width 0.0508)
			(type default)
		)
		(layer "In5.Cu")
	)
	(gr_arc
		(start 208.367122 -84.707984)
		(mid 208.448901 -84.510731)
		(end 208.36763 -84.313268)
		(stroke
			(width 0.06985)
			(type default)
		)
		(layer "In5.Cu")
	)
	(gr_arc
		(start 208.60131 -84.079588)
		(mid 208.798414 -84.161306)
		(end 208.995518 -84.079588)
		(stroke
			(width 0.06985)
			(type default)
		)
		(layer "In5.Cu")
	)
	(gr_line
		(start 211.06003 -63.924688)
		(end 211.223098 -63.76162)
		(stroke
			(width 0.0508)
			(type default)
		)
		(layer "In5.Cu")
	)
	(gr_arc
		(start 211.223098 -63.76162)
		(mid 211.278245 -63.628517)
		(end 211.223098 -63.495428)
		(stroke
			(width 0.0508)
			(type default)
		)
		(layer "In5.Cu")
	)
	(gr_line
		(start 211.228686 -66.367914)
		(end 211.391754 -66.204846)
		(stroke
			(width 0.0508)
			(type default)
		)
		(layer "In5.Cu")
	)
	(gr_arc
		(start 211.391754 -66.204846)
		(mid 211.446932 -66.071735)
		(end 211.391754 -65.938654)
		(stroke
			(width 0.0508)
			(type default)
		)
		(layer "In5.Cu")
	)
	(gr_arc
		(start 211.438998 -63.279782)
		(mid 211.572004 -63.334912)
		(end 211.704936 -63.279782)
		(stroke
			(width 0.0508)
			(type default)
		)
		(layer "In5.Cu")
	)
	(gr_arc
		(start 211.6074 -65.723008)
		(mid 211.740496 -65.778138)
		(end 211.873592 -65.723008)
		(stroke
			(width 0.0508)
			(type default)
		)
		(layer "In5.Cu")
	)
	(gr_line
		(start 211.698078 -46.14799)
		(end 211.717128 -46.16069)
		(stroke
			(width 0.0508)
			(type default)
		)
		(layer "In5.Cu")
	)
	(gr_line
		(start 211.704936 -63.279782)
		(end 211.868258 -63.11646)
		(stroke
			(width 0.0508)
			(type default)
		)
		(layer "In5.Cu")
	)
	(gr_line
		(start 211.717128 -46.16069)
		(end 211.729828 -46.17974)
		(stroke
			(width 0.0508)
			(type default)
		)
		(layer "In5.Cu")
	)
	(gr_line
		(start 211.873592 -65.723008)
		(end 212.036914 -65.559686)
		(stroke
			(width 0.0508)
			(type default)
		)
		(layer "In5.Cu")
	)
	(gr_line
		(start 212.240622 -45.28312)
		(end 212.258148 -45.294804)
		(stroke
			(width 0.0508)
			(type default)
		)
		(layer "In5.Cu")
	)
	(gr_line
		(start 212.258148 -45.294804)
		(end 212.270086 -45.31233)
		(stroke
			(width 0.0508)
			(type default)
		)
		(layer "In5.Cu")
	)
	(gr_line
		(start 212.41258 -61.55182)
		(end 212.423248 -61.498734)
		(stroke
			(width 0.0508)
			(type default)
		)
		(layer "In5.Cu")
	)
	(gr_line
		(start 212.701886 -68.018914)
		(end 212.864954 -67.855846)
		(stroke
			(width 0.0508)
			(type default)
		)
		(layer "In5.Cu")
	)
	(gr_line
		(start 212.792564 -44.360338)
		(end 212.81009 -44.372022)
		(stroke
			(width 0.0508)
			(type default)
		)
		(layer "In5.Cu")
	)
	(gr_line
		(start 212.81009 -44.372022)
		(end 212.822028 -44.389548)
		(stroke
			(width 0.0508)
			(type default)
		)
		(layer "In5.Cu")
	)
	(gr_arc
		(start 212.864954 -67.855846)
		(mid 212.920132 -67.722735)
		(end 212.864954 -67.589654)
		(stroke
			(width 0.0508)
			(type default)
		)
		(layer "In5.Cu")
	)
	(gr_line
		(start 212.955378 -48.017938)
		(end 212.96757 -48.035972)
		(stroke
			(width 0.0508)
			(type default)
		)
		(layer "In5.Cu")
	)
	(gr_line
		(start 212.96757 -48.035972)
		(end 212.971888 -48.057562)
		(stroke
			(width 0.0508)
			(type default)
		)
		(layer "In5.Cu")
	)
	(gr_arc
		(start 213.0806 -67.374008)
		(mid 213.213696 -67.429138)
		(end 213.346792 -67.374008)
		(stroke
			(width 0.0508)
			(type default)
		)
		(layer "In5.Cu")
	)
	(gr_line
		(start 213.346792 -67.374008)
		(end 213.510114 -67.210686)
		(stroke
			(width 0.0508)
			(type default)
		)
		(layer "In5.Cu")
	)
	(gr_line
		(start 213.471506 -63.007494)
		(end 213.482174 -62.954408)
		(stroke
			(width 0.0508)
			(type default)
		)
		(layer "In5.Cu")
	)
	(gr_line
		(start 213.717886 -72.794114)
		(end 213.880954 -72.631046)
		(stroke
			(width 0.0508)
			(type default)
		)
		(layer "In5.Cu")
	)
	(gr_line
		(start 213.803484 -44.04233)
		(end 213.822534 -44.05503)
		(stroke
			(width 0.0508)
			(type default)
		)
		(layer "In5.Cu")
	)
	(gr_line
		(start 213.822534 -44.05503)
		(end 213.835234 -44.07408)
		(stroke
			(width 0.0508)
			(type default)
		)
		(layer "In5.Cu")
	)
	(gr_line
		(start 213.869524 -47.683674)
		(end 213.882732 -47.702978)
		(stroke
			(width 0.0508)
			(type default)
		)
		(layer "In5.Cu")
	)
	(gr_arc
		(start 213.880954 -72.631046)
		(mid 213.936132 -72.497935)
		(end 213.880954 -72.364854)
		(stroke
			(width 0.0508)
			(type default)
		)
		(layer "In5.Cu")
	)
	(gr_line
		(start 213.882732 -47.702978)
		(end 213.887304 -47.726346)
		(stroke
			(width 0.0508)
			(type default)
		)
		(layer "In5.Cu")
	)
	(gr_line
		(start 214.03691 -53.43144)
		(end 214.041228 -53.40985)
		(stroke
			(width 0.0508)
			(type default)
		)
		(layer "In5.Cu")
	)
	(gr_line
		(start 214.03691 -53.38826)
		(end 214.041228 -53.40985)
		(stroke
			(width 0.0508)
			(type default)
		)
		(layer "In5.Cu")
	)
	(gr_arc
		(start 214.0966 -72.149208)
		(mid 214.229696 -72.204338)
		(end 214.362792 -72.149208)
		(stroke
			(width 0.0508)
			(type default)
		)
		(layer "In5.Cu")
	)
	(gr_line
		(start 214.225886 -69.492114)
		(end 214.388954 -69.329046)
		(stroke
			(width 0.0508)
			(type default)
		)
		(layer "In5.Cu")
	)
	(gr_line
		(start 214.291164 -65.286636)
		(end 214.301832 -65.23355)
		(stroke
			(width 0.0508)
			(type default)
		)
		(layer "In5.Cu")
	)
	(gr_line
		(start 214.362792 -72.149208)
		(end 214.526114 -71.985886)
		(stroke
			(width 0.0508)
			(type default)
		)
		(layer "In5.Cu")
	)
	(gr_arc
		(start 214.388954 -69.329046)
		(mid 214.444132 -69.195935)
		(end 214.388954 -69.062854)
		(stroke
			(width 0.0508)
			(type default)
		)
		(layer "In5.Cu")
	)
	(gr_arc
		(start 214.6046 -68.847208)
		(mid 214.737696 -68.902338)
		(end 214.870792 -68.847208)
		(stroke
			(width 0.0508)
			(type default)
		)
		(layer "In5.Cu")
	)
	(gr_line
		(start 214.800688 -43.694096)
		(end 214.819738 -43.706796)
		(stroke
			(width 0.0508)
			(type default)
		)
		(layer "In5.Cu")
	)
	(gr_line
		(start 214.819738 -43.706796)
		(end 214.832438 -43.725846)
		(stroke
			(width 0.0508)
			(type default)
		)
		(layer "In5.Cu")
	)
	(gr_line
		(start 214.870792 -68.847208)
		(end 215.034114 -68.683886)
		(stroke
			(width 0.0508)
			(type default)
		)
		(layer "In5.Cu")
	)
	(gr_line
		(start 214.962994 -47.563786)
		(end 214.976202 -47.58309)
		(stroke
			(width 0.0508)
			(type default)
		)
		(layer "In5.Cu")
	)
	(gr_line
		(start 214.976202 -47.58309)
		(end 214.980774 -47.606458)
		(stroke
			(width 0.0508)
			(type default)
		)
		(layer "In5.Cu")
	)
	(gr_line
		(start 215.114886 -74.191114)
		(end 215.277954 -74.028046)
		(stroke
			(width 0.0508)
			(type default)
		)
		(layer "In5.Cu")
	)
	(gr_line
		(start 215.184482 -54.443884)
		(end 215.1888 -54.421786)
		(stroke
			(width 0.0508)
			(type default)
		)
		(layer "In5.Cu")
	)
	(gr_line
		(start 215.184482 -54.399434)
		(end 215.1888 -54.421786)
		(stroke
			(width 0.0508)
			(type default)
		)
		(layer "In5.Cu")
	)
	(gr_line
		(start 215.277192 -67.297808)
		(end 215.28786 -67.244722)
		(stroke
			(width 0.0508)
			(type default)
		)
		(layer "In5.Cu")
	)
	(gr_arc
		(start 215.277954 -74.028046)
		(mid 215.333132 -73.894935)
		(end 215.277954 -73.761854)
		(stroke
			(width 0.0508)
			(type default)
		)
		(layer "In5.Cu")
	)
	(gr_arc
		(start 215.4936 -73.546208)
		(mid 215.626696 -73.601338)
		(end 215.759792 -73.546208)
		(stroke
			(width 0.0508)
			(type default)
		)
		(layer "In5.Cu")
	)
	(gr_line
		(start 215.495886 -79.652114)
		(end 215.658954 -79.489046)
		(stroke
			(width 0.0508)
			(type default)
		)
		(layer "In5.Cu")
	)
	(gr_arc
		(start 215.658954 -79.489046)
		(mid 215.714084 -79.35595)
		(end 215.658954 -79.222854)
		(stroke
			(width 0.0508)
			(type default)
		)
		(layer "In5.Cu")
	)
	(gr_line
		(start 215.7222 -43.32605)
		(end 215.74125 -43.33875)
		(stroke
			(width 0.0508)
			(type default)
		)
		(layer "In5.Cu")
	)
	(gr_line
		(start 215.74125 -43.33875)
		(end 215.75395 -43.3578)
		(stroke
			(width 0.0508)
			(type default)
		)
		(layer "In5.Cu")
	)
	(gr_line
		(start 215.759792 -73.546208)
		(end 215.923114 -73.382886)
		(stroke
			(width 0.0508)
			(type default)
		)
		(layer "In5.Cu")
	)
	(gr_arc
		(start 215.8746 -79.007208)
		(mid 216.007696 -79.062338)
		(end 216.140792 -79.007208)
		(stroke
			(width 0.0508)
			(type default)
		)
		(layer "In5.Cu")
	)
	(gr_line
		(start 215.89111 -47.158402)
		(end 215.903302 -47.176436)
		(stroke
			(width 0.0508)
			(type default)
		)
		(layer "In5.Cu")
	)
	(gr_line
		(start 215.903302 -47.176436)
		(end 215.907366 -47.197772)
		(stroke
			(width 0.0508)
			(type default)
		)
		(layer "In5.Cu")
	)
	(gr_line
		(start 216.140792 -79.007208)
		(end 216.304114 -78.843886)
		(stroke
			(width 0.0508)
			(type default)
		)
		(layer "In5.Cu")
	)
	(gr_line
		(start 216.379298 -54.84495)
		(end 216.383616 -54.822852)
		(stroke
			(width 0.0508)
			(type default)
		)
		(layer "In5.Cu")
	)
	(gr_line
		(start 216.379298 -54.8005)
		(end 216.383616 -54.822852)
		(stroke
			(width 0.0508)
			(type default)
		)
		(layer "In5.Cu")
	)
	(gr_line
		(start 216.569798 -42.867326)
		(end 216.588848 -42.880026)
		(stroke
			(width 0.0508)
			(type default)
		)
		(layer "In5.Cu")
	)
	(gr_line
		(start 216.588848 -42.880026)
		(end 216.601548 -42.899076)
		(stroke
			(width 0.0508)
			(type default)
		)
		(layer "In5.Cu")
	)
	(gr_line
		(start 216.606374 -68.762626)
		(end 216.617042 -68.70954)
		(stroke
			(width 0.0508)
			(type default)
		)
		(layer "In5.Cu")
	)
	(gr_line
		(start 216.638886 -75.715114)
		(end 216.801954 -75.552046)
		(stroke
			(width 0.0508)
			(type default)
		)
		(layer "In5.Cu")
	)
	(gr_arc
		(start 216.801954 -75.552046)
		(mid 216.857132 -75.418935)
		(end 216.801954 -75.285854)
		(stroke
			(width 0.0508)
			(type default)
		)
		(layer "In5.Cu")
	)
	(gr_line
		(start 216.941146 -46.889162)
		(end 216.953338 -46.907196)
		(stroke
			(width 0.0508)
			(type default)
		)
		(layer "In5.Cu")
	)
	(gr_line
		(start 216.953338 -46.907196)
		(end 216.957402 -46.928532)
		(stroke
			(width 0.0508)
			(type default)
		)
		(layer "In5.Cu")
	)
	(gr_arc
		(start 217.0176 -75.070208)
		(mid 217.150696 -75.125338)
		(end 217.283792 -75.070208)
		(stroke
			(width 0.0508)
			(type default)
		)
		(layer "In5.Cu")
	)
	(gr_line
		(start 217.283792 -75.070208)
		(end 217.447114 -74.906886)
		(stroke
			(width 0.0508)
			(type default)
		)
		(layer "In5.Cu")
	)
	(gr_line
		(start 217.330528 -42.325036)
		(end 217.349578 -42.337736)
		(stroke
			(width 0.0508)
			(type default)
		)
		(layer "In5.Cu")
	)
	(gr_line
		(start 217.349578 -42.337736)
		(end 217.362278 -42.356786)
		(stroke
			(width 0.0508)
			(type default)
		)
		(layer "In5.Cu")
	)
	(gr_line
		(start 217.59799 -55.694072)
		(end 217.602308 -55.672482)
		(stroke
			(width 0.0508)
			(type default)
		)
		(layer "In5.Cu")
	)
	(gr_line
		(start 217.59799 -55.650892)
		(end 217.602308 -55.672482)
		(stroke
			(width 0.0508)
			(type default)
		)
		(layer "In5.Cu")
	)
	(gr_line
		(start 217.859356 -69.534278)
		(end 217.872056 -69.515482)
		(stroke
			(width 0.0508)
			(type default)
		)
		(layer "In5.Cu")
	)
	(gr_line
		(start 217.872056 -69.515482)
		(end 217.876628 -69.492876)
		(stroke
			(width 0.0508)
			(type default)
		)
		(layer "In5.Cu")
	)
	(gr_line
		(start 217.931492 -46.623986)
		(end 217.944192 -46.642782)
		(stroke
			(width 0.0508)
			(type default)
		)
		(layer "In5.Cu")
	)
	(gr_line
		(start 217.944192 -46.642782)
		(end 217.948764 -46.665388)
		(stroke
			(width 0.0508)
			(type default)
		)
		(layer "In5.Cu")
	)
	(gr_line
		(start 218.312238 -72.44715)
		(end 218.324938 -72.428354)
		(stroke
			(width 0.0508)
			(type default)
		)
		(layer "In5.Cu")
	)
	(gr_line
		(start 218.324938 -72.428354)
		(end 218.32951 -72.405748)
		(stroke
			(width 0.0508)
			(type default)
		)
		(layer "In5.Cu")
	)
	(gr_line
		(start 218.843098 -46.261274)
		(end 218.855798 -46.28007)
		(stroke
			(width 0.0508)
			(type default)
		)
		(layer "In5.Cu")
	)
	(gr_line
		(start 218.855798 -46.28007)
		(end 218.86037 -46.302676)
		(stroke
			(width 0.0508)
			(type default)
		)
		(layer "In5.Cu")
	)
	(gr_line
		(start 218.960446 -56.990488)
		(end 218.964764 -56.968898)
		(stroke
			(width 0.0508)
			(type default)
		)
		(layer "In5.Cu")
	)
	(gr_line
		(start 218.960446 -56.947308)
		(end 218.964764 -56.968898)
		(stroke
			(width 0.0508)
			(type default)
		)
		(layer "In5.Cu")
	)
	(gr_line
		(start 219.356686 -74.007726)
		(end 219.369386 -73.98893)
		(stroke
			(width 0.0508)
			(type default)
		)
		(layer "In5.Cu")
	)
	(gr_line
		(start 219.369386 -73.98893)
		(end 219.373958 -73.966324)
		(stroke
			(width 0.0508)
			(type default)
		)
		(layer "In5.Cu")
	)
	(gr_line
		(start 219.920058 -46.194472)
		(end 219.93225 -46.212506)
		(stroke
			(width 0.0508)
			(type default)
		)
		(layer "In5.Cu")
	)
	(gr_line
		(start 219.93225 -46.212506)
		(end 219.936314 -46.233842)
		(stroke
			(width 0.0508)
			(type default)
		)
		(layer "In5.Cu")
	)
	(gr_line
		(start 220.190568 -57.921144)
		(end 220.194886 -57.899554)
		(stroke
			(width 0.0508)
			(type default)
		)
		(layer "In5.Cu")
	)
	(gr_line
		(start 220.190568 -57.877964)
		(end 220.194886 -57.899554)
		(stroke
			(width 0.0508)
			(type default)
		)
		(layer "In5.Cu")
	)
	(gr_line
		(start 221.201234 -58.050684)
		(end 221.205552 -58.029094)
		(stroke
			(width 0.0508)
			(type default)
		)
		(layer "In5.Cu")
	)
	(gr_line
		(start 221.201234 -58.007504)
		(end 221.205552 -58.029094)
		(stroke
			(width 0.0508)
			(type default)
		)
		(layer "In5.Cu")
	)
	(gr_line
		(start 222.424498 -58.715656)
		(end 222.428816 -58.694066)
		(stroke
			(width 0.0508)
			(type default)
		)
		(layer "In5.Cu")
	)
	(gr_line
		(start 222.424498 -58.672476)
		(end 222.428816 -58.694066)
		(stroke
			(width 0.0508)
			(type default)
		)
		(layer "In5.Cu")
	)
	(gr_line
		(start 0 -183.76392)
		(end 0 -0.999998)
		(stroke
			(width 1.524)
			(type default)
		)
		(layer "In6.Cu")
	)
	(gr_arc
		(start 0 -183.76392)
		(mid 0.026807 -183.993715)
		(end 0.105664 -184.211214)
		(stroke
			(width 1.524)
			(type default)
		)
		(layer "In6.Cu")
	)
	(gr_arc
		(start 0.999998 0)
		(mid 0.292893 -0.292893)
		(end 0 -0.999998)
		(stroke
			(width 1.524)
			(type default)
		)
		(layer "In6.Cu")
	)
	(gr_line
		(start 0.999998 0)
		(end 29.53004 0)
		(stroke
			(width 1.524)
			(type default)
		)
		(layer "In6.Cu")
	)
	(gr_line
		(start 4.723638 -193.447162)
		(end 0.105664 -184.211214)
		(stroke
			(width 1.524)
			(type default)
		)
		(layer "In6.Cu")
	)
	(gr_arc
		(start 4.723638 -193.447162)
		(mid 5.092281 -193.850645)
		(end 5.617972 -194.00012)
		(stroke
			(width 1.524)
			(type default)
		)
		(layer "In6.Cu")
	)
	(gr_arc
		(start 30.530038 -109.050074)
		(mid 30.822931 -109.757179)
		(end 31.530036 -110.050072)
		(stroke
			(width 1.524)
			(type default)
		)
		(layer "In6.Cu")
	)
	(gr_arc
		(start 30.530038 -0.999998)
		(mid 30.237147 -0.29288)
		(end 29.53004 0)
		(stroke
			(width 1.524)
			(type default)
		)
		(layer "In6.Cu")
	)
	(gr_line
		(start 30.530038 -0.999998)
		(end 30.530038 -109.050074)
		(stroke
			(width 1.524)
			(type default)
		)
		(layer "In6.Cu")
	)
	(gr_line
		(start 31.530036 -110.050072)
		(end 72.030082 -110.050072)
		(stroke
			(width 1.524)
			(type default)
		)
		(layer "In6.Cu")
	)
	(gr_arc
		(start 72.030082 -110.050072)
		(mid 72.737187 -109.757179)
		(end 73.03008 -109.050074)
		(stroke
			(width 1.524)
			(type default)
		)
		(layer "In6.Cu")
	)
	(gr_line
		(start 73.03008 -109.050074)
		(end 73.03008 -0.999998)
		(stroke
			(width 1.524)
			(type default)
		)
		(layer "In6.Cu")
	)
	(gr_arc
		(start 74.030078 0)
		(mid 73.322986 -0.2929)
		(end 73.03008 -0.999998)
		(stroke
			(width 1.524)
			(type default)
		)
		(layer "In6.Cu")
	)
	(gr_line
		(start 74.030078 0)
		(end 234.00004 0)
		(stroke
			(width 1.524)
			(type default)
		)
		(layer "In6.Cu")
	)
	(gr_arc
		(start 76.891134 -68.211192)
		(mid 77.274674 -68.594732)
		(end 77.658214 -68.211192)
		(stroke
			(width 0.2)
			(type default)
		)
		(layer "In6.Cu")
	)
	(gr_line
		(start 76.891134 -67.322192)
		(end 76.891134 -68.211192)
		(stroke
			(width 0.2)
			(type default)
		)
		(layer "In6.Cu")
	)
	(gr_arc
		(start 76.900278 -93.799914)
		(mid 77.283691 -94.183708)
		(end 77.667358 -93.800168)
		(stroke
			(width 0.2)
			(type default)
		)
		(layer "In6.Cu")
	)
	(gr_line
		(start 76.900278 -92.911168)
		(end 76.900278 -93.799914)
		(stroke
			(width 0.2)
			(type default)
		)
		(layer "In6.Cu")
	)
	(gr_arc
		(start 76.900278 -87.399114)
		(mid 77.283691 -87.782908)
		(end 77.667358 -87.399368)
		(stroke
			(width 0.2)
			(type default)
		)
		(layer "In6.Cu")
	)
	(gr_line
		(start 76.900278 -86.510368)
		(end 76.900278 -87.399114)
		(stroke
			(width 0.2)
			(type default)
		)
		(layer "In6.Cu")
	)
	(gr_arc
		(start 76.900278 -80.998314)
		(mid 77.283691 -81.382108)
		(end 77.667358 -80.998568)
		(stroke
			(width 0.2)
			(type default)
		)
		(layer "In6.Cu")
	)
	(gr_line
		(start 76.900278 -80.109568)
		(end 76.900278 -80.998314)
		(stroke
			(width 0.2)
			(type default)
		)
		(layer "In6.Cu")
	)
	(gr_arc
		(start 76.900278 -74.597514)
		(mid 77.283691 -74.981308)
		(end 77.667358 -74.597768)
		(stroke
			(width 0.2)
			(type default)
		)
		(layer "In6.Cu")
	)
	(gr_line
		(start 76.900278 -73.708768)
		(end 76.900278 -74.597514)
		(stroke
			(width 0.2)
			(type default)
		)
		(layer "In6.Cu")
	)
	(gr_line
		(start 77.658214 -68.211192)
		(end 77.658214 -67.322446)
		(stroke
			(width 0.2)
			(type default)
		)
		(layer "In6.Cu")
	)
	(gr_arc
		(start 77.658214 -67.322446)
		(mid 77.274801 -66.938652)
		(end 76.891134 -67.322192)
		(stroke
			(width 0.2)
			(type default)
		)
		(layer "In6.Cu")
	)
	(gr_line
		(start 77.667358 -93.800168)
		(end 77.667358 -92.911168)
		(stroke
			(width 0.2)
			(type default)
		)
		(layer "In6.Cu")
	)
	(gr_arc
		(start 77.667358 -92.911168)
		(mid 77.283818 -92.527628)
		(end 76.900278 -92.911168)
		(stroke
			(width 0.2)
			(type default)
		)
		(layer "In6.Cu")
	)
	(gr_line
		(start 77.667358 -87.399368)
		(end 77.667358 -86.510368)
		(stroke
			(width 0.2)
			(type default)
		)
		(layer "In6.Cu")
	)
	(gr_arc
		(start 77.667358 -86.510368)
		(mid 77.283818 -86.126828)
		(end 76.900278 -86.510368)
		(stroke
			(width 0.2)
			(type default)
		)
		(layer "In6.Cu")
	)
	(gr_line
		(start 77.667358 -80.998568)
		(end 77.667358 -80.109568)
		(stroke
			(width 0.2)
			(type default)
		)
		(layer "In6.Cu")
	)
	(gr_arc
		(start 77.667358 -80.109568)
		(mid 77.283818 -79.726028)
		(end 76.900278 -80.109568)
		(stroke
			(width 0.2)
			(type default)
		)
		(layer "In6.Cu")
	)
	(gr_line
		(start 77.667358 -74.597768)
		(end 77.667358 -73.708768)
		(stroke
			(width 0.2)
			(type default)
		)
		(layer "In6.Cu")
	)
	(gr_arc
		(start 77.667358 -73.708768)
		(mid 77.283818 -73.325228)
		(end 76.900278 -73.708768)
		(stroke
			(width 0.2)
			(type default)
		)
		(layer "In6.Cu")
	)
	(gr_arc
		(start 77.738478 -90.599514)
		(mid 78.121891 -90.983308)
		(end 78.505558 -90.599768)
		(stroke
			(width 0.2)
			(type default)
		)
		(layer "In6.Cu")
	)
	(gr_line
		(start 77.738478 -89.710768)
		(end 77.738478 -90.599514)
		(stroke
			(width 0.2)
			(type default)
		)
		(layer "In6.Cu")
	)
	(gr_arc
		(start 77.738478 -84.224114)
		(mid 78.121891 -84.607908)
		(end 78.505558 -84.224368)
		(stroke
			(width 0.2)
			(type default)
		)
		(layer "In6.Cu")
	)
	(gr_line
		(start 77.738478 -83.335368)
		(end 77.738478 -84.224114)
		(stroke
			(width 0.2)
			(type default)
		)
		(layer "In6.Cu")
	)
	(gr_arc
		(start 77.738478 -77.797914)
		(mid 78.121891 -78.181708)
		(end 78.505558 -77.798168)
		(stroke
			(width 0.2)
			(type default)
		)
		(layer "In6.Cu")
	)
	(gr_line
		(start 77.738478 -76.909168)
		(end 77.738478 -77.797914)
		(stroke
			(width 0.2)
			(type default)
		)
		(layer "In6.Cu")
	)
	(gr_arc
		(start 77.738478 -71.397114)
		(mid 78.121891 -71.780908)
		(end 78.505558 -71.397368)
		(stroke
			(width 0.2)
			(type default)
		)
		(layer "In6.Cu")
	)
	(gr_line
		(start 77.738478 -70.508368)
		(end 77.738478 -71.397114)
		(stroke
			(width 0.2)
			(type default)
		)
		(layer "In6.Cu")
	)
	(gr_line
		(start 78.505558 -90.599768)
		(end 78.505558 -89.710768)
		(stroke
			(width 0.2)
			(type default)
		)
		(layer "In6.Cu")
	)
	(gr_arc
		(start 78.505558 -89.710768)
		(mid 78.122018 -89.327228)
		(end 77.738478 -89.710768)
		(stroke
			(width 0.2)
			(type default)
		)
		(layer "In6.Cu")
	)
	(gr_line
		(start 78.505558 -84.224368)
		(end 78.505558 -83.335368)
		(stroke
			(width 0.2)
			(type default)
		)
		(layer "In6.Cu")
	)
	(gr_arc
		(start 78.505558 -83.335368)
		(mid 78.122018 -82.951828)
		(end 77.738478 -83.335368)
		(stroke
			(width 0.2)
			(type default)
		)
		(layer "In6.Cu")
	)
	(gr_line
		(start 78.505558 -77.798168)
		(end 78.505558 -76.909168)
		(stroke
			(width 0.2)
			(type default)
		)
		(layer "In6.Cu")
	)
	(gr_arc
		(start 78.505558 -76.909168)
		(mid 78.122018 -76.525628)
		(end 77.738478 -76.909168)
		(stroke
			(width 0.2)
			(type default)
		)
		(layer "In6.Cu")
	)
	(gr_line
		(start 78.505558 -71.397368)
		(end 78.505558 -70.508368)
		(stroke
			(width 0.2)
			(type default)
		)
		(layer "In6.Cu")
	)
	(gr_arc
		(start 78.505558 -70.508368)
		(mid 78.122018 -70.124828)
		(end 77.738478 -70.508368)
		(stroke
			(width 0.2)
			(type default)
		)
		(layer "In6.Cu")
	)
	(gr_arc
		(start 82.974688 -95.381318)
		(mid 83.358101 -95.765112)
		(end 83.741768 -95.381572)
		(stroke
			(width 0.2)
			(type default)
		)
		(layer "In6.Cu")
	)
	(gr_line
		(start 82.974688 -94.492572)
		(end 82.974688 -95.381318)
		(stroke
			(width 0.2)
			(type default)
		)
		(layer "In6.Cu")
	)
	(gr_arc
		(start 82.974688 -88.994234)
		(mid 83.358228 -89.377774)
		(end 83.741768 -88.994234)
		(stroke
			(width 0.2)
			(type default)
		)
		(layer "In6.Cu")
	)
	(gr_line
		(start 82.974688 -88.105234)
		(end 82.974688 -88.994234)
		(stroke
			(width 0.2)
			(type default)
		)
		(layer "In6.Cu")
	)
	(gr_arc
		(start 82.974688 -82.593942)
		(mid 83.358101 -82.977736)
		(end 83.741768 -82.594196)
		(stroke
			(width 0.2)
			(type default)
		)
		(layer "In6.Cu")
	)
	(gr_line
		(start 82.974688 -81.705196)
		(end 82.974688 -82.593942)
		(stroke
			(width 0.2)
			(type default)
		)
		(layer "In6.Cu")
	)
	(gr_arc
		(start 82.974688 -76.193904)
		(mid 83.358101 -76.577698)
		(end 83.741768 -76.194158)
		(stroke
			(width 0.2)
			(type default)
		)
		(layer "In6.Cu")
	)
	(gr_line
		(start 82.974688 -75.305158)
		(end 82.974688 -76.193904)
		(stroke
			(width 0.2)
			(type default)
		)
		(layer "In6.Cu")
	)
	(gr_line
		(start 83.741768 -95.381572)
		(end 83.741768 -94.492572)
		(stroke
			(width 0.2)
			(type default)
		)
		(layer "In6.Cu")
	)
	(gr_arc
		(start 83.741768 -94.492572)
		(mid 83.358228 -94.109032)
		(end 82.974688 -94.492572)
		(stroke
			(width 0.2)
			(type default)
		)
		(layer "In6.Cu")
	)
	(gr_line
		(start 83.741768 -88.994234)
		(end 83.741768 -88.105488)
		(stroke
			(width 0.2)
			(type default)
		)
		(layer "In6.Cu")
	)
	(gr_arc
		(start 83.741768 -88.105488)
		(mid 83.358355 -87.721694)
		(end 82.974688 -88.105234)
		(stroke
			(width 0.2)
			(type default)
		)
		(layer "In6.Cu")
	)
	(gr_line
		(start 83.741768 -82.594196)
		(end 83.741768 -81.705196)
		(stroke
			(width 0.2)
			(type default)
		)
		(layer "In6.Cu")
	)
	(gr_arc
		(start 83.741768 -81.705196)
		(mid 83.358228 -81.321656)
		(end 82.974688 -81.705196)
		(stroke
			(width 0.2)
			(type default)
		)
		(layer "In6.Cu")
	)
	(gr_line
		(start 83.741768 -76.194158)
		(end 83.741768 -75.305158)
		(stroke
			(width 0.2)
			(type default)
		)
		(layer "In6.Cu")
	)
	(gr_arc
		(start 83.741768 -75.305158)
		(mid 83.358228 -74.921618)
		(end 82.974688 -75.305158)
		(stroke
			(width 0.2)
			(type default)
		)
		(layer "In6.Cu")
	)
	(gr_arc
		(start 84.600288 -92.195142)
		(mid 84.983701 -92.578936)
		(end 85.367368 -92.195396)
		(stroke
			(width 0.2)
			(type default)
		)
		(layer "In6.Cu")
	)
	(gr_line
		(start 84.600288 -91.306396)
		(end 84.600288 -92.195142)
		(stroke
			(width 0.2)
			(type default)
		)
		(layer "In6.Cu")
	)
	(gr_arc
		(start 84.600288 -85.79358)
		(mid 84.983701 -86.177374)
		(end 85.367368 -85.793834)
		(stroke
			(width 0.2)
			(type default)
		)
		(layer "In6.Cu")
	)
	(gr_line
		(start 84.600288 -84.904834)
		(end 84.600288 -85.79358)
		(stroke
			(width 0.2)
			(type default)
		)
		(layer "In6.Cu")
	)
	(gr_arc
		(start 84.600288 -79.393542)
		(mid 84.983701 -79.777336)
		(end 85.367368 -79.393796)
		(stroke
			(width 0.2)
			(type default)
		)
		(layer "In6.Cu")
	)
	(gr_line
		(start 84.600288 -78.504796)
		(end 84.600288 -79.393542)
		(stroke
			(width 0.2)
			(type default)
		)
		(layer "In6.Cu")
	)
	(gr_arc
		(start 84.600288 -72.970136)
		(mid 84.983828 -73.353676)
		(end 85.367368 -72.970136)
		(stroke
			(width 0.2)
			(type default)
		)
		(layer "In6.Cu")
	)
	(gr_line
		(start 84.600288 -72.081136)
		(end 84.600288 -72.970136)
		(stroke
			(width 0.2)
			(type default)
		)
		(layer "In6.Cu")
	)
	(gr_line
		(start 85.367368 -92.195396)
		(end 85.367368 -91.306396)
		(stroke
			(width 0.2)
			(type default)
		)
		(layer "In6.Cu")
	)
	(gr_arc
		(start 85.367368 -91.306396)
		(mid 84.983828 -90.922856)
		(end 84.600288 -91.306396)
		(stroke
			(width 0.2)
			(type default)
		)
		(layer "In6.Cu")
	)
	(gr_line
		(start 85.367368 -85.793834)
		(end 85.367368 -84.904834)
		(stroke
			(width 0.2)
			(type default)
		)
		(layer "In6.Cu")
	)
	(gr_arc
		(start 85.367368 -84.904834)
		(mid 84.983828 -84.521294)
		(end 84.600288 -84.904834)
		(stroke
			(width 0.2)
			(type default)
		)
		(layer "In6.Cu")
	)
	(gr_line
		(start 85.367368 -79.393796)
		(end 85.367368 -78.504796)
		(stroke
			(width 0.2)
			(type default)
		)
		(layer "In6.Cu")
	)
	(gr_arc
		(start 85.367368 -78.504796)
		(mid 84.983828 -78.121256)
		(end 84.600288 -78.504796)
		(stroke
			(width 0.2)
			(type default)
		)
		(layer "In6.Cu")
	)
	(gr_line
		(start 85.367368 -72.970136)
		(end 85.367368 -72.08139)
		(stroke
			(width 0.2)
			(type default)
		)
		(layer "In6.Cu")
	)
	(gr_arc
		(start 85.367368 -72.08139)
		(mid 84.983955 -71.697596)
		(end 84.600288 -72.081136)
		(stroke
			(width 0.2)
			(type default)
		)
		(layer "In6.Cu")
	)
	(gr_line
		(start 98.081846 -194.00012)
		(end 5.617972 -194.00012)
		(stroke
			(width 1.524)
			(type default)
		)
		(layer "In6.Cu")
	)
	(gr_arc
		(start 98.081846 -194.00012)
		(mid 98.607706 -193.850755)
		(end 98.976434 -193.447162)
		(stroke
			(width 1.524)
			(type default)
		)
		(layer "In6.Cu")
	)
	(gr_line
		(start 103.594408 -184.211214)
		(end 98.976434 -193.447162)
		(stroke
			(width 1.524)
			(type default)
		)
		(layer "In6.Cu")
	)
	(gr_arc
		(start 103.594408 -184.211214)
		(mid 103.673311 -183.993725)
		(end 103.700072 -183.76392)
		(stroke
			(width 1.524)
			(type default)
		)
		(layer "In6.Cu")
	)
	(gr_line
		(start 103.700072 -47.999904)
		(end 103.700072 -183.76392)
		(stroke
			(width 1.524)
			(type default)
		)
		(layer "In6.Cu")
	)
	(gr_arc
		(start 104.70007 -47.999904)
		(mid 104.200198 -47.500032)
		(end 103.700072 -47.999904)
		(stroke
			(width 1.524)
			(type default)
		)
		(layer "In6.Cu")
	)
	(gr_arc
		(start 106.614722 -38.200076)
		(mid 107.099862 -38.685216)
		(end 107.585002 -38.200076)
		(stroke
			(width 0.2)
			(type default)
		)
		(layer "In6.Cu")
	)
	(gr_line
		(start 106.614722 -36.800028)
		(end 106.614722 -38.200076)
		(stroke
			(width 0.2)
			(type default)
		)
		(layer "In6.Cu")
	)
	(gr_arc
		(start 106.614722 -34.600134)
		(mid 107.099862 -35.085274)
		(end 107.585002 -34.600134)
		(stroke
			(width 0.2)
			(type default)
		)
		(layer "In6.Cu")
	)
	(gr_line
		(start 106.614722 -33.200086)
		(end 106.614722 -34.600134)
		(stroke
			(width 0.2)
			(type default)
		)
		(layer "In6.Cu")
	)
	(gr_line
		(start 107.585002 -38.200076)
		(end 107.585002 -36.800282)
		(stroke
			(width 0.2)
			(type default)
		)
		(layer "In6.Cu")
	)
	(gr_arc
		(start 107.585002 -36.800282)
		(mid 107.099989 -36.314888)
		(end 106.614722 -36.800028)
		(stroke
			(width 0.2)
			(type default)
		)
		(layer "In6.Cu")
	)
	(gr_line
		(start 107.585002 -34.600134)
		(end 107.585002 -33.20034)
		(stroke
			(width 0.2)
			(type default)
		)
		(layer "In6.Cu")
	)
	(gr_arc
		(start 107.585002 -33.20034)
		(mid 107.099989 -32.714946)
		(end 106.614722 -33.200086)
		(stroke
			(width 0.2)
			(type default)
		)
		(layer "In6.Cu")
	)
	(gr_arc
		(start 108.41482 -37.00018)
		(mid 108.89996 -37.48532)
		(end 109.3851 -37.00018)
		(stroke
			(width 0.2)
			(type default)
		)
		(layer "In6.Cu")
	)
	(gr_line
		(start 108.41482 -35.600132)
		(end 108.41482 -37.00018)
		(stroke
			(width 0.2)
			(type default)
		)
		(layer "In6.Cu")
	)
	(gr_arc
		(start 108.41482 -33.399984)
		(mid 108.89996 -33.885124)
		(end 109.3851 -33.399984)
		(stroke
			(width 0.2)
			(type default)
		)
		(layer "In6.Cu")
	)
	(gr_line
		(start 108.41482 -32.00019)
		(end 108.41482 -33.399984)
		(stroke
			(width 0.2)
			(type default)
		)
		(layer "In6.Cu")
	)
	(gr_line
		(start 109.3851 -37.00018)
		(end 109.3851 -35.600386)
		(stroke
			(width 0.2)
			(type default)
		)
		(layer "In6.Cu")
	)
	(gr_arc
		(start 109.3851 -35.600386)
		(mid 108.900087 -35.114992)
		(end 108.41482 -35.600132)
		(stroke
			(width 0.2)
			(type default)
		)
		(layer "In6.Cu")
	)
	(gr_line
		(start 109.3851 -33.399984)
		(end 109.3851 -32.000444)
		(stroke
			(width 0.2)
			(type default)
		)
		(layer "In6.Cu")
	)
	(gr_arc
		(start 109.3851 -32.000444)
		(mid 108.900087 -31.51505)
		(end 108.41482 -32.00019)
		(stroke
			(width 0.2)
			(type default)
		)
		(layer "In6.Cu")
	)
	(gr_arc
		(start 110.214918 -38.200076)
		(mid 110.700058 -38.685216)
		(end 111.185198 -38.200076)
		(stroke
			(width 0.2)
			(type default)
		)
		(layer "In6.Cu")
	)
	(gr_line
		(start 110.214918 -36.800028)
		(end 110.214918 -38.200076)
		(stroke
			(width 0.2)
			(type default)
		)
		(layer "In6.Cu")
	)
	(gr_arc
		(start 110.214918 -34.600134)
		(mid 110.700058 -35.085274)
		(end 111.185198 -34.600134)
		(stroke
			(width 0.2)
			(type default)
		)
		(layer "In6.Cu")
	)
	(gr_line
		(start 110.214918 -33.200086)
		(end 110.214918 -34.600134)
		(stroke
			(width 0.2)
			(type default)
		)
		(layer "In6.Cu")
	)
	(gr_line
		(start 111.185198 -38.200076)
		(end 111.185198 -36.800282)
		(stroke
			(width 0.2)
			(type default)
		)
		(layer "In6.Cu")
	)
	(gr_arc
		(start 111.185198 -36.800282)
		(mid 110.700185 -36.314888)
		(end 110.214918 -36.800028)
		(stroke
			(width 0.2)
			(type default)
		)
		(layer "In6.Cu")
	)
	(gr_line
		(start 111.185198 -34.600134)
		(end 111.185198 -33.20034)
		(stroke
			(width 0.2)
			(type default)
		)
		(layer "In6.Cu")
	)
	(gr_arc
		(start 111.185198 -33.20034)
		(mid 110.700185 -32.714946)
		(end 110.214918 -33.200086)
		(stroke
			(width 0.2)
			(type default)
		)
		(layer "In6.Cu")
	)
	(gr_arc
		(start 112.014762 -37.00018)
		(mid 112.499902 -37.48532)
		(end 112.985042 -37.00018)
		(stroke
			(width 0.2)
			(type default)
		)
		(layer "In6.Cu")
	)
	(gr_line
		(start 112.014762 -35.600132)
		(end 112.014762 -37.00018)
		(stroke
			(width 0.2)
			(type default)
		)
		(layer "In6.Cu")
	)
	(gr_arc
		(start 112.014762 -33.399984)
		(mid 112.499902 -33.885124)
		(end 112.985042 -33.399984)
		(stroke
			(width 0.2)
			(type default)
		)
		(layer "In6.Cu")
	)
	(gr_line
		(start 112.014762 -32.00019)
		(end 112.014762 -33.399984)
		(stroke
			(width 0.2)
			(type default)
		)
		(layer "In6.Cu")
	)
	(gr_line
		(start 112.985042 -37.00018)
		(end 112.985042 -35.600386)
		(stroke
			(width 0.2)
			(type default)
		)
		(layer "In6.Cu")
	)
	(gr_arc
		(start 112.985042 -35.600386)
		(mid 112.500029 -35.114992)
		(end 112.014762 -35.600132)
		(stroke
			(width 0.2)
			(type default)
		)
		(layer "In6.Cu")
	)
	(gr_line
		(start 112.985042 -33.399984)
		(end 112.985042 -32.000444)
		(stroke
			(width 0.2)
			(type default)
		)
		(layer "In6.Cu")
	)
	(gr_arc
		(start 112.985042 -32.000444)
		(mid 112.500029 -31.51505)
		(end 112.014762 -32.00019)
		(stroke
			(width 0.2)
			(type default)
		)
		(layer "In6.Cu")
	)
	(gr_arc
		(start 113.81486 -38.200076)
		(mid 114.3 -38.685216)
		(end 114.78514 -38.200076)
		(stroke
			(width 0.2)
			(type default)
		)
		(layer "In6.Cu")
	)
	(gr_line
		(start 113.81486 -36.800028)
		(end 113.81486 -38.200076)
		(stroke
			(width 0.2)
			(type default)
		)
		(layer "In6.Cu")
	)
	(gr_arc
		(start 113.81486 -34.600134)
		(mid 114.3 -35.085274)
		(end 114.78514 -34.600134)
		(stroke
			(width 0.2)
			(type default)
		)
		(layer "In6.Cu")
	)
	(gr_line
		(start 113.81486 -33.200086)
		(end 113.81486 -34.600134)
		(stroke
			(width 0.2)
			(type default)
		)
		(layer "In6.Cu")
	)
	(gr_line
		(start 114.78514 -38.200076)
		(end 114.78514 -36.800282)
		(stroke
			(width 0.2)
			(type default)
		)
		(layer "In6.Cu")
	)
	(gr_arc
		(start 114.78514 -36.800282)
		(mid 114.300127 -36.314888)
		(end 113.81486 -36.800028)
		(stroke
			(width 0.2)
			(type default)
		)
		(layer "In6.Cu")
	)
	(gr_line
		(start 114.78514 -34.600134)
		(end 114.78514 -33.20034)
		(stroke
			(width 0.2)
			(type default)
		)
		(layer "In6.Cu")
	)
	(gr_arc
		(start 114.78514 -33.20034)
		(mid 114.300127 -32.714946)
		(end 113.81486 -33.200086)
		(stroke
			(width 0.2)
			(type default)
		)
		(layer "In6.Cu")
	)
	(gr_arc
		(start 115.614704 -37.00018)
		(mid 116.099844 -37.48532)
		(end 116.584984 -37.00018)
		(stroke
			(width 0.2)
			(type default)
		)
		(layer "In6.Cu")
	)
	(gr_line
		(start 115.614704 -35.600132)
		(end 115.614704 -37.00018)
		(stroke
			(width 0.2)
			(type default)
		)
		(layer "In6.Cu")
	)
	(gr_arc
		(start 115.614704 -33.399984)
		(mid 116.099844 -33.885124)
		(end 116.584984 -33.399984)
		(stroke
			(width 0.2)
			(type default)
		)
		(layer "In6.Cu")
	)
	(gr_line
		(start 115.614704 -32.00019)
		(end 115.614704 -33.399984)
		(stroke
			(width 0.2)
			(type default)
		)
		(layer "In6.Cu")
	)
	(gr_line
		(start 116.584984 -37.00018)
		(end 116.584984 -35.600386)
		(stroke
			(width 0.2)
			(type default)
		)
		(layer "In6.Cu")
	)
	(gr_arc
		(start 116.584984 -35.600386)
		(mid 116.099971 -35.114992)
		(end 115.614704 -35.600132)
		(stroke
			(width 0.2)
			(type default)
		)
		(layer "In6.Cu")
	)
	(gr_line
		(start 116.584984 -33.399984)
		(end 116.584984 -32.000444)
		(stroke
			(width 0.2)
			(type default)
		)
		(layer "In6.Cu")
	)
	(gr_arc
		(start 116.584984 -32.000444)
		(mid 116.099971 -31.51505)
		(end 115.614704 -32.00019)
		(stroke
			(width 0.2)
			(type default)
		)
		(layer "In6.Cu")
	)
	(gr_arc
		(start 117.414802 -38.200076)
		(mid 117.899942 -38.685216)
		(end 118.385082 -38.200076)
		(stroke
			(width 0.2)
			(type default)
		)
		(layer "In6.Cu")
	)
	(gr_line
		(start 117.414802 -36.800028)
		(end 117.414802 -38.200076)
		(stroke
			(width 0.2)
			(type default)
		)
		(layer "In6.Cu")
	)
	(gr_arc
		(start 117.414802 -34.600134)
		(mid 117.899942 -35.085274)
		(end 118.385082 -34.600134)
		(stroke
			(width 0.2)
			(type default)
		)
		(layer "In6.Cu")
	)
	(gr_line
		(start 117.414802 -33.200086)
		(end 117.414802 -34.600134)
		(stroke
			(width 0.2)
			(type default)
		)
		(layer "In6.Cu")
	)
	(gr_line
		(start 118.385082 -38.200076)
		(end 118.385082 -36.800282)
		(stroke
			(width 0.2)
			(type default)
		)
		(layer "In6.Cu")
	)
	(gr_arc
		(start 118.385082 -36.800282)
		(mid 117.900069 -36.314888)
		(end 117.414802 -36.800028)
		(stroke
			(width 0.2)
			(type default)
		)
		(layer "In6.Cu")
	)
	(gr_line
		(start 118.385082 -34.600134)
		(end 118.385082 -33.20034)
		(stroke
			(width 0.2)
			(type default)
		)
		(layer "In6.Cu")
	)
	(gr_arc
		(start 118.385082 -33.20034)
		(mid 117.900069 -32.714946)
		(end 117.414802 -33.200086)
		(stroke
			(width 0.2)
			(type default)
		)
		(layer "In6.Cu")
	)
	(gr_arc
		(start 119.2149 -37.00018)
		(mid 119.70004 -37.48532)
		(end 120.18518 -37.00018)
		(stroke
			(width 0.2)
			(type default)
		)
		(layer "In6.Cu")
	)
	(gr_line
		(start 119.2149 -35.600132)
		(end 119.2149 -37.00018)
		(stroke
			(width 0.2)
			(type default)
		)
		(layer "In6.Cu")
	)
	(gr_arc
		(start 119.2149 -33.399984)
		(mid 119.70004 -33.885124)
		(end 120.18518 -33.399984)
		(stroke
			(width 0.2)
			(type default)
		)
		(layer "In6.Cu")
	)
	(gr_line
		(start 119.2149 -32.00019)
		(end 119.2149 -33.399984)
		(stroke
			(width 0.2)
			(type default)
		)
		(layer "In6.Cu")
	)
	(gr_line
		(start 120.18518 -37.00018)
		(end 120.18518 -35.600386)
		(stroke
			(width 0.2)
			(type default)
		)
		(layer "In6.Cu")
	)
	(gr_arc
		(start 120.18518 -35.600386)
		(mid 119.700167 -35.114992)
		(end 119.2149 -35.600132)
		(stroke
			(width 0.2)
			(type default)
		)
		(layer "In6.Cu")
	)
	(gr_line
		(start 120.18518 -33.399984)
		(end 120.18518 -32.000444)
		(stroke
			(width 0.2)
			(type default)
		)
		(layer "In6.Cu")
	)
	(gr_arc
		(start 120.18518 -32.000444)
		(mid 119.700167 -31.51505)
		(end 119.2149 -32.00019)
		(stroke
			(width 0.2)
			(type default)
		)
		(layer "In6.Cu")
	)
	(gr_arc
		(start 128.214882 -38.200076)
		(mid 128.700022 -38.685216)
		(end 129.185162 -38.200076)
		(stroke
			(width 0.2)
			(type default)
		)
		(layer "In6.Cu")
	)
	(gr_line
		(start 128.214882 -36.800028)
		(end 128.214882 -38.200076)
		(stroke
			(width 0.2)
			(type default)
		)
		(layer "In6.Cu")
	)
	(gr_arc
		(start 128.214882 -34.600134)
		(mid 128.700022 -35.085274)
		(end 129.185162 -34.600134)
		(stroke
			(width 0.2)
			(type default)
		)
		(layer "In6.Cu")
	)
	(gr_line
		(start 128.214882 -33.200086)
		(end 128.214882 -34.600134)
		(stroke
			(width 0.2)
			(type default)
		)
		(layer "In6.Cu")
	)
	(gr_line
		(start 129.185162 -38.200076)
		(end 129.185162 -36.800282)
		(stroke
			(width 0.2)
			(type default)
		)
		(layer "In6.Cu")
	)
	(gr_arc
		(start 129.185162 -36.800282)
		(mid 128.700149 -36.314888)
		(end 128.214882 -36.800028)
		(stroke
			(width 0.2)
			(type default)
		)
		(layer "In6.Cu")
	)
	(gr_line
		(start 129.185162 -34.600134)
		(end 129.185162 -33.20034)
		(stroke
			(width 0.2)
			(type default)
		)
		(layer "In6.Cu")
	)
	(gr_arc
		(start 129.185162 -33.20034)
		(mid 128.700149 -32.714946)
		(end 128.214882 -33.200086)
		(stroke
			(width 0.2)
			(type default)
		)
		(layer "In6.Cu")
	)
	(gr_arc
		(start 130.014726 -37.00018)
		(mid 130.499866 -37.48532)
		(end 130.985006 -37.00018)
		(stroke
			(width 0.2)
			(type default)
		)
		(layer "In6.Cu")
	)
	(gr_line
		(start 130.014726 -35.600132)
		(end 130.014726 -37.00018)
		(stroke
			(width 0.2)
			(type default)
		)
		(layer "In6.Cu")
	)
	(gr_arc
		(start 130.014726 -33.399984)
		(mid 130.499866 -33.885124)
		(end 130.985006 -33.399984)
		(stroke
			(width 0.2)
			(type default)
		)
		(layer "In6.Cu")
	)
	(gr_line
		(start 130.014726 -32.00019)
		(end 130.014726 -33.399984)
		(stroke
			(width 0.2)
			(type default)
		)
		(layer "In6.Cu")
	)
	(gr_line
		(start 130.985006 -37.00018)
		(end 130.985006 -35.600386)
		(stroke
			(width 0.2)
			(type default)
		)
		(layer "In6.Cu")
	)
	(gr_arc
		(start 130.985006 -35.600386)
		(mid 130.499993 -35.114992)
		(end 130.014726 -35.600132)
		(stroke
			(width 0.2)
			(type default)
		)
		(layer "In6.Cu")
	)
	(gr_line
		(start 130.985006 -33.399984)
		(end 130.985006 -32.000444)
		(stroke
			(width 0.2)
			(type default)
		)
		(layer "In6.Cu")
	)
	(gr_arc
		(start 130.985006 -32.000444)
		(mid 130.499993 -31.51505)
		(end 130.014726 -32.00019)
		(stroke
			(width 0.2)
			(type default)
		)
		(layer "In6.Cu")
	)
	(gr_arc
		(start 131.814824 -38.200076)
		(mid 132.299964 -38.685216)
		(end 132.785104 -38.200076)
		(stroke
			(width 0.2)
			(type default)
		)
		(layer "In6.Cu")
	)
	(gr_line
		(start 131.814824 -36.800028)
		(end 131.814824 -38.200076)
		(stroke
			(width 0.2)
			(type default)
		)
		(layer "In6.Cu")
	)
	(gr_arc
		(start 131.814824 -34.600134)
		(mid 132.299964 -35.085274)
		(end 132.785104 -34.600134)
		(stroke
			(width 0.2)
			(type default)
		)
		(layer "In6.Cu")
	)
	(gr_line
		(start 131.814824 -33.200086)
		(end 131.814824 -34.600134)
		(stroke
			(width 0.2)
			(type default)
		)
		(layer "In6.Cu")
	)
	(gr_line
		(start 132.785104 -38.200076)
		(end 132.785104 -36.800282)
		(stroke
			(width 0.2)
			(type default)
		)
		(layer "In6.Cu")
	)
	(gr_arc
		(start 132.785104 -36.800282)
		(mid 132.300091 -36.314888)
		(end 131.814824 -36.800028)
		(stroke
			(width 0.2)
			(type default)
		)
		(layer "In6.Cu")
	)
	(gr_line
		(start 132.785104 -34.600134)
		(end 132.785104 -33.20034)
		(stroke
			(width 0.2)
			(type default)
		)
		(layer "In6.Cu")
	)
	(gr_arc
		(start 132.785104 -33.20034)
		(mid 132.300091 -32.714946)
		(end 131.814824 -33.200086)
		(stroke
			(width 0.2)
			(type default)
		)
		(layer "In6.Cu")
	)
	(gr_arc
		(start 133.614922 -37.00018)
		(mid 134.100062 -37.48532)
		(end 134.585202 -37.00018)
		(stroke
			(width 0.2)
			(type default)
		)
		(layer "In6.Cu")
	)
	(gr_line
		(start 133.614922 -35.600132)
		(end 133.614922 -37.00018)
		(stroke
			(width 0.2)
			(type default)
		)
		(layer "In6.Cu")
	)
	(gr_arc
		(start 133.614922 -33.399984)
		(mid 134.100062 -33.885124)
		(end 134.585202 -33.399984)
		(stroke
			(width 0.2)
			(type default)
		)
		(layer "In6.Cu")
	)
	(gr_line
		(start 133.614922 -32.00019)
		(end 133.614922 -33.399984)
		(stroke
			(width 0.2)
			(type default)
		)
		(layer "In6.Cu")
	)
	(gr_line
		(start 134.585202 -37.00018)
		(end 134.585202 -35.600386)
		(stroke
			(width 0.2)
			(type default)
		)
		(layer "In6.Cu")
	)
	(gr_arc
		(start 134.585202 -35.600386)
		(mid 134.100189 -35.114992)
		(end 133.614922 -35.600132)
		(stroke
			(width 0.2)
			(type default)
		)
		(layer "In6.Cu")
	)
	(gr_line
		(start 134.585202 -33.399984)
		(end 134.585202 -32.000444)
		(stroke
			(width 0.2)
			(type default)
		)
		(layer "In6.Cu")
	)
	(gr_arc
		(start 134.585202 -32.000444)
		(mid 134.100189 -31.51505)
		(end 133.614922 -32.00019)
		(stroke
			(width 0.2)
			(type default)
		)
		(layer "In6.Cu")
	)
	(gr_arc
		(start 135.414766 -38.200076)
		(mid 135.899906 -38.685216)
		(end 136.385046 -38.200076)
		(stroke
			(width 0.2)
			(type default)
		)
		(layer "In6.Cu")
	)
	(gr_line
		(start 135.414766 -36.800028)
		(end 135.414766 -38.200076)
		(stroke
			(width 0.2)
			(type default)
		)
		(layer "In6.Cu")
	)
	(gr_arc
		(start 135.414766 -34.600134)
		(mid 135.899906 -35.085274)
		(end 136.385046 -34.600134)
		(stroke
			(width 0.2)
			(type default)
		)
		(layer "In6.Cu")
	)
	(gr_line
		(start 135.414766 -33.200086)
		(end 135.414766 -34.600134)
		(stroke
			(width 0.2)
			(type default)
		)
		(layer "In6.Cu")
	)
	(gr_line
		(start 136.385046 -38.200076)
		(end 136.385046 -36.800282)
		(stroke
			(width 0.2)
			(type default)
		)
		(layer "In6.Cu")
	)
	(gr_arc
		(start 136.385046 -36.800282)
		(mid 135.900033 -36.314888)
		(end 135.414766 -36.800028)
		(stroke
			(width 0.2)
			(type default)
		)
		(layer "In6.Cu")
	)
	(gr_line
		(start 136.385046 -34.600134)
		(end 136.385046 -33.20034)
		(stroke
			(width 0.2)
			(type default)
		)
		(layer "In6.Cu")
	)
	(gr_arc
		(start 136.385046 -33.20034)
		(mid 135.900033 -32.714946)
		(end 135.414766 -33.200086)
		(stroke
			(width 0.2)
			(type default)
		)
		(layer "In6.Cu")
	)
	(gr_arc
		(start 137.214864 -37.00018)
		(mid 137.700004 -37.48532)
		(end 138.185144 -37.00018)
		(stroke
			(width 0.2)
			(type default)
		)
		(layer "In6.Cu")
	)
	(gr_line
		(start 137.214864 -35.600132)
		(end 137.214864 -37.00018)
		(stroke
			(width 0.2)
			(type default)
		)
		(layer "In6.Cu")
	)
	(gr_arc
		(start 137.214864 -33.399984)
		(mid 137.700004 -33.885124)
		(end 138.185144 -33.399984)
		(stroke
			(width 0.2)
			(type default)
		)
		(layer "In6.Cu")
	)
	(gr_line
		(start 137.214864 -32.00019)
		(end 137.214864 -33.399984)
		(stroke
			(width 0.2)
			(type default)
		)
		(layer "In6.Cu")
	)
	(gr_line
		(start 138.185144 -37.00018)
		(end 138.185144 -35.600386)
		(stroke
			(width 0.2)
			(type default)
		)
		(layer "In6.Cu")
	)
	(gr_arc
		(start 138.185144 -35.600386)
		(mid 137.700131 -35.114992)
		(end 137.214864 -35.600132)
		(stroke
			(width 0.2)
			(type default)
		)
		(layer "In6.Cu")
	)
	(gr_line
		(start 138.185144 -33.399984)
		(end 138.185144 -32.000444)
		(stroke
			(width 0.2)
			(type default)
		)
		(layer "In6.Cu")
	)
	(gr_arc
		(start 138.185144 -32.000444)
		(mid 137.700131 -31.51505)
		(end 137.214864 -32.00019)
		(stroke
			(width 0.2)
			(type default)
		)
		(layer "In6.Cu")
	)
	(gr_arc
		(start 139.014708 -38.200076)
		(mid 139.499848 -38.685216)
		(end 139.984988 -38.200076)
		(stroke
			(width 0.2)
			(type default)
		)
		(layer "In6.Cu")
	)
	(gr_line
		(start 139.014708 -36.800028)
		(end 139.014708 -38.200076)
		(stroke
			(width 0.2)
			(type default)
		)
		(layer "In6.Cu")
	)
	(gr_arc
		(start 139.014708 -34.600134)
		(mid 139.499848 -35.085274)
		(end 139.984988 -34.600134)
		(stroke
			(width 0.2)
			(type default)
		)
		(layer "In6.Cu")
	)
	(gr_line
		(start 139.014708 -33.200086)
		(end 139.014708 -34.600134)
		(stroke
			(width 0.2)
			(type default)
		)
		(layer "In6.Cu")
	)
	(gr_line
		(start 139.984988 -38.200076)
		(end 139.984988 -36.800282)
		(stroke
			(width 0.2)
			(type default)
		)
		(layer "In6.Cu")
	)
	(gr_arc
		(start 139.984988 -36.800282)
		(mid 139.499975 -36.314888)
		(end 139.014708 -36.800028)
		(stroke
			(width 0.2)
			(type default)
		)
		(layer "In6.Cu")
	)
	(gr_line
		(start 139.984988 -34.600134)
		(end 139.984988 -33.20034)
		(stroke
			(width 0.2)
			(type default)
		)
		(layer "In6.Cu")
	)
	(gr_arc
		(start 139.984988 -33.20034)
		(mid 139.499975 -32.714946)
		(end 139.014708 -33.200086)
		(stroke
			(width 0.2)
			(type default)
		)
		(layer "In6.Cu")
	)
	(gr_arc
		(start 140.814806 -37.00018)
		(mid 141.299946 -37.48532)
		(end 141.785086 -37.00018)
		(stroke
			(width 0.2)
			(type default)
		)
		(layer "In6.Cu")
	)
	(gr_line
		(start 140.814806 -35.600132)
		(end 140.814806 -37.00018)
		(stroke
			(width 0.2)
			(type default)
		)
		(layer "In6.Cu")
	)
	(gr_arc
		(start 140.814806 -33.399984)
		(mid 141.299946 -33.885124)
		(end 141.785086 -33.399984)
		(stroke
			(width 0.2)
			(type default)
		)
		(layer "In6.Cu")
	)
	(gr_line
		(start 140.814806 -32.00019)
		(end 140.814806 -33.399984)
		(stroke
			(width 0.2)
			(type default)
		)
		(layer "In6.Cu")
	)
	(gr_line
		(start 141.785086 -37.00018)
		(end 141.785086 -35.600386)
		(stroke
			(width 0.2)
			(type default)
		)
		(layer "In6.Cu")
	)
	(gr_arc
		(start 141.785086 -35.600386)
		(mid 141.300073 -35.114992)
		(end 140.814806 -35.600132)
		(stroke
			(width 0.2)
			(type default)
		)
		(layer "In6.Cu")
	)
	(gr_line
		(start 141.785086 -33.399984)
		(end 141.785086 -32.000444)
		(stroke
			(width 0.2)
			(type default)
		)
		(layer "In6.Cu")
	)
	(gr_arc
		(start 141.785086 -32.000444)
		(mid 141.300073 -31.51505)
		(end 140.814806 -32.00019)
		(stroke
			(width 0.2)
			(type default)
		)
		(layer "In6.Cu")
	)
	(gr_line
		(start 143.299942 -47.999904)
		(end 104.70007 -47.999904)
		(stroke
			(width 1.524)
			(type default)
		)
		(layer "In6.Cu")
	)
	(gr_line
		(start 144.29994 -183.76392)
		(end 144.29994 -47.999904)
		(stroke
			(width 1.524)
			(type default)
		)
		(layer "In6.Cu")
	)
	(gr_arc
		(start 144.29994 -183.76392)
		(mid 144.326755 -183.993712)
		(end 144.405604 -184.211214)
		(stroke
			(width 1.524)
			(type default)
		)
		(layer "In6.Cu")
	)
	(gr_arc
		(start 144.29994 -47.999904)
		(mid 143.800068 -47.500032)
		(end 143.299942 -47.999904)
		(stroke
			(width 1.524)
			(type default)
		)
		(layer "In6.Cu")
	)
	(gr_line
		(start 149.023578 -193.447162)
		(end 144.405604 -184.211214)
		(stroke
			(width 1.524)
			(type default)
		)
		(layer "In6.Cu")
	)
	(gr_arc
		(start 149.023578 -193.447162)
		(mid 149.392225 -193.85063)
		(end 149.917912 -194.00012)
		(stroke
			(width 1.524)
			(type default)
		)
		(layer "In6.Cu")
	)
	(gr_arc
		(start 158.833566 -30.277054)
		(mid 159.027114 -30.916626)
		(end 159.666686 -30.723078)
		(stroke
			(width 0.2)
			(type default)
		)
		(layer "In6.Cu")
	)
	(gr_arc
		(start 158.833566 -26.47696)
		(mid 159.027114 -27.116532)
		(end 159.666686 -26.922984)
		(stroke
			(width 0.2)
			(type default)
		)
		(layer "In6.Cu")
	)
	(gr_arc
		(start 158.833566 -18.877026)
		(mid 159.027114 -19.516598)
		(end 159.666686 -19.32305)
		(stroke
			(width 0.2)
			(type default)
		)
		(layer "In6.Cu")
	)
	(gr_arc
		(start 158.836614 -22.671278)
		(mid 159.024316 -23.31492)
		(end 159.666686 -23.12289)
		(stroke
			(width 0.2)
			(type default)
		)
		(layer "In6.Cu")
	)
	(gr_line
		(start 159.583374 -28.877006)
		(end 158.833566 -30.277054)
		(stroke
			(width 0.2)
			(type default)
		)
		(layer "In6.Cu")
	)
	(gr_line
		(start 159.583374 -25.076912)
		(end 158.833566 -26.47696)
		(stroke
			(width 0.2)
			(type default)
		)
		(layer "In6.Cu")
	)
	(gr_line
		(start 159.583374 -21.277072)
		(end 158.836614 -22.671278)
		(stroke
			(width 0.2)
			(type default)
		)
		(layer "In6.Cu")
	)
	(gr_line
		(start 159.583374 -17.476978)
		(end 158.833566 -18.877026)
		(stroke
			(width 0.2)
			(type default)
		)
		(layer "In6.Cu")
	)
	(gr_line
		(start 159.666686 -30.723078)
		(end 160.413446 -29.328618)
		(stroke
			(width 0.2)
			(type default)
		)
		(layer "In6.Cu")
	)
	(gr_line
		(start 159.666686 -26.922984)
		(end 160.413446 -25.528524)
		(stroke
			(width 0.2)
			(type default)
		)
		(layer "In6.Cu")
	)
	(gr_line
		(start 159.666686 -23.12289)
		(end 160.416494 -21.723096)
		(stroke
			(width 0.2)
			(type default)
		)
		(layer "In6.Cu")
	)
	(gr_line
		(start 159.666686 -19.32305)
		(end 160.413446 -17.92859)
		(stroke
			(width 0.2)
			(type default)
		)
		(layer "In6.Cu")
	)
	(gr_arc
		(start 160.413446 -29.328618)
		(mid 160.225744 -28.684976)
		(end 159.583374 -28.877006)
		(stroke
			(width 0.2)
			(type default)
		)
		(layer "In6.Cu")
	)
	(gr_arc
		(start 160.413446 -25.528524)
		(mid 160.225744 -24.884882)
		(end 159.583374 -25.076912)
		(stroke
			(width 0.2)
			(type default)
		)
		(layer "In6.Cu")
	)
	(gr_arc
		(start 160.413446 -17.92859)
		(mid 160.225744 -17.284948)
		(end 159.583374 -17.476978)
		(stroke
			(width 0.2)
			(type default)
		)
		(layer "In6.Cu")
	)
	(gr_arc
		(start 160.416494 -21.723096)
		(mid 160.222946 -21.083524)
		(end 159.583374 -21.277072)
		(stroke
			(width 0.2)
			(type default)
		)
		(layer "In6.Cu")
	)
	(gr_line
		(start 161.081466 -22.675596)
		(end 161.083752 -22.676866)
		(stroke
			(width 0.2)
			(type default)
		)
		(layer "In6.Cu")
	)
	(gr_arc
		(start 161.083498 -30.277054)
		(mid 161.277046 -30.916626)
		(end 161.916618 -30.723078)
		(stroke
			(width 0.2)
			(type default)
		)
		(layer "In6.Cu")
	)
	(gr_arc
		(start 161.083498 -26.47696)
		(mid 161.277046 -27.116532)
		(end 161.916618 -26.922984)
		(stroke
			(width 0.2)
			(type default)
		)
		(layer "In6.Cu")
	)
	(gr_arc
		(start 161.083498 -18.877026)
		(mid 161.277046 -19.516598)
		(end 161.916618 -19.32305)
		(stroke
			(width 0.2)
			(type default)
		)
		(layer "In6.Cu")
	)
	(gr_arc
		(start 161.083752 -22.676866)
		(mid 161.277046 -23.316184)
		(end 161.916364 -23.12289)
		(stroke
			(width 0.2)
			(type default)
		)
		(layer "In6.Cu")
	)
	(gr_line
		(start 161.831528 -21.275802)
		(end 161.081466 -22.675596)
		(stroke
			(width 0.2)
			(type default)
		)
		(layer "In6.Cu")
	)
	(gr_line
		(start 161.83356 -28.877006)
		(end 161.083498 -30.277054)
		(stroke
			(width 0.2)
			(type default)
		)
		(layer "In6.Cu")
	)
	(gr_line
		(start 161.83356 -25.076912)
		(end 161.083498 -26.47696)
		(stroke
			(width 0.2)
			(type default)
		)
		(layer "In6.Cu")
	)
	(gr_line
		(start 161.83356 -17.476978)
		(end 161.083498 -18.877026)
		(stroke
			(width 0.2)
			(type default)
		)
		(layer "In6.Cu")
	)
	(gr_line
		(start 161.833814 -21.277072)
		(end 161.831528 -21.275802)
		(stroke
			(width 0.2)
			(type default)
		)
		(layer "In6.Cu")
	)
	(gr_line
		(start 161.916364 -23.12289)
		(end 161.91865 -23.12416)
		(stroke
			(width 0.2)
			(type default)
		)
		(layer "In6.Cu")
	)
	(gr_line
		(start 161.916618 -30.723078)
		(end 162.663632 -29.328618)
		(stroke
			(width 0.2)
			(type default)
		)
		(layer "In6.Cu")
	)
	(gr_line
		(start 161.916618 -26.922984)
		(end 162.663632 -25.528524)
		(stroke
			(width 0.2)
			(type default)
		)
		(layer "In6.Cu")
	)
	(gr_line
		(start 161.916618 -19.32305)
		(end 162.663632 -17.92859)
		(stroke
			(width 0.2)
			(type default)
		)
		(layer "In6.Cu")
	)
	(gr_line
		(start 161.91865 -23.12416)
		(end 162.668712 -21.72462)
		(stroke
			(width 0.2)
			(type default)
		)
		(layer "In6.Cu")
	)
	(gr_arc
		(start 162.663632 -29.328618)
		(mid 162.47593 -28.684976)
		(end 161.83356 -28.877006)
		(stroke
			(width 0.2)
			(type default)
		)
		(layer "In6.Cu")
	)
	(gr_arc
		(start 162.663632 -25.528524)
		(mid 162.47593 -24.884882)
		(end 161.83356 -25.076912)
		(stroke
			(width 0.2)
			(type default)
		)
		(layer "In6.Cu")
	)
	(gr_arc
		(start 162.663632 -17.92859)
		(mid 162.47593 -17.284948)
		(end 161.83356 -17.476978)
		(stroke
			(width 0.2)
			(type default)
		)
		(layer "In6.Cu")
	)
	(gr_arc
		(start 162.666426 -21.72335)
		(mid 162.473287 -21.083725)
		(end 161.833814 -21.277072)
		(stroke
			(width 0.2)
			(type default)
		)
		(layer "In6.Cu")
	)
	(gr_line
		(start 162.668458 -21.724366)
		(end 162.666426 -21.72335)
		(stroke
			(width 0.2)
			(type default)
		)
		(layer "In6.Cu")
	)
	(gr_line
		(start 162.668712 -21.72462)
		(end 162.668458 -21.724366)
		(stroke
			(width 0.2)
			(type default)
		)
		(layer "In6.Cu")
	)
	(gr_arc
		(start 165.172136 -38.823138)
		(mid 165.187015 -38.859059)
		(end 165.222936 -38.873938)
		(stroke
			(width 0.2)
			(type default)
		)
		(layer "In6.Cu")
	)
	(gr_line
		(start 165.172136 -38.010338)
		(end 165.172136 -38.823138)
		(stroke
			(width 0.2)
			(type default)
		)
		(layer "In6.Cu")
	)
	(gr_line
		(start 165.222936 -38.873938)
		(end 165.426136 -38.873938)
		(stroke
			(width 0.2)
			(type default)
		)
		(layer "In6.Cu")
	)
	(gr_arc
		(start 165.222936 -37.959538)
		(mid 165.187015 -37.974417)
		(end 165.172136 -38.010338)
		(stroke
			(width 0.2)
			(type default)
		)
		(layer "In6.Cu")
	)
	(gr_arc
		(start 165.426136 -38.873938)
		(mid 165.462057 -38.859059)
		(end 165.476936 -38.823138)
		(stroke
			(width 0.2)
			(type default)
		)
		(layer "In6.Cu")
	)
	(gr_line
		(start 165.426136 -37.959538)
		(end 165.222936 -37.959538)
		(stroke
			(width 0.2)
			(type default)
		)
		(layer "In6.Cu")
	)
	(gr_line
		(start 165.476936 -38.823138)
		(end 165.476936 -38.010338)
		(stroke
			(width 0.2)
			(type default)
		)
		(layer "In6.Cu")
	)
	(gr_arc
		(start 165.476936 -38.010338)
		(mid 165.462057 -37.974417)
		(end 165.426136 -37.959538)
		(stroke
			(width 0.2)
			(type default)
		)
		(layer "In6.Cu")
	)
	(gr_arc
		(start 165.807136 -38.823138)
		(mid 165.822015 -38.859059)
		(end 165.857936 -38.873938)
		(stroke
			(width 0.2)
			(type default)
		)
		(layer "In6.Cu")
	)
	(gr_line
		(start 165.807136 -38.010338)
		(end 165.807136 -38.823138)
		(stroke
			(width 0.2)
			(type default)
		)
		(layer "In6.Cu")
	)
	(gr_line
		(start 165.857936 -38.873938)
		(end 166.061136 -38.873938)
		(stroke
			(width 0.2)
			(type default)
		)
		(layer "In6.Cu")
	)
	(gr_arc
		(start 165.857936 -37.959538)
		(mid 165.822015 -37.974417)
		(end 165.807136 -38.010338)
		(stroke
			(width 0.2)
			(type default)
		)
		(layer "In6.Cu")
	)
	(gr_arc
		(start 166.061136 -38.873938)
		(mid 166.097057 -38.859059)
		(end 166.111936 -38.823138)
		(stroke
			(width 0.2)
			(type default)
		)
		(layer "In6.Cu")
	)
	(gr_line
		(start 166.061136 -37.959538)
		(end 165.857936 -37.959538)
		(stroke
			(width 0.2)
			(type default)
		)
		(layer "In6.Cu")
	)
	(gr_line
		(start 166.111936 -38.823138)
		(end 166.111936 -38.010338)
		(stroke
			(width 0.2)
			(type default)
		)
		(layer "In6.Cu")
	)
	(gr_arc
		(start 166.111936 -38.010338)
		(mid 166.097057 -37.974417)
		(end 166.061136 -37.959538)
		(stroke
			(width 0.2)
			(type default)
		)
		(layer "In6.Cu")
	)
	(gr_arc
		(start 166.49319 -38.823138)
		(mid 166.508069 -38.859059)
		(end 166.54399 -38.873938)
		(stroke
			(width 0.2)
			(type default)
		)
		(layer "In6.Cu")
	)
	(gr_line
		(start 166.49319 -38.010338)
		(end 166.49319 -38.823138)
		(stroke
			(width 0.2)
			(type default)
		)
		(layer "In6.Cu")
	)
	(gr_line
		(start 166.54399 -38.873938)
		(end 166.74719 -38.873938)
		(stroke
			(width 0.2)
			(type default)
		)
		(layer "In6.Cu")
	)
	(gr_arc
		(start 166.54399 -37.959538)
		(mid 166.508069 -37.974417)
		(end 166.49319 -38.010338)
		(stroke
			(width 0.2)
			(type default)
		)
		(layer "In6.Cu")
	)
	(gr_arc
		(start 166.74719 -38.873938)
		(mid 166.783111 -38.859059)
		(end 166.79799 -38.823138)
		(stroke
			(width 0.2)
			(type default)
		)
		(layer "In6.Cu")
	)
	(gr_line
		(start 166.74719 -37.959538)
		(end 166.54399 -37.959538)
		(stroke
			(width 0.2)
			(type default)
		)
		(layer "In6.Cu")
	)
	(gr_line
		(start 166.79799 -38.823138)
		(end 166.79799 -38.010338)
		(stroke
			(width 0.2)
			(type default)
		)
		(layer "In6.Cu")
	)
	(gr_arc
		(start 166.79799 -38.010338)
		(mid 166.783111 -37.974417)
		(end 166.74719 -37.959538)
		(stroke
			(width 0.2)
			(type default)
		)
		(layer "In6.Cu")
	)
	(gr_arc
		(start 167.12819 -38.823138)
		(mid 167.143069 -38.859059)
		(end 167.17899 -38.873938)
		(stroke
			(width 0.2)
			(type default)
		)
		(layer "In6.Cu")
	)
	(gr_line
		(start 167.12819 -38.010338)
		(end 167.12819 -38.823138)
		(stroke
			(width 0.2)
			(type default)
		)
		(layer "In6.Cu")
	)
	(gr_line
		(start 167.17899 -38.873938)
		(end 167.38219 -38.873938)
		(stroke
			(width 0.2)
			(type default)
		)
		(layer "In6.Cu")
	)
	(gr_arc
		(start 167.17899 -37.959538)
		(mid 167.143069 -37.974417)
		(end 167.12819 -38.010338)
		(stroke
			(width 0.2)
			(type default)
		)
		(layer "In6.Cu")
	)
	(gr_arc
		(start 167.38219 -38.873938)
		(mid 167.418111 -38.859059)
		(end 167.43299 -38.823138)
		(stroke
			(width 0.2)
			(type default)
		)
		(layer "In6.Cu")
	)
	(gr_line
		(start 167.38219 -37.959538)
		(end 167.17899 -37.959538)
		(stroke
			(width 0.2)
			(type default)
		)
		(layer "In6.Cu")
	)
	(gr_line
		(start 167.43299 -38.823138)
		(end 167.43299 -38.010338)
		(stroke
			(width 0.2)
			(type default)
		)
		(layer "In6.Cu")
	)
	(gr_arc
		(start 167.43299 -38.010338)
		(mid 167.418111 -37.974417)
		(end 167.38219 -37.959538)
		(stroke
			(width 0.2)
			(type default)
		)
		(layer "In6.Cu")
	)
	(gr_arc
		(start 167.813736 -38.848538)
		(mid 167.828615 -38.884459)
		(end 167.864536 -38.899338)
		(stroke
			(width 0.2)
			(type default)
		)
		(layer "In6.Cu")
	)
	(gr_line
		(start 167.813736 -38.035738)
		(end 167.813736 -38.848538)
		(stroke
			(width 0.2)
			(type default)
		)
		(layer "In6.Cu")
	)
	(gr_line
		(start 167.864536 -38.899338)
		(end 168.067736 -38.899338)
		(stroke
			(width 0.2)
			(type default)
		)
		(layer "In6.Cu")
	)
	(gr_arc
		(start 167.864536 -37.984938)
		(mid 167.828615 -37.999817)
		(end 167.813736 -38.035738)
		(stroke
			(width 0.2)
			(type default)
		)
		(layer "In6.Cu")
	)
	(gr_arc
		(start 168.067736 -38.899338)
		(mid 168.103657 -38.884459)
		(end 168.118536 -38.848538)
		(stroke
			(width 0.2)
			(type default)
		)
		(layer "In6.Cu")
	)
	(gr_line
		(start 168.067736 -37.984938)
		(end 167.864536 -37.984938)
		(stroke
			(width 0.2)
			(type default)
		)
		(layer "In6.Cu")
	)
	(gr_line
		(start 168.118536 -38.848538)
		(end 168.118536 -38.035738)
		(stroke
			(width 0.2)
			(type default)
		)
		(layer "In6.Cu")
	)
	(gr_arc
		(start 168.118536 -38.035738)
		(mid 168.103657 -37.999817)
		(end 168.067736 -37.984938)
		(stroke
			(width 0.2)
			(type default)
		)
		(layer "In6.Cu")
	)
	(gr_arc
		(start 168.448736 -38.848538)
		(mid 168.463615 -38.884459)
		(end 168.499536 -38.899338)
		(stroke
			(width 0.2)
			(type default)
		)
		(layer "In6.Cu")
	)
	(gr_line
		(start 168.448736 -38.035738)
		(end 168.448736 -38.848538)
		(stroke
			(width 0.2)
			(type default)
		)
		(layer "In6.Cu")
	)
	(gr_line
		(start 168.499536 -38.899338)
		(end 168.702736 -38.899338)
		(stroke
			(width 0.2)
			(type default)
		)
		(layer "In6.Cu")
	)
	(gr_arc
		(start 168.499536 -37.984938)
		(mid 168.463615 -37.999817)
		(end 168.448736 -38.035738)
		(stroke
			(width 0.2)
			(type default)
		)
		(layer "In6.Cu")
	)
	(gr_arc
		(start 168.702736 -38.899338)
		(mid 168.738657 -38.884459)
		(end 168.753536 -38.848538)
		(stroke
			(width 0.2)
			(type default)
		)
		(layer "In6.Cu")
	)
	(gr_line
		(start 168.702736 -37.984938)
		(end 168.499536 -37.984938)
		(stroke
			(width 0.2)
			(type default)
		)
		(layer "In6.Cu")
	)
	(gr_line
		(start 168.753536 -38.848538)
		(end 168.753536 -38.035738)
		(stroke
			(width 0.2)
			(type default)
		)
		(layer "In6.Cu")
	)
	(gr_arc
		(start 168.753536 -38.035738)
		(mid 168.738657 -37.999817)
		(end 168.702736 -37.984938)
		(stroke
			(width 0.2)
			(type default)
		)
		(layer "In6.Cu")
	)
	(gr_arc
		(start 169.18559 -38.848538)
		(mid 169.200469 -38.884459)
		(end 169.23639 -38.899338)
		(stroke
			(width 0.2)
			(type default)
		)
		(layer "In6.Cu")
	)
	(gr_line
		(start 169.18559 -38.035738)
		(end 169.18559 -38.848538)
		(stroke
			(width 0.2)
			(type default)
		)
		(layer "In6.Cu")
	)
	(gr_line
		(start 169.23639 -38.899338)
		(end 169.43959 -38.899338)
		(stroke
			(width 0.2)
			(type default)
		)
		(layer "In6.Cu")
	)
	(gr_arc
		(start 169.23639 -37.984938)
		(mid 169.200469 -37.999817)
		(end 169.18559 -38.035738)
		(stroke
			(width 0.2)
			(type default)
		)
		(layer "In6.Cu")
	)
	(gr_arc
		(start 169.43959 -38.899338)
		(mid 169.475511 -38.884459)
		(end 169.49039 -38.848538)
		(stroke
			(width 0.2)
			(type default)
		)
		(layer "In6.Cu")
	)
	(gr_line
		(start 169.43959 -37.984938)
		(end 169.23639 -37.984938)
		(stroke
			(width 0.2)
			(type default)
		)
		(layer "In6.Cu")
	)
	(gr_line
		(start 169.49039 -38.848538)
		(end 169.49039 -38.035738)
		(stroke
			(width 0.2)
			(type default)
		)
		(layer "In6.Cu")
	)
	(gr_arc
		(start 169.49039 -38.035738)
		(mid 169.475511 -37.999817)
		(end 169.43959 -37.984938)
		(stroke
			(width 0.2)
			(type default)
		)
		(layer "In6.Cu")
	)
	(gr_arc
		(start 169.82059 -38.848538)
		(mid 169.835469 -38.884459)
		(end 169.87139 -38.899338)
		(stroke
			(width 0.2)
			(type default)
		)
		(layer "In6.Cu")
	)
	(gr_line
		(start 169.82059 -38.035738)
		(end 169.82059 -38.848538)
		(stroke
			(width 0.2)
			(type default)
		)
		(layer "In6.Cu")
	)
	(gr_line
		(start 169.87139 -38.899338)
		(end 170.07459 -38.899338)
		(stroke
			(width 0.2)
			(type default)
		)
		(layer "In6.Cu")
	)
	(gr_arc
		(start 169.87139 -37.984938)
		(mid 169.835469 -37.999817)
		(end 169.82059 -38.035738)
		(stroke
			(width 0.2)
			(type default)
		)
		(layer "In6.Cu")
	)
	(gr_arc
		(start 170.07459 -38.899338)
		(mid 170.110511 -38.884459)
		(end 170.12539 -38.848538)
		(stroke
			(width 0.2)
			(type default)
		)
		(layer "In6.Cu")
	)
	(gr_line
		(start 170.07459 -37.984938)
		(end 169.87139 -37.984938)
		(stroke
			(width 0.2)
			(type default)
		)
		(layer "In6.Cu")
	)
	(gr_line
		(start 170.12539 -38.848538)
		(end 170.12539 -38.035738)
		(stroke
			(width 0.2)
			(type default)
		)
		(layer "In6.Cu")
	)
	(gr_arc
		(start 170.12539 -38.035738)
		(mid 170.110511 -37.999817)
		(end 170.07459 -37.984938)
		(stroke
			(width 0.2)
			(type default)
		)
		(layer "In6.Cu")
	)
	(gr_arc
		(start 178.811174 -26.465022)
		(mid 179.015136 -27.138884)
		(end 179.688998 -26.934922)
		(stroke
			(width 0.2)
			(type default)
		)
		(layer "In6.Cu")
	)
	(gr_arc
		(start 178.833526 -30.277054)
		(mid 179.027074 -30.916626)
		(end 179.666646 -30.723078)
		(stroke
			(width 0.2)
			(type default)
		)
		(layer "In6.Cu")
	)
	(gr_arc
		(start 178.833526 -18.877026)
		(mid 179.027074 -19.516598)
		(end 179.666646 -19.32305)
		(stroke
			(width 0.2)
			(type default)
		)
		(layer "In6.Cu")
	)
	(gr_arc
		(start 178.836574 -22.671278)
		(mid 179.024276 -23.31492)
		(end 179.666646 -23.12289)
		(stroke
			(width 0.2)
			(type default)
		)
		(layer "In6.Cu")
	)
	(gr_line
		(start 179.560982 -25.064974)
		(end 178.811174 -26.465022)
		(stroke
			(width 0.2)
			(type default)
		)
		(layer "In6.Cu")
	)
	(gr_line
		(start 179.583334 -28.877006)
		(end 178.833526 -30.277054)
		(stroke
			(width 0.2)
			(type default)
		)
		(layer "In6.Cu")
	)
	(gr_line
		(start 179.583334 -21.277072)
		(end 178.836574 -22.671278)
		(stroke
			(width 0.2)
			(type default)
		)
		(layer "In6.Cu")
	)
	(gr_line
		(start 179.583334 -17.476978)
		(end 178.833526 -18.877026)
		(stroke
			(width 0.2)
			(type default)
		)
		(layer "In6.Cu")
	)
	(gr_line
		(start 179.666646 -30.723078)
		(end 180.413406 -29.328618)
		(stroke
			(width 0.2)
			(type default)
		)
		(layer "In6.Cu")
	)
	(gr_line
		(start 179.666646 -23.12289)
		(end 180.416454 -21.723096)
		(stroke
			(width 0.2)
			(type default)
		)
		(layer "In6.Cu")
	)
	(gr_line
		(start 179.666646 -19.32305)
		(end 180.413406 -17.92859)
		(stroke
			(width 0.2)
			(type default)
		)
		(layer "In6.Cu")
	)
	(gr_line
		(start 179.688998 -26.934922)
		(end 180.43398 -25.543764)
		(stroke
			(width 0.2)
			(type default)
		)
		(layer "In6.Cu")
	)
	(gr_arc
		(start 180.413406 -29.328618)
		(mid 180.225704 -28.684976)
		(end 179.583334 -28.877006)
		(stroke
			(width 0.2)
			(type default)
		)
		(layer "In6.Cu")
	)
	(gr_arc
		(start 180.413406 -17.92859)
		(mid 180.225704 -17.284948)
		(end 179.583334 -17.476978)
		(stroke
			(width 0.2)
			(type default)
		)
		(layer "In6.Cu")
	)
	(gr_arc
		(start 180.416454 -21.723096)
		(mid 180.222906 -21.083524)
		(end 179.583334 -21.277072)
		(stroke
			(width 0.2)
			(type default)
		)
		(layer "In6.Cu")
	)
	(gr_arc
		(start 180.43398 -25.543764)
		(mid 180.239312 -24.863383)
		(end 179.560982 -25.064974)
		(stroke
			(width 0.2)
			(type default)
		)
		(layer "In6.Cu")
	)
	(gr_arc
		(start 181.061106 -26.464768)
		(mid 181.264814 -27.138884)
		(end 181.93893 -26.935176)
		(stroke
			(width 0.2)
			(type default)
		)
		(layer "In6.Cu")
	)
	(gr_line
		(start 181.081426 -22.675596)
		(end 181.083712 -22.676866)
		(stroke
			(width 0.2)
			(type default)
		)
		(layer "In6.Cu")
	)
	(gr_arc
		(start 181.083458 -30.277054)
		(mid 181.277006 -30.916626)
		(end 181.916578 -30.723078)
		(stroke
			(width 0.2)
			(type default)
		)
		(layer "In6.Cu")
	)
	(gr_arc
		(start 181.083458 -18.877026)
		(mid 181.277006 -19.516598)
		(end 181.916578 -19.32305)
		(stroke
			(width 0.2)
			(type default)
		)
		(layer "In6.Cu")
	)
	(gr_arc
		(start 181.083712 -22.676866)
		(mid 181.277006 -23.316184)
		(end 181.916324 -23.12289)
		(stroke
			(width 0.2)
			(type default)
		)
		(layer "In6.Cu")
	)
	(gr_line
		(start 181.811168 -25.06472)
		(end 181.061106 -26.464768)
		(stroke
			(width 0.2)
			(type default)
		)
		(layer "In6.Cu")
	)
	(gr_line
		(start 181.831488 -21.275802)
		(end 181.081426 -22.675596)
		(stroke
			(width 0.2)
			(type default)
		)
		(layer "In6.Cu")
	)
	(gr_line
		(start 181.83352 -28.877006)
		(end 181.083458 -30.277054)
		(stroke
			(width 0.2)
			(type default)
		)
		(layer "In6.Cu")
	)
	(gr_line
		(start 181.83352 -17.476978)
		(end 181.083458 -18.877026)
		(stroke
			(width 0.2)
			(type default)
		)
		(layer "In6.Cu")
	)
	(gr_line
		(start 181.833774 -21.277072)
		(end 181.831488 -21.275802)
		(stroke
			(width 0.2)
			(type default)
		)
		(layer "In6.Cu")
	)
	(gr_line
		(start 181.916324 -23.12289)
		(end 181.91861 -23.12416)
		(stroke
			(width 0.2)
			(type default)
		)
		(layer "In6.Cu")
	)
	(gr_line
		(start 181.916578 -30.723078)
		(end 182.663592 -29.328618)
		(stroke
			(width 0.2)
			(type default)
		)
		(layer "In6.Cu")
	)
	(gr_line
		(start 181.916578 -19.32305)
		(end 182.663592 -17.92859)
		(stroke
			(width 0.2)
			(type default)
		)
		(layer "In6.Cu")
	)
	(gr_line
		(start 181.91861 -23.12416)
		(end 182.668672 -21.72462)
		(stroke
			(width 0.2)
			(type default)
		)
		(layer "In6.Cu")
	)
	(gr_line
		(start 181.93893 -26.935176)
		(end 182.684166 -25.543764)
		(stroke
			(width 0.2)
			(type default)
		)
		(layer "In6.Cu")
	)
	(gr_arc
		(start 182.663592 -29.328618)
		(mid 182.47589 -28.684976)
		(end 181.83352 -28.877006)
		(stroke
			(width 0.2)
			(type default)
		)
		(layer "In6.Cu")
	)
	(gr_arc
		(start 182.663592 -17.92859)
		(mid 182.47589 -17.284948)
		(end 181.83352 -17.476978)
		(stroke
			(width 0.2)
			(type default)
		)
		(layer "In6.Cu")
	)
	(gr_arc
		(start 182.666386 -21.72335)
		(mid 182.473247 -21.083725)
		(end 181.833774 -21.277072)
		(stroke
			(width 0.2)
			(type default)
		)
		(layer "In6.Cu")
	)
	(gr_line
		(start 182.668418 -21.724366)
		(end 182.666386 -21.72335)
		(stroke
			(width 0.2)
			(type default)
		)
		(layer "In6.Cu")
	)
	(gr_line
		(start 182.668672 -21.72462)
		(end 182.668418 -21.724366)
		(stroke
			(width 0.2)
			(type default)
		)
		(layer "In6.Cu")
	)
	(gr_arc
		(start 182.684166 -25.543764)
		(mid 182.489596 -24.863437)
		(end 181.811168 -25.06472)
		(stroke
			(width 0.2)
			(type default)
		)
		(layer "In6.Cu")
	)
	(gr_arc
		(start 187.837318 -81.5594)
		(mid 187.852197 -81.595321)
		(end 187.888118 -81.6102)
		(stroke
			(width 0.2)
			(type default)
		)
		(layer "In6.Cu")
	)
	(gr_line
		(start 187.837318 -80.7466)
		(end 187.837318 -81.5594)
		(stroke
			(width 0.2)
			(type default)
		)
		(layer "In6.Cu")
	)
	(gr_line
		(start 187.888118 -81.6102)
		(end 188.091318 -81.6102)
		(stroke
			(width 0.2)
			(type default)
		)
		(layer "In6.Cu")
	)
	(gr_arc
		(start 187.888118 -80.6958)
		(mid 187.852197 -80.710679)
		(end 187.837318 -80.7466)
		(stroke
			(width 0.2)
			(type default)
		)
		(layer "In6.Cu")
	)
	(gr_arc
		(start 188.091318 -81.6102)
		(mid 188.127239 -81.595321)
		(end 188.142118 -81.5594)
		(stroke
			(width 0.2)
			(type default)
		)
		(layer "In6.Cu")
	)
	(gr_line
		(start 188.091318 -80.6958)
		(end 187.888118 -80.6958)
		(stroke
			(width 0.2)
			(type default)
		)
		(layer "In6.Cu")
	)
	(gr_line
		(start 188.142118 -81.5594)
		(end 188.142118 -80.7466)
		(stroke
			(width 0.2)
			(type default)
		)
		(layer "In6.Cu")
	)
	(gr_arc
		(start 188.142118 -80.7466)
		(mid 188.127239 -80.710679)
		(end 188.091318 -80.6958)
		(stroke
			(width 0.2)
			(type default)
		)
		(layer "In6.Cu")
	)
	(gr_arc
		(start 188.396118 -81.5594)
		(mid 188.410997 -81.595321)
		(end 188.446918 -81.6102)
		(stroke
			(width 0.2)
			(type default)
		)
		(layer "In6.Cu")
	)
	(gr_line
		(start 188.396118 -80.7466)
		(end 188.396118 -81.5594)
		(stroke
			(width 0.2)
			(type default)
		)
		(layer "In6.Cu")
	)
	(gr_line
		(start 188.446918 -81.6102)
		(end 188.650118 -81.6102)
		(stroke
			(width 0.2)
			(type default)
		)
		(layer "In6.Cu")
	)
	(gr_arc
		(start 188.446918 -80.6958)
		(mid 188.410997 -80.710679)
		(end 188.396118 -80.7466)
		(stroke
			(width 0.2)
			(type default)
		)
		(layer "In6.Cu")
	)
	(gr_arc
		(start 188.650118 -81.6102)
		(mid 188.686039 -81.595321)
		(end 188.700918 -81.5594)
		(stroke
			(width 0.2)
			(type default)
		)
		(layer "In6.Cu")
	)
	(gr_line
		(start 188.650118 -80.6958)
		(end 188.446918 -80.6958)
		(stroke
			(width 0.2)
			(type default)
		)
		(layer "In6.Cu")
	)
	(gr_line
		(start 188.700918 -81.5594)
		(end 188.700918 -80.7466)
		(stroke
			(width 0.2)
			(type default)
		)
		(layer "In6.Cu")
	)
	(gr_arc
		(start 188.700918 -80.7466)
		(mid 188.686039 -80.710679)
		(end 188.650118 -80.6958)
		(stroke
			(width 0.2)
			(type default)
		)
		(layer "In6.Cu")
	)
	(gr_arc
		(start 189.286134 -84.241132)
		(mid 189.279055 -84.782246)
		(end 189.820296 -84.784692)
		(stroke
			(width 0.2)
			(type default)
		)
		(layer "In6.Cu")
	)
	(gr_arc
		(start 189.488318 -81.5594)
		(mid 189.503197 -81.595321)
		(end 189.539118 -81.6102)
		(stroke
			(width 0.2)
			(type default)
		)
		(layer "In6.Cu")
	)
	(gr_line
		(start 189.488318 -80.7466)
		(end 189.488318 -81.5594)
		(stroke
			(width 0.2)
			(type default)
		)
		(layer "In6.Cu")
	)
	(gr_line
		(start 189.539118 -81.6102)
		(end 189.742318 -81.6102)
		(stroke
			(width 0.2)
			(type default)
		)
		(layer "In6.Cu")
	)
	(gr_arc
		(start 189.539118 -80.6958)
		(mid 189.503197 -80.710679)
		(end 189.488318 -80.7466)
		(stroke
			(width 0.2)
			(type default)
		)
		(layer "In6.Cu")
	)
	(gr_arc
		(start 189.742318 -81.6102)
		(mid 189.778239 -81.595321)
		(end 189.793118 -81.5594)
		(stroke
			(width 0.2)
			(type default)
		)
		(layer "In6.Cu")
	)
	(gr_line
		(start 189.742318 -80.6958)
		(end 189.539118 -80.6958)
		(stroke
			(width 0.2)
			(type default)
		)
		(layer "In6.Cu")
	)
	(gr_line
		(start 189.793118 -81.5594)
		(end 189.793118 -80.7466)
		(stroke
			(width 0.2)
			(type default)
		)
		(layer "In6.Cu")
	)
	(gr_arc
		(start 189.793118 -80.7466)
		(mid 189.778239 -80.710679)
		(end 189.742318 -80.6958)
		(stroke
			(width 0.2)
			(type default)
		)
		(layer "In6.Cu")
	)
	(gr_line
		(start 189.820296 -84.784692)
		(end 190.448692 -84.156296)
		(stroke
			(width 0.2)
			(type default)
		)
		(layer "In6.Cu")
	)
	(gr_line
		(start 189.909704 -83.617308)
		(end 189.286134 -84.241132)
		(stroke
			(width 0.2)
			(type default)
		)
		(layer "In6.Cu")
	)
	(gr_arc
		(start 190.047118 -81.5594)
		(mid 190.061997 -81.595321)
		(end 190.097918 -81.6102)
		(stroke
			(width 0.2)
			(type default)
		)
		(layer "In6.Cu")
	)
	(gr_line
		(start 190.047118 -80.7466)
		(end 190.047118 -81.5594)
		(stroke
			(width 0.2)
			(type default)
		)
		(layer "In6.Cu")
	)
	(gr_line
		(start 190.097918 -81.6102)
		(end 190.301118 -81.6102)
		(stroke
			(width 0.2)
			(type default)
		)
		(layer "In6.Cu")
	)
	(gr_arc
		(start 190.097918 -80.6958)
		(mid 190.061997 -80.710679)
		(end 190.047118 -80.7466)
		(stroke
			(width 0.2)
			(type default)
		)
		(layer "In6.Cu")
	)
	(gr_arc
		(start 190.301118 -81.6102)
		(mid 190.337039 -81.595321)
		(end 190.351918 -81.5594)
		(stroke
			(width 0.2)
			(type default)
		)
		(layer "In6.Cu")
	)
	(gr_line
		(start 190.301118 -80.6958)
		(end 190.097918 -80.6958)
		(stroke
			(width 0.2)
			(type default)
		)
		(layer "In6.Cu")
	)
	(gr_line
		(start 190.351918 -81.5594)
		(end 190.351918 -80.7466)
		(stroke
			(width 0.2)
			(type default)
		)
		(layer "In6.Cu")
	)
	(gr_arc
		(start 190.351918 -80.7466)
		(mid 190.337039 -80.710679)
		(end 190.301118 -80.6958)
		(stroke
			(width 0.2)
			(type default)
		)
		(layer "In6.Cu")
	)
	(gr_arc
		(start 190.448692 -84.156296)
		(mid 190.448692 -83.617308)
		(end 189.909704 -83.617308)
		(stroke
			(width 0.2)
			(type default)
		)
		(layer "In6.Cu")
	)
	(gr_arc
		(start 190.835534 -87.035132)
		(mid 190.828455 -87.576246)
		(end 191.369696 -87.578692)
		(stroke
			(width 0.2)
			(type default)
		)
		(layer "In6.Cu")
	)
	(gr_arc
		(start 191.232536 -26.0096)
		(mid 191.247415 -26.045521)
		(end 191.283336 -26.0604)
		(stroke
			(width 0.2)
			(type default)
		)
		(layer "In6.Cu")
	)
	(gr_line
		(start 191.232536 -25.8064)
		(end 191.232536 -26.0096)
		(stroke
			(width 0.2)
			(type default)
		)
		(layer "In6.Cu")
	)
	(gr_arc
		(start 191.232536 -25.3746)
		(mid 191.247415 -25.410521)
		(end 191.283336 -25.4254)
		(stroke
			(width 0.2)
			(type default)
		)
		(layer "In6.Cu")
	)
	(gr_line
		(start 191.232536 -25.1714)
		(end 191.232536 -25.3746)
		(stroke
			(width 0.2)
			(type default)
		)
		(layer "In6.Cu")
	)
	(gr_arc
		(start 191.23279 -23.9776)
		(mid 191.247669 -24.013521)
		(end 191.28359 -24.0284)
		(stroke
			(width 0.2)
			(type default)
		)
		(layer "In6.Cu")
	)
	(gr_line
		(start 191.23279 -23.7744)
		(end 191.23279 -23.9776)
		(stroke
			(width 0.2)
			(type default)
		)
		(layer "In6.Cu")
	)
	(gr_arc
		(start 191.23279 -23.3426)
		(mid 191.247669 -23.378521)
		(end 191.28359 -23.3934)
		(stroke
			(width 0.2)
			(type default)
		)
		(layer "In6.Cu")
	)
	(gr_line
		(start 191.23279 -23.1394)
		(end 191.23279 -23.3426)
		(stroke
			(width 0.2)
			(type default)
		)
		(layer "In6.Cu")
	)
	(gr_arc
		(start 191.23279 -21.9456)
		(mid 191.247669 -21.981521)
		(end 191.28359 -21.9964)
		(stroke
			(width 0.2)
			(type default)
		)
		(layer "In6.Cu")
	)
	(gr_line
		(start 191.23279 -21.7424)
		(end 191.23279 -21.9456)
		(stroke
			(width 0.2)
			(type default)
		)
		(layer "In6.Cu")
	)
	(gr_arc
		(start 191.23279 -21.3106)
		(mid 191.247669 -21.346521)
		(end 191.28359 -21.3614)
		(stroke
			(width 0.2)
			(type default)
		)
		(layer "In6.Cu")
	)
	(gr_line
		(start 191.23279 -21.1074)
		(end 191.23279 -21.3106)
		(stroke
			(width 0.2)
			(type default)
		)
		(layer "In6.Cu")
	)
	(gr_arc
		(start 191.23279 -19.9136)
		(mid 191.247669 -19.949521)
		(end 191.28359 -19.9644)
		(stroke
			(width 0.2)
			(type default)
		)
		(layer "In6.Cu")
	)
	(gr_line
		(start 191.23279 -19.7104)
		(end 191.23279 -19.9136)
		(stroke
			(width 0.2)
			(type default)
		)
		(layer "In6.Cu")
	)
	(gr_arc
		(start 191.23279 -19.2786)
		(mid 191.247669 -19.314521)
		(end 191.28359 -19.3294)
		(stroke
			(width 0.2)
			(type default)
		)
		(layer "In6.Cu")
	)
	(gr_line
		(start 191.23279 -19.0754)
		(end 191.23279 -19.2786)
		(stroke
			(width 0.2)
			(type default)
		)
		(layer "In6.Cu")
	)
	(gr_line
		(start 191.283336 -26.0604)
		(end 192.096136 -26.0604)
		(stroke
			(width 0.2)
			(type default)
		)
		(layer "In6.Cu")
	)
	(gr_arc
		(start 191.283336 -25.7556)
		(mid 191.247415 -25.770479)
		(end 191.232536 -25.8064)
		(stroke
			(width 0.2)
			(type default)
		)
		(layer "In6.Cu")
	)
	(gr_line
		(start 191.283336 -25.4254)
		(end 192.096136 -25.4254)
		(stroke
			(width 0.2)
			(type default)
		)
		(layer "In6.Cu")
	)
	(gr_arc
		(start 191.283336 -25.1206)
		(mid 191.247415 -25.135479)
		(end 191.232536 -25.1714)
		(stroke
			(width 0.2)
			(type default)
		)
		(layer "In6.Cu")
	)
	(gr_line
		(start 191.28359 -24.0284)
		(end 192.09639 -24.0284)
		(stroke
			(width 0.2)
			(type default)
		)
		(layer "In6.Cu")
	)
	(gr_arc
		(start 191.28359 -23.7236)
		(mid 191.247669 -23.738479)
		(end 191.23279 -23.7744)
		(stroke
			(width 0.2)
			(type default)
		)
		(layer "In6.Cu")
	)
	(gr_line
		(start 191.28359 -23.3934)
		(end 192.09639 -23.3934)
		(stroke
			(width 0.2)
			(type default)
		)
		(layer "In6.Cu")
	)
	(gr_arc
		(start 191.28359 -23.0886)
		(mid 191.247669 -23.103479)
		(end 191.23279 -23.1394)
		(stroke
			(width 0.2)
			(type default)
		)
		(layer "In6.Cu")
	)
	(gr_line
		(start 191.28359 -21.9964)
		(end 192.09639 -21.9964)
		(stroke
			(width 0.2)
			(type default)
		)
		(layer "In6.Cu")
	)
	(gr_arc
		(start 191.28359 -21.6916)
		(mid 191.247669 -21.706479)
		(end 191.23279 -21.7424)
		(stroke
			(width 0.2)
			(type default)
		)
		(layer "In6.Cu")
	)
	(gr_line
		(start 191.28359 -21.3614)
		(end 192.09639 -21.3614)
		(stroke
			(width 0.2)
			(type default)
		)
		(layer "In6.Cu")
	)
	(gr_arc
		(start 191.28359 -21.0566)
		(mid 191.247669 -21.071479)
		(end 191.23279 -21.1074)
		(stroke
			(width 0.2)
			(type default)
		)
		(layer "In6.Cu")
	)
	(gr_line
		(start 191.28359 -19.9644)
		(end 192.09639 -19.9644)
		(stroke
			(width 0.2)
			(type default)
		)
		(layer "In6.Cu")
	)
	(gr_arc
		(start 191.28359 -19.6596)
		(mid 191.247669 -19.674479)
		(end 191.23279 -19.7104)
		(stroke
			(width 0.2)
			(type default)
		)
		(layer "In6.Cu")
	)
	(gr_line
		(start 191.28359 -19.3294)
		(end 192.09639 -19.3294)
		(stroke
			(width 0.2)
			(type default)
		)
		(layer "In6.Cu")
	)
	(gr_arc
		(start 191.28359 -19.0246)
		(mid 191.247669 -19.039479)
		(end 191.23279 -19.0754)
		(stroke
			(width 0.2)
			(type default)
		)
		(layer "In6.Cu")
	)
	(gr_line
		(start 191.369696 -87.578692)
		(end 191.998092 -86.950296)
		(stroke
			(width 0.2)
			(type default)
		)
		(layer "In6.Cu")
	)
	(gr_line
		(start 191.459104 -86.411308)
		(end 190.835534 -87.035132)
		(stroke
			(width 0.2)
			(type default)
		)
		(layer "In6.Cu")
	)
	(gr_arc
		(start 191.520318 -81.5594)
		(mid 191.535197 -81.595321)
		(end 191.571118 -81.6102)
		(stroke
			(width 0.2)
			(type default)
		)
		(layer "In6.Cu")
	)
	(gr_line
		(start 191.520318 -80.7466)
		(end 191.520318 -81.5594)
		(stroke
			(width 0.2)
			(type default)
		)
		(layer "In6.Cu")
	)
	(gr_line
		(start 191.571118 -81.6102)
		(end 191.774318 -81.6102)
		(stroke
			(width 0.2)
			(type default)
		)
		(layer "In6.Cu")
	)
	(gr_arc
		(start 191.571118 -80.6958)
		(mid 191.535197 -80.710679)
		(end 191.520318 -80.7466)
		(stroke
			(width 0.2)
			(type default)
		)
		(layer "In6.Cu")
	)
	(gr_arc
		(start 191.64173 -74.699622)
		(mid 191.99987 -75.057762)
		(end 192.35801 -74.699622)
		(stroke
			(width 0.2)
			(type default)
		)
		(layer "In6.Cu")
	)
	(gr_line
		(start 191.64173 -73.899776)
		(end 191.64173 -74.699622)
		(stroke
			(width 0.2)
			(type default)
		)
		(layer "In6.Cu")
	)
	(gr_arc
		(start 191.774318 -81.6102)
		(mid 191.810239 -81.595321)
		(end 191.825118 -81.5594)
		(stroke
			(width 0.2)
			(type default)
		)
		(layer "In6.Cu")
	)
	(gr_line
		(start 191.774318 -80.6958)
		(end 191.571118 -80.6958)
		(stroke
			(width 0.2)
			(type default)
		)
		(layer "In6.Cu")
	)
	(gr_line
		(start 191.825118 -81.5594)
		(end 191.825118 -80.7466)
		(stroke
			(width 0.2)
			(type default)
		)
		(layer "In6.Cu")
	)
	(gr_arc
		(start 191.825118 -80.7466)
		(mid 191.810239 -80.710679)
		(end 191.774318 -80.6958)
		(stroke
			(width 0.2)
			(type default)
		)
		(layer "In6.Cu")
	)
	(gr_arc
		(start 191.998092 -86.950296)
		(mid 191.998092 -86.411308)
		(end 191.459104 -86.411308)
		(stroke
			(width 0.2)
			(type default)
		)
		(layer "In6.Cu")
	)
	(gr_arc
		(start 192.079118 -81.5594)
		(mid 192.093997 -81.595321)
		(end 192.129918 -81.6102)
		(stroke
			(width 0.2)
			(type default)
		)
		(layer "In6.Cu")
	)
	(gr_line
		(start 192.079118 -80.7466)
		(end 192.079118 -81.5594)
		(stroke
			(width 0.2)
			(type default)
		)
		(layer "In6.Cu")
	)
	(gr_arc
		(start 192.096136 -26.0604)
		(mid 192.132057 -26.045521)
		(end 192.146936 -26.0096)
		(stroke
			(width 0.2)
			(type default)
		)
		(layer "In6.Cu")
	)
	(gr_line
		(start 192.096136 -25.7556)
		(end 191.283336 -25.7556)
		(stroke
			(width 0.2)
			(type default)
		)
		(layer "In6.Cu")
	)
	(gr_arc
		(start 192.096136 -25.4254)
		(mid 192.132057 -25.410521)
		(end 192.146936 -25.3746)
		(stroke
			(width 0.2)
			(type default)
		)
		(layer "In6.Cu")
	)
	(gr_line
		(start 192.096136 -25.1206)
		(end 191.283336 -25.1206)
		(stroke
			(width 0.2)
			(type default)
		)
		(layer "In6.Cu")
	)
	(gr_arc
		(start 192.09639 -24.0284)
		(mid 192.132311 -24.013521)
		(end 192.14719 -23.9776)
		(stroke
			(width 0.2)
			(type default)
		)
		(layer "In6.Cu")
	)
	(gr_line
		(start 192.09639 -23.7236)
		(end 191.28359 -23.7236)
		(stroke
			(width 0.2)
			(type default)
		)
		(layer "In6.Cu")
	)
	(gr_arc
		(start 192.09639 -23.3934)
		(mid 192.132311 -23.378521)
		(end 192.14719 -23.3426)
		(stroke
			(width 0.2)
			(type default)
		)
		(layer "In6.Cu")
	)
	(gr_line
		(start 192.09639 -23.0886)
		(end 191.28359 -23.0886)
		(stroke
			(width 0.2)
			(type default)
		)
		(layer "In6.Cu")
	)
	(gr_arc
		(start 192.09639 -21.9964)
		(mid 192.132311 -21.981521)
		(end 192.14719 -21.9456)
		(stroke
			(width 0.2)
			(type default)
		)
		(layer "In6.Cu")
	)
	(gr_line
		(start 192.09639 -21.6916)
		(end 191.28359 -21.6916)
		(stroke
			(width 0.2)
			(type default)
		)
		(layer "In6.Cu")
	)
	(gr_arc
		(start 192.09639 -21.3614)
		(mid 192.132311 -21.346521)
		(end 192.14719 -21.3106)
		(stroke
			(width 0.2)
			(type default)
		)
		(layer "In6.Cu")
	)
	(gr_line
		(start 192.09639 -21.0566)
		(end 191.28359 -21.0566)
		(stroke
			(width 0.2)
			(type default)
		)
		(layer "In6.Cu")
	)
	(gr_arc
		(start 192.09639 -19.9644)
		(mid 192.132311 -19.949521)
		(end 192.14719 -19.9136)
		(stroke
			(width 0.2)
			(type default)
		)
		(layer "In6.Cu")
	)
	(gr_line
		(start 192.09639 -19.6596)
		(end 191.28359 -19.6596)
		(stroke
			(width 0.2)
			(type default)
		)
		(layer "In6.Cu")
	)
	(gr_arc
		(start 192.09639 -19.3294)
		(mid 192.132311 -19.314521)
		(end 192.14719 -19.2786)
		(stroke
			(width 0.2)
			(type default)
		)
		(layer "In6.Cu")
	)
	(gr_line
		(start 192.09639 -19.0246)
		(end 191.28359 -19.0246)
		(stroke
			(width 0.2)
			(type default)
		)
		(layer "In6.Cu")
	)
	(gr_line
		(start 192.129918 -81.6102)
		(end 192.333118 -81.6102)
		(stroke
			(width 0.2)
			(type default)
		)
		(layer "In6.Cu")
	)
	(gr_arc
		(start 192.129918 -80.6958)
		(mid 192.093997 -80.710679)
		(end 192.079118 -80.7466)
		(stroke
			(width 0.2)
			(type default)
		)
		(layer "In6.Cu")
	)
	(gr_line
		(start 192.146936 -26.0096)
		(end 192.146936 -25.8064)
		(stroke
			(width 0.2)
			(type default)
		)
		(layer "In6.Cu")
	)
	(gr_arc
		(start 192.146936 -25.8064)
		(mid 192.132057 -25.770479)
		(end 192.096136 -25.7556)
		(stroke
			(width 0.2)
			(type default)
		)
		(layer "In6.Cu")
	)
	(gr_line
		(start 192.146936 -25.3746)
		(end 192.146936 -25.1714)
		(stroke
			(width 0.2)
			(type default)
		)
		(layer "In6.Cu")
	)
	(gr_arc
		(start 192.146936 -25.1714)
		(mid 192.132057 -25.135479)
		(end 192.096136 -25.1206)
		(stroke
			(width 0.2)
			(type default)
		)
		(layer "In6.Cu")
	)
	(gr_line
		(start 192.14719 -23.9776)
		(end 192.14719 -23.7744)
		(stroke
			(width 0.2)
			(type default)
		)
		(layer "In6.Cu")
	)
	(gr_arc
		(start 192.14719 -23.7744)
		(mid 192.132311 -23.738479)
		(end 192.09639 -23.7236)
		(stroke
			(width 0.2)
			(type default)
		)
		(layer "In6.Cu")
	)
	(gr_line
		(start 192.14719 -23.3426)
		(end 192.14719 -23.1394)
		(stroke
			(width 0.2)
			(type default)
		)
		(layer "In6.Cu")
	)
	(gr_arc
		(start 192.14719 -23.1394)
		(mid 192.132311 -23.103479)
		(end 192.09639 -23.0886)
		(stroke
			(width 0.2)
			(type default)
		)
		(layer "In6.Cu")
	)
	(gr_line
		(start 192.14719 -21.9456)
		(end 192.14719 -21.7424)
		(stroke
			(width 0.2)
			(type default)
		)
		(layer "In6.Cu")
	)
	(gr_arc
		(start 192.14719 -21.7424)
		(mid 192.132311 -21.706479)
		(end 192.09639 -21.6916)
		(stroke
			(width 0.2)
			(type default)
		)
		(layer "In6.Cu")
	)
	(gr_line
		(start 192.14719 -21.3106)
		(end 192.14719 -21.1074)
		(stroke
			(width 0.2)
			(type default)
		)
		(layer "In6.Cu")
	)
	(gr_arc
		(start 192.14719 -21.1074)
		(mid 192.132311 -21.071479)
		(end 192.09639 -21.0566)
		(stroke
			(width 0.2)
			(type default)
		)
		(layer "In6.Cu")
	)
	(gr_line
		(start 192.14719 -19.9136)
		(end 192.14719 -19.7104)
		(stroke
			(width 0.2)
			(type default)
		)
		(layer "In6.Cu")
	)
	(gr_arc
		(start 192.14719 -19.7104)
		(mid 192.132311 -19.674479)
		(end 192.09639 -19.6596)
		(stroke
			(width 0.2)
			(type default)
		)
		(layer "In6.Cu")
	)
	(gr_line
		(start 192.14719 -19.2786)
		(end 192.14719 -19.0754)
		(stroke
			(width 0.2)
			(type default)
		)
		(layer "In6.Cu")
	)
	(gr_arc
		(start 192.14719 -19.0754)
		(mid 192.132311 -19.039479)
		(end 192.09639 -19.0246)
		(stroke
			(width 0.2)
			(type default)
		)
		(layer "In6.Cu")
	)
	(gr_arc
		(start 192.333118 -81.6102)
		(mid 192.369039 -81.595321)
		(end 192.383918 -81.5594)
		(stroke
			(width 0.2)
			(type default)
		)
		(layer "In6.Cu")
	)
	(gr_line
		(start 192.333118 -80.6958)
		(end 192.129918 -80.6958)
		(stroke
			(width 0.2)
			(type default)
		)
		(layer "In6.Cu")
	)
	(gr_line
		(start 192.35801 -74.699622)
		(end 192.35801 -73.90003)
		(stroke
			(width 0.2)
			(type default)
		)
		(layer "In6.Cu")
	)
	(gr_arc
		(start 192.35801 -73.90003)
		(mid 191.999997 -73.541636)
		(end 191.64173 -73.899776)
		(stroke
			(width 0.2)
			(type default)
		)
		(layer "In6.Cu")
	)
	(gr_line
		(start 192.383918 -81.5594)
		(end 192.383918 -80.7466)
		(stroke
			(width 0.2)
			(type default)
		)
		(layer "In6.Cu")
	)
	(gr_arc
		(start 192.383918 -80.7466)
		(mid 192.369039 -80.710679)
		(end 192.333118 -80.6958)
		(stroke
			(width 0.2)
			(type default)
		)
		(layer "In6.Cu")
	)
	(gr_line
		(start 192.441576 -73.90003)
		(end 192.44183 -74.699876)
		(stroke
			(width 0.2)
			(type default)
		)
		(layer "In6.Cu")
	)
	(gr_arc
		(start 192.44183 -74.699876)
		(mid 192.800097 -75.058016)
		(end 193.15811 -74.699622)
		(stroke
			(width 0.2)
			(type default)
		)
		(layer "In6.Cu")
	)
	(gr_arc
		(start 192.790318 -81.5594)
		(mid 192.805197 -81.595321)
		(end 192.841118 -81.6102)
		(stroke
			(width 0.2)
			(type default)
		)
		(layer "In6.Cu")
	)
	(gr_line
		(start 192.790318 -80.7466)
		(end 192.790318 -81.5594)
		(stroke
			(width 0.2)
			(type default)
		)
		(layer "In6.Cu")
	)
	(gr_line
		(start 192.841118 -81.6102)
		(end 193.044318 -81.6102)
		(stroke
			(width 0.2)
			(type default)
		)
		(layer "In6.Cu")
	)
	(gr_arc
		(start 192.841118 -80.6958)
		(mid 192.805197 -80.710679)
		(end 192.790318 -80.7466)
		(stroke
			(width 0.2)
			(type default)
		)
		(layer "In6.Cu")
	)
	(gr_arc
		(start 193.044318 -81.6102)
		(mid 193.080239 -81.595321)
		(end 193.095118 -81.5594)
		(stroke
			(width 0.2)
			(type default)
		)
		(layer "In6.Cu")
	)
	(gr_line
		(start 193.044318 -80.6958)
		(end 192.841118 -80.6958)
		(stroke
			(width 0.2)
			(type default)
		)
		(layer "In6.Cu")
	)
	(gr_line
		(start 193.095118 -81.5594)
		(end 193.095118 -80.7466)
		(stroke
			(width 0.2)
			(type default)
		)
		(layer "In6.Cu")
	)
	(gr_arc
		(start 193.095118 -80.7466)
		(mid 193.080239 -80.710679)
		(end 193.044318 -80.6958)
		(stroke
			(width 0.2)
			(type default)
		)
		(layer "In6.Cu")
	)
	(gr_arc
		(start 193.157856 -73.90003)
		(mid 192.799716 -73.541636)
		(end 192.441576 -73.90003)
		(stroke
			(width 0.2)
			(type default)
		)
		(layer "In6.Cu")
	)
	(gr_line
		(start 193.15811 -74.699622)
		(end 193.157856 -73.90003)
		(stroke
			(width 0.2)
			(type default)
		)
		(layer "In6.Cu")
	)
	(gr_arc
		(start 193.349118 -81.5594)
		(mid 193.363997 -81.595321)
		(end 193.399918 -81.6102)
		(stroke
			(width 0.2)
			(type default)
		)
		(layer "In6.Cu")
	)
	(gr_line
		(start 193.349118 -80.7466)
		(end 193.349118 -81.5594)
		(stroke
			(width 0.2)
			(type default)
		)
		(layer "In6.Cu")
	)
	(gr_line
		(start 193.399918 -81.6102)
		(end 193.603118 -81.6102)
		(stroke
			(width 0.2)
			(type default)
		)
		(layer "In6.Cu")
	)
	(gr_arc
		(start 193.399918 -80.6958)
		(mid 193.363997 -80.710679)
		(end 193.349118 -80.7466)
		(stroke
			(width 0.2)
			(type default)
		)
		(layer "In6.Cu")
	)
	(gr_arc
		(start 193.557906 -88.736932)
		(mid 193.550827 -89.278046)
		(end 194.092068 -89.280492)
		(stroke
			(width 0.2)
			(type default)
		)
		(layer "In6.Cu")
	)
	(gr_arc
		(start 193.603118 -81.6102)
		(mid 193.639039 -81.595321)
		(end 193.653918 -81.5594)
		(stroke
			(width 0.2)
			(type default)
		)
		(layer "In6.Cu")
	)
	(gr_line
		(start 193.603118 -80.6958)
		(end 193.399918 -80.6958)
		(stroke
			(width 0.2)
			(type default)
		)
		(layer "In6.Cu")
	)
	(gr_line
		(start 193.653918 -81.5594)
		(end 193.653918 -80.7466)
		(stroke
			(width 0.2)
			(type default)
		)
		(layer "In6.Cu")
	)
	(gr_arc
		(start 193.653918 -80.7466)
		(mid 193.639039 -80.710679)
		(end 193.603118 -80.6958)
		(stroke
			(width 0.2)
			(type default)
		)
		(layer "In6.Cu")
	)
	(gr_arc
		(start 193.781934 -84.012532)
		(mid 193.774855 -84.553646)
		(end 194.316096 -84.556092)
		(stroke
			(width 0.2)
			(type default)
		)
		(layer "In6.Cu")
	)
	(gr_arc
		(start 194.03441 -74.698606)
		(mid 194.389248 -75.060048)
		(end 194.75069 -74.70521)
		(stroke
			(width 0.2)
			(type default)
		)
		(layer "In6.Cu")
	)
	(gr_line
		(start 194.041522 -73.896474)
		(end 194.03441 -74.698606)
		(stroke
			(width 0.2)
			(type default)
		)
		(layer "In6.Cu")
	)
	(gr_line
		(start 194.092068 -89.280492)
		(end 194.720464 -88.652096)
		(stroke
			(width 0.2)
			(type default)
		)
		(layer "In6.Cu")
	)
	(gr_line
		(start 194.181476 -88.113108)
		(end 193.557906 -88.736932)
		(stroke
			(width 0.2)
			(type default)
		)
		(layer "In6.Cu")
	)
	(gr_line
		(start 194.316096 -84.556092)
		(end 194.944492 -83.927696)
		(stroke
			(width 0.2)
			(type default)
		)
		(layer "In6.Cu")
	)
	(gr_line
		(start 194.405504 -83.388708)
		(end 193.781934 -84.012532)
		(stroke
			(width 0.2)
			(type default)
		)
		(layer "In6.Cu")
	)
	(gr_arc
		(start 194.720464 -88.652096)
		(mid 194.720464 -88.113108)
		(end 194.181476 -88.113108)
		(stroke
			(width 0.2)
			(type default)
		)
		(layer "In6.Cu")
	)
	(gr_line
		(start 194.75069 -74.70521)
		(end 194.757802 -73.903332)
		(stroke
			(width 0.2)
			(type default)
		)
		(layer "In6.Cu")
	)
	(gr_arc
		(start 194.757802 -73.903332)
		(mid 194.403091 -73.541891)
		(end 194.041522 -73.896474)
		(stroke
			(width 0.2)
			(type default)
		)
		(layer "In6.Cu")
	)
	(gr_arc
		(start 194.840352 -74.706988)
		(mid 195.197984 -75.065636)
		(end 195.556632 -74.708004)
		(stroke
			(width 0.2)
			(type default)
		)
		(layer "In6.Cu")
	)
	(gr_line
		(start 194.841622 -73.899268)
		(end 194.840352 -74.706988)
		(stroke
			(width 0.2)
			(type default)
		)
		(layer "In6.Cu")
	)
	(gr_arc
		(start 194.944492 -83.927696)
		(mid 194.944492 -83.388708)
		(end 194.405504 -83.388708)
		(stroke
			(width 0.2)
			(type default)
		)
		(layer "In6.Cu")
	)
	(gr_line
		(start 195.556632 -74.708004)
		(end 195.557902 -73.900538)
		(stroke
			(width 0.2)
			(type default)
		)
		(layer "In6.Cu")
	)
	(gr_arc
		(start 195.557902 -73.900538)
		(mid 195.200397 -73.54189)
		(end 194.841622 -73.899268)
		(stroke
			(width 0.2)
			(type default)
		)
		(layer "In6.Cu")
	)
	(gr_line
		(start 196.441568 -73.903586)
		(end 196.44995 -74.702162)
		(stroke
			(width 0.2)
			(type default)
		)
		(layer "In6.Cu")
	)
	(gr_arc
		(start 196.44995 -74.702162)
		(mid 196.8119 -75.056492)
		(end 197.16623 -74.694542)
		(stroke
			(width 0.2)
			(type default)
		)
		(layer "In6.Cu")
	)
	(gr_arc
		(start 196.631306 -85.688932)
		(mid 196.624227 -86.230046)
		(end 197.165468 -86.232492)
		(stroke
			(width 0.2)
			(type default)
		)
		(layer "In6.Cu")
	)
	(gr_arc
		(start 197.108318 -81.5594)
		(mid 197.123197 -81.595321)
		(end 197.159118 -81.6102)
		(stroke
			(width 0.2)
			(type default)
		)
		(layer "In6.Cu")
	)
	(gr_line
		(start 197.108318 -80.7466)
		(end 197.108318 -81.5594)
		(stroke
			(width 0.2)
			(type default)
		)
		(layer "In6.Cu")
	)
	(gr_arc
		(start 197.157848 -73.89622)
		(mid 196.796025 -73.541889)
		(end 196.441568 -73.903586)
		(stroke
			(width 0.2)
			(type default)
		)
		(layer "In6.Cu")
	)
	(gr_line
		(start 197.159118 -81.6102)
		(end 197.362318 -81.6102)
		(stroke
			(width 0.2)
			(type default)
		)
		(layer "In6.Cu")
	)
	(gr_arc
		(start 197.159118 -80.6958)
		(mid 197.123197 -80.710679)
		(end 197.108318 -80.7466)
		(stroke
			(width 0.2)
			(type default)
		)
		(layer "In6.Cu")
	)
	(gr_line
		(start 197.165468 -86.232492)
		(end 197.793864 -85.604096)
		(stroke
			(width 0.2)
			(type default)
		)
		(layer "In6.Cu")
	)
	(gr_line
		(start 197.16623 -74.694542)
		(end 197.157848 -73.89622)
		(stroke
			(width 0.2)
			(type default)
		)
		(layer "In6.Cu")
	)
	(gr_line
		(start 197.241668 -73.904094)
		(end 197.251066 -74.70394)
		(stroke
			(width 0.2)
			(type default)
		)
		(layer "In6.Cu")
	)
	(gr_arc
		(start 197.251066 -74.70394)
		(mid 197.613524 -75.057762)
		(end 197.967346 -74.695304)
		(stroke
			(width 0.2)
			(type default)
		)
		(layer "In6.Cu")
	)
	(gr_line
		(start 197.254876 -85.065108)
		(end 196.631306 -85.688932)
		(stroke
			(width 0.2)
			(type default)
		)
		(layer "In6.Cu")
	)
	(gr_arc
		(start 197.362318 -81.6102)
		(mid 197.398239 -81.595321)
		(end 197.413118 -81.5594)
		(stroke
			(width 0.2)
			(type default)
		)
		(layer "In6.Cu")
	)
	(gr_line
		(start 197.362318 -80.6958)
		(end 197.159118 -80.6958)
		(stroke
			(width 0.2)
			(type default)
		)
		(layer "In6.Cu")
	)
	(gr_line
		(start 197.413118 -81.5594)
		(end 197.413118 -80.7466)
		(stroke
			(width 0.2)
			(type default)
		)
		(layer "In6.Cu")
	)
	(gr_arc
		(start 197.413118 -80.7466)
		(mid 197.398239 -80.710679)
		(end 197.362318 -80.6958)
		(stroke
			(width 0.2)
			(type default)
		)
		(layer "In6.Cu")
	)
	(gr_arc
		(start 197.667118 -81.5594)
		(mid 197.681997 -81.595321)
		(end 197.717918 -81.6102)
		(stroke
			(width 0.2)
			(type default)
		)
		(layer "In6.Cu")
	)
	(gr_line
		(start 197.667118 -80.7466)
		(end 197.667118 -81.5594)
		(stroke
			(width 0.2)
			(type default)
		)
		(layer "In6.Cu")
	)
	(gr_line
		(start 197.717918 -81.6102)
		(end 197.921118 -81.6102)
		(stroke
			(width 0.2)
			(type default)
		)
		(layer "In6.Cu")
	)
	(gr_arc
		(start 197.717918 -80.6958)
		(mid 197.681997 -80.710679)
		(end 197.667118 -80.7466)
		(stroke
			(width 0.2)
			(type default)
		)
		(layer "In6.Cu")
	)
	(gr_arc
		(start 197.793864 -85.604096)
		(mid 197.793864 -85.065108)
		(end 197.254876 -85.065108)
		(stroke
			(width 0.2)
			(type default)
		)
		(layer "In6.Cu")
	)
	(gr_arc
		(start 197.921118 -81.6102)
		(mid 197.957039 -81.595321)
		(end 197.971918 -81.5594)
		(stroke
			(width 0.2)
			(type default)
		)
		(layer "In6.Cu")
	)
	(gr_line
		(start 197.921118 -80.6958)
		(end 197.717918 -80.6958)
		(stroke
			(width 0.2)
			(type default)
		)
		(layer "In6.Cu")
	)
	(gr_arc
		(start 197.922134 -88.813132)
		(mid 197.915055 -89.354246)
		(end 198.456296 -89.356692)
		(stroke
			(width 0.2)
			(type default)
		)
		(layer "In6.Cu")
	)
	(gr_arc
		(start 197.957948 -73.895712)
		(mid 197.595617 -73.541888)
		(end 197.241668 -73.904094)
		(stroke
			(width 0.2)
			(type default)
		)
		(layer "In6.Cu")
	)
	(gr_line
		(start 197.967346 -74.695304)
		(end 197.957948 -73.895712)
		(stroke
			(width 0.2)
			(type default)
		)
		(layer "In6.Cu")
	)
	(gr_line
		(start 197.971918 -81.5594)
		(end 197.971918 -80.7466)
		(stroke
			(width 0.2)
			(type default)
		)
		(layer "In6.Cu")
	)
	(gr_arc
		(start 197.971918 -80.7466)
		(mid 197.957039 -80.710679)
		(end 197.921118 -80.6958)
		(stroke
			(width 0.2)
			(type default)
		)
		(layer "In6.Cu")
	)
	(gr_arc
		(start 198.378318 -81.5594)
		(mid 198.393197 -81.595321)
		(end 198.429118 -81.6102)
		(stroke
			(width 0.2)
			(type default)
		)
		(layer "In6.Cu")
	)
	(gr_line
		(start 198.378318 -80.7466)
		(end 198.378318 -81.5594)
		(stroke
			(width 0.2)
			(type default)
		)
		(layer "In6.Cu")
	)
	(gr_line
		(start 198.429118 -81.6102)
		(end 198.632318 -81.6102)
		(stroke
			(width 0.2)
			(type default)
		)
		(layer "In6.Cu")
	)
	(gr_arc
		(start 198.429118 -80.6958)
		(mid 198.393197 -80.710679)
		(end 198.378318 -80.7466)
		(stroke
			(width 0.2)
			(type default)
		)
		(layer "In6.Cu")
	)
	(gr_line
		(start 198.456296 -89.356692)
		(end 199.084692 -88.728296)
		(stroke
			(width 0.2)
			(type default)
		)
		(layer "In6.Cu")
	)
	(gr_line
		(start 198.545704 -88.189308)
		(end 197.922134 -88.813132)
		(stroke
			(width 0.2)
			(type default)
		)
		(layer "In6.Cu")
	)
	(gr_arc
		(start 198.632318 -81.6102)
		(mid 198.668239 -81.595321)
		(end 198.683118 -81.5594)
		(stroke
			(width 0.2)
			(type default)
		)
		(layer "In6.Cu")
	)
	(gr_line
		(start 198.632318 -80.6958)
		(end 198.429118 -80.6958)
		(stroke
			(width 0.2)
			(type default)
		)
		(layer "In6.Cu")
	)
	(gr_line
		(start 198.683118 -81.5594)
		(end 198.683118 -80.7466)
		(stroke
			(width 0.2)
			(type default)
		)
		(layer "In6.Cu")
	)
	(gr_arc
		(start 198.683118 -80.7466)
		(mid 198.668239 -80.710679)
		(end 198.632318 -80.6958)
		(stroke
			(width 0.2)
			(type default)
		)
		(layer "In6.Cu")
	)
	(gr_line
		(start 198.841614 -73.900538)
		(end 198.843392 -74.693018)
		(stroke
			(width 0.2)
			(type default)
		)
		(layer "In6.Cu")
	)
	(gr_arc
		(start 198.843392 -74.693018)
		(mid 199.202294 -75.050396)
		(end 199.559672 -74.691494)
		(stroke
			(width 0.2)
			(type default)
		)
		(layer "In6.Cu")
	)
	(gr_arc
		(start 198.937118 -81.5594)
		(mid 198.951997 -81.595321)
		(end 198.987918 -81.6102)
		(stroke
			(width 0.2)
			(type default)
		)
		(layer "In6.Cu")
	)
	(gr_line
		(start 198.937118 -80.7466)
		(end 198.937118 -81.5594)
		(stroke
			(width 0.2)
			(type default)
		)
		(layer "In6.Cu")
	)
	(gr_line
		(start 198.987918 -81.6102)
		(end 199.191118 -81.6102)
		(stroke
			(width 0.2)
			(type default)
		)
		(layer "In6.Cu")
	)
	(gr_arc
		(start 198.987918 -80.6958)
		(mid 198.951997 -80.710679)
		(end 198.937118 -80.7466)
		(stroke
			(width 0.2)
			(type default)
		)
		(layer "In6.Cu")
	)
	(gr_arc
		(start 199.084692 -88.728296)
		(mid 199.084692 -88.189308)
		(end 198.545704 -88.189308)
		(stroke
			(width 0.2)
			(type default)
		)
		(layer "In6.Cu")
	)
	(gr_arc
		(start 199.191118 -81.6102)
		(mid 199.227039 -81.595321)
		(end 199.241918 -81.5594)
		(stroke
			(width 0.2)
			(type default)
		)
		(layer "In6.Cu")
	)
	(gr_line
		(start 199.191118 -80.6958)
		(end 198.987918 -80.6958)
		(stroke
			(width 0.2)
			(type default)
		)
		(layer "In6.Cu")
	)
	(gr_line
		(start 199.241918 -81.5594)
		(end 199.241918 -80.7466)
		(stroke
			(width 0.2)
			(type default)
		)
		(layer "In6.Cu")
	)
	(gr_arc
		(start 199.241918 -80.7466)
		(mid 199.227039 -80.710679)
		(end 199.191118 -80.6958)
		(stroke
			(width 0.2)
			(type default)
		)
		(layer "In6.Cu")
	)
	(gr_arc
		(start 199.557894 -73.899268)
		(mid 199.199119 -73.54189)
		(end 198.841614 -73.900538)
		(stroke
			(width 0.2)
			(type default)
		)
		(layer "In6.Cu")
	)
	(gr_line
		(start 199.559672 -74.691494)
		(end 199.557894 -73.899268)
		(stroke
			(width 0.2)
			(type default)
		)
		(layer "In6.Cu")
	)
	(gr_line
		(start 199.641714 -73.900538)
		(end 199.643492 -74.695558)
		(stroke
			(width 0.2)
			(type default)
		)
		(layer "In6.Cu")
	)
	(gr_arc
		(start 199.643492 -74.695558)
		(mid 200.002394 -75.052936)
		(end 200.359772 -74.694034)
		(stroke
			(width 0.2)
			(type default)
		)
		(layer "In6.Cu")
	)
	(gr_arc
		(start 199.648318 -81.5594)
		(mid 199.663197 -81.595321)
		(end 199.699118 -81.6102)
		(stroke
			(width 0.2)
			(type default)
		)
		(layer "In6.Cu")
	)
	(gr_line
		(start 199.648318 -80.7466)
		(end 199.648318 -81.5594)
		(stroke
			(width 0.2)
			(type default)
		)
		(layer "In6.Cu")
	)
	(gr_line
		(start 199.699118 -81.6102)
		(end 199.902318 -81.6102)
		(stroke
			(width 0.2)
			(type default)
		)
		(layer "In6.Cu")
	)
	(gr_arc
		(start 199.699118 -80.6958)
		(mid 199.663197 -80.710679)
		(end 199.648318 -80.7466)
		(stroke
			(width 0.2)
			(type default)
		)
		(layer "In6.Cu")
	)
	(gr_arc
		(start 199.902318 -81.6102)
		(mid 199.938239 -81.595321)
		(end 199.953118 -81.5594)
		(stroke
			(width 0.2)
			(type default)
		)
		(layer "In6.Cu")
	)
	(gr_line
		(start 199.902318 -80.6958)
		(end 199.699118 -80.6958)
		(stroke
			(width 0.2)
			(type default)
		)
		(layer "In6.Cu")
	)
	(gr_line
		(start 199.953118 -81.5594)
		(end 199.953118 -80.7466)
		(stroke
			(width 0.2)
			(type default)
		)
		(layer "In6.Cu")
	)
	(gr_arc
		(start 199.953118 -80.7466)
		(mid 199.938239 -80.710679)
		(end 199.902318 -80.6958)
		(stroke
			(width 0.2)
			(type default)
		)
		(layer "In6.Cu")
	)
	(gr_arc
		(start 200.207118 -81.5594)
		(mid 200.221997 -81.595321)
		(end 200.257918 -81.6102)
		(stroke
			(width 0.2)
			(type default)
		)
		(layer "In6.Cu")
	)
	(gr_line
		(start 200.207118 -80.7466)
		(end 200.207118 -81.5594)
		(stroke
			(width 0.2)
			(type default)
		)
		(layer "In6.Cu")
	)
	(gr_line
		(start 200.257918 -81.6102)
		(end 200.461118 -81.6102)
		(stroke
			(width 0.2)
			(type default)
		)
		(layer "In6.Cu")
	)
	(gr_arc
		(start 200.257918 -80.6958)
		(mid 200.221997 -80.710679)
		(end 200.207118 -80.7466)
		(stroke
			(width 0.2)
			(type default)
		)
		(layer "In6.Cu")
	)
	(gr_arc
		(start 200.357994 -73.899268)
		(mid 199.999219 -73.54189)
		(end 199.641714 -73.900538)
		(stroke
			(width 0.2)
			(type default)
		)
		(layer "In6.Cu")
	)
	(gr_line
		(start 200.359772 -74.694034)
		(end 200.357994 -73.899268)
		(stroke
			(width 0.2)
			(type default)
		)
		(layer "In6.Cu")
	)
	(gr_arc
		(start 200.461118 -81.6102)
		(mid 200.497039 -81.595321)
		(end 200.511918 -81.5594)
		(stroke
			(width 0.2)
			(type default)
		)
		(layer "In6.Cu")
	)
	(gr_line
		(start 200.461118 -80.6958)
		(end 200.257918 -80.6958)
		(stroke
			(width 0.2)
			(type default)
		)
		(layer "In6.Cu")
	)
	(gr_line
		(start 200.511918 -81.5594)
		(end 200.511918 -80.7466)
		(stroke
			(width 0.2)
			(type default)
		)
		(layer "In6.Cu")
	)
	(gr_arc
		(start 200.511918 -80.7466)
		(mid 200.497039 -80.710679)
		(end 200.461118 -80.6958)
		(stroke
			(width 0.2)
			(type default)
		)
		(layer "In6.Cu")
	)
	(gr_line
		(start 200.79843 -74.287126)
		(end 201.598276 -74.287126)
		(stroke
			(width 0.2)
			(type default)
		)
		(layer "In6.Cu")
	)
	(gr_arc
		(start 200.798684 -73.520046)
		(mid 200.41489 -73.903459)
		(end 200.79843 -74.287126)
		(stroke
			(width 0.2)
			(type default)
		)
		(layer "In6.Cu")
	)
	(gr_arc
		(start 200.918318 -81.5594)
		(mid 200.933197 -81.595321)
		(end 200.969118 -81.6102)
		(stroke
			(width 0.2)
			(type default)
		)
		(layer "In6.Cu")
	)
	(gr_line
		(start 200.918318 -80.7466)
		(end 200.918318 -81.5594)
		(stroke
			(width 0.2)
			(type default)
		)
		(layer "In6.Cu")
	)
	(gr_arc
		(start 200.944734 -85.815932)
		(mid 200.937655 -86.357046)
		(end 201.478896 -86.359492)
		(stroke
			(width 0.2)
			(type default)
		)
		(layer "In6.Cu")
	)
	(gr_line
		(start 200.969118 -81.6102)
		(end 201.172318 -81.6102)
		(stroke
			(width 0.2)
			(type default)
		)
		(layer "In6.Cu")
	)
	(gr_arc
		(start 200.969118 -80.6958)
		(mid 200.933197 -80.710679)
		(end 200.918318 -80.7466)
		(stroke
			(width 0.2)
			(type default)
		)
		(layer "In6.Cu")
	)
	(gr_arc
		(start 201.172318 -81.6102)
		(mid 201.208239 -81.595321)
		(end 201.223118 -81.5594)
		(stroke
			(width 0.2)
			(type default)
		)
		(layer "In6.Cu")
	)
	(gr_line
		(start 201.172318 -80.6958)
		(end 200.969118 -80.6958)
		(stroke
			(width 0.2)
			(type default)
		)
		(layer "In6.Cu")
	)
	(gr_arc
		(start 201.209656 -67.49923)
		(mid 201.590021 -67.886073)
		(end 201.976736 -67.50558)
		(stroke
			(width 0.2)
			(type default)
		)
		(layer "In6.Cu")
	)
	(gr_arc
		(start 201.20991 -72.297036)
		(mid 201.592815 -72.681338)
		(end 201.97699 -72.298306)
		(stroke
			(width 0.2)
			(type default)
		)
		(layer "In6.Cu")
	)
	(gr_line
		(start 201.210926 -71.502524)
		(end 201.20991 -72.297036)
		(stroke
			(width 0.2)
			(type default)
		)
		(layer "In6.Cu")
	)
	(gr_line
		(start 201.211688 -69.111114)
		(end 201.225658 -69.906388)
		(stroke
			(width 0.2)
			(type default)
		)
		(layer "In6.Cu")
	)
	(gr_line
		(start 201.216006 -66.705988)
		(end 201.209656 -67.49923)
		(stroke
			(width 0.2)
			(type default)
		)
		(layer "In6.Cu")
	)
	(gr_line
		(start 201.223118 -81.5594)
		(end 201.223118 -80.7466)
		(stroke
			(width 0.2)
			(type default)
		)
		(layer "In6.Cu")
	)
	(gr_arc
		(start 201.223118 -80.7466)
		(mid 201.208239 -80.710679)
		(end 201.172318 -80.6958)
		(stroke
			(width 0.2)
			(type default)
		)
		(layer "In6.Cu")
	)
	(gr_arc
		(start 201.225658 -69.906388)
		(mid 201.615929 -70.283322)
		(end 201.992738 -69.892926)
		(stroke
			(width 0.2)
			(type default)
		)
		(layer "In6.Cu")
	)
	(gr_arc
		(start 201.477118 -81.5594)
		(mid 201.491997 -81.595321)
		(end 201.527918 -81.6102)
		(stroke
			(width 0.2)
			(type default)
		)
		(layer "In6.Cu")
	)
	(gr_line
		(start 201.477118 -80.7466)
		(end 201.477118 -81.5594)
		(stroke
			(width 0.2)
			(type default)
		)
		(layer "In6.Cu")
	)
	(gr_line
		(start 201.478896 -86.359492)
		(end 202.107292 -85.731096)
		(stroke
			(width 0.2)
			(type default)
		)
		(layer "In6.Cu")
	)
	(gr_line
		(start 201.527918 -81.6102)
		(end 201.731118 -81.6102)
		(stroke
			(width 0.2)
			(type default)
		)
		(layer "In6.Cu")
	)
	(gr_arc
		(start 201.527918 -80.6958)
		(mid 201.491997 -80.710679)
		(end 201.477118 -80.7466)
		(stroke
			(width 0.2)
			(type default)
		)
		(layer "In6.Cu")
	)
	(gr_line
		(start 201.568304 -85.192108)
		(end 200.944734 -85.815932)
		(stroke
			(width 0.2)
			(type default)
		)
		(layer "In6.Cu")
	)
	(gr_line
		(start 201.591672 -68.678806)
		(end 202.39609 -68.68668)
		(stroke
			(width 0.2)
			(type default)
		)
		(layer "In6.Cu")
	)
	(gr_line
		(start 201.592688 -71.086218)
		(end 202.40371 -71.087996)
		(stroke
			(width 0.2)
			(type default)
		)
		(layer "In6.Cu")
	)
	(gr_arc
		(start 201.594466 -70.319138)
		(mid 201.210164 -70.701789)
		(end 201.592688 -71.086218)
		(stroke
			(width 0.2)
			(type default)
		)
		(layer "In6.Cu")
	)
	(gr_arc
		(start 201.598276 -74.287126)
		(mid 201.981816 -73.903586)
		(end 201.598276 -73.520046)
		(stroke
			(width 0.2)
			(type default)
		)
		(layer "In6.Cu")
	)
	(gr_line
		(start 201.598276 -73.520046)
		(end 200.798684 -73.520046)
		(stroke
			(width 0.2)
			(type default)
		)
		(layer "In6.Cu")
	)
	(gr_arc
		(start 201.599292 -72.716898)
		(mid 201.217276 -73.101835)
		(end 201.602086 -73.483978)
		(stroke
			(width 0.2)
			(type default)
		)
		(layer "In6.Cu")
	)
	(gr_arc
		(start 201.599546 -67.911726)
		(mid 201.212197 -68.291329)
		(end 201.591672 -68.678806)
		(stroke
			(width 0.2)
			(type default)
		)
		(layer "In6.Cu")
	)
	(gr_line
		(start 201.5998 -75.883262)
		(end 202.399646 -75.883262)
		(stroke
			(width 0.2)
			(type default)
		)
		(layer "In6.Cu")
	)
	(gr_arc
		(start 201.600054 -75.116182)
		(mid 201.21626 -75.499595)
		(end 201.5998 -75.883262)
		(stroke
			(width 0.2)
			(type default)
		)
		(layer "In6.Cu")
	)
	(gr_line
		(start 201.602086 -73.483978)
		(end 202.39863 -73.480676)
		(stroke
			(width 0.2)
			(type default)
		)
		(layer "In6.Cu")
	)
	(gr_arc
		(start 201.731118 -81.6102)
		(mid 201.767039 -81.595321)
		(end 201.781918 -81.5594)
		(stroke
			(width 0.2)
			(type default)
		)
		(layer "In6.Cu")
	)
	(gr_line
		(start 201.731118 -80.6958)
		(end 201.527918 -80.6958)
		(stroke
			(width 0.2)
			(type default)
		)
		(layer "In6.Cu")
	)
	(gr_line
		(start 201.781918 -81.5594)
		(end 201.781918 -80.7466)
		(stroke
			(width 0.2)
			(type default)
		)
		(layer "In6.Cu")
	)
	(gr_arc
		(start 201.781918 -80.7466)
		(mid 201.767039 -80.710679)
		(end 201.731118 -80.6958)
		(stroke
			(width 0.2)
			(type default)
		)
		(layer "In6.Cu")
	)
	(gr_line
		(start 201.976736 -67.50558)
		(end 201.983086 -66.712084)
		(stroke
			(width 0.2)
			(type default)
		)
		(layer "In6.Cu")
	)
	(gr_line
		(start 201.97699 -72.298306)
		(end 201.978006 -71.50354)
		(stroke
			(width 0.2)
			(type default)
		)
		(layer "In6.Cu")
	)
	(gr_arc
		(start 201.978006 -71.50354)
		(mid 201.594974 -71.119492)
		(end 201.210926 -71.502524)
		(stroke
			(width 0.2)
			(type default)
		)
		(layer "In6.Cu")
	)
	(gr_arc
		(start 201.978768 -69.097398)
		(mid 201.58837 -68.720716)
		(end 201.211688 -69.111114)
		(stroke
			(width 0.2)
			(type default)
		)
		(layer "In6.Cu")
	)
	(gr_arc
		(start 201.983086 -66.712084)
		(mid 201.602594 -66.325496)
		(end 201.216006 -66.705988)
		(stroke
			(width 0.2)
			(type default)
		)
		(layer "In6.Cu")
	)
	(gr_line
		(start 201.992738 -69.892926)
		(end 201.978768 -69.097398)
		(stroke
			(width 0.2)
			(type default)
		)
		(layer "In6.Cu")
	)
	(gr_arc
		(start 202.107292 -85.731096)
		(mid 202.107292 -85.192108)
		(end 201.568304 -85.192108)
		(stroke
			(width 0.2)
			(type default)
		)
		(layer "In6.Cu")
	)
	(gr_line
		(start 202.395582 -72.713596)
		(end 201.599292 -72.716898)
		(stroke
			(width 0.2)
			(type default)
		)
		(layer "In6.Cu")
	)
	(gr_arc
		(start 202.39609 -68.68668)
		(mid 202.78344 -68.30695)
		(end 202.40371 -67.9196)
		(stroke
			(width 0.2)
			(type default)
		)
		(layer "In6.Cu")
	)
	(gr_arc
		(start 202.39863 -73.480676)
		(mid 202.780646 -73.095612)
		(end 202.395582 -72.713596)
		(stroke
			(width 0.2)
			(type default)
		)
		(layer "In6.Cu")
	)
	(gr_arc
		(start 202.399646 -75.883262)
		(mid 202.783186 -75.499722)
		(end 202.399646 -75.116182)
		(stroke
			(width 0.2)
			(type default)
		)
		(layer "In6.Cu")
	)
	(gr_line
		(start 202.399646 -75.116182)
		(end 201.600054 -75.116182)
		(stroke
			(width 0.2)
			(type default)
		)
		(layer "In6.Cu")
	)
	(gr_arc
		(start 202.40371 -71.087996)
		(mid 202.788012 -70.705218)
		(end 202.405234 -70.320916)
		(stroke
			(width 0.2)
			(type default)
		)
		(layer "In6.Cu")
	)
	(gr_line
		(start 202.40371 -67.9196)
		(end 201.599546 -67.911726)
		(stroke
			(width 0.2)
			(type default)
		)
		(layer "In6.Cu")
	)
	(gr_line
		(start 202.405234 -70.320916)
		(end 201.594466 -70.319138)
		(stroke
			(width 0.2)
			(type default)
		)
		(layer "In6.Cu")
	)
	(gr_arc
		(start 203.535534 -85.231732)
		(mid 203.528455 -85.772846)
		(end 204.069696 -85.775292)
		(stroke
			(width 0.2)
			(type default)
		)
		(layer "In6.Cu")
	)
	(gr_line
		(start 204.069696 -85.775292)
		(end 204.698092 -85.146896)
		(stroke
			(width 0.2)
			(type default)
		)
		(layer "In6.Cu")
	)
	(gr_line
		(start 204.159104 -84.607908)
		(end 203.535534 -85.231732)
		(stroke
			(width 0.2)
			(type default)
		)
		(layer "In6.Cu")
	)
	(gr_arc
		(start 204.698092 -85.146896)
		(mid 204.698092 -84.607908)
		(end 204.159104 -84.607908)
		(stroke
			(width 0.2)
			(type default)
		)
		(layer "In6.Cu")
	)
	(gr_line
		(start 210.790536 -63.655194)
		(end 210.79079 -63.655448)
		(stroke
			(width 0.2)
			(type default)
		)
		(layer "In6.Cu")
	)
	(gr_arc
		(start 210.79079 -63.655448)
		(mid 210.79079 -64.193928)
		(end 211.32927 -64.193928)
		(stroke
			(width 0.2)
			(type default)
		)
		(layer "In6.Cu")
	)
	(gr_line
		(start 210.959192 -66.09842)
		(end 210.959446 -66.098674)
		(stroke
			(width 0.2)
			(type default)
		)
		(layer "In6.Cu")
	)
	(gr_arc
		(start 210.959446 -66.098674)
		(mid 210.959446 -66.637154)
		(end 211.497926 -66.637154)
		(stroke
			(width 0.2)
			(type default)
		)
		(layer "In6.Cu")
	)
	(gr_line
		(start 211.32927 -64.193928)
		(end 211.329524 -64.194182)
		(stroke
			(width 0.2)
			(type default)
		)
		(layer "In6.Cu")
	)
	(gr_line
		(start 211.329524 -64.194182)
		(end 212.137498 -63.385954)
		(stroke
			(width 0.2)
			(type default)
		)
		(layer "In6.Cu")
	)
	(gr_line
		(start 211.497926 -66.637154)
		(end 211.49818 -66.637408)
		(stroke
			(width 0.2)
			(type default)
		)
		(layer "In6.Cu")
	)
	(gr_line
		(start 211.49818 -66.637408)
		(end 212.306154 -65.82918)
		(stroke
			(width 0.2)
			(type default)
		)
		(layer "In6.Cu")
	)
	(gr_line
		(start 211.598764 -62.846966)
		(end 210.790536 -63.655194)
		(stroke
			(width 0.2)
			(type default)
		)
		(layer "In6.Cu")
	)
	(gr_line
		(start 211.599018 -62.84722)
		(end 211.598764 -62.846966)
		(stroke
			(width 0.2)
			(type default)
		)
		(layer "In6.Cu")
	)
	(gr_line
		(start 211.76742 -65.290192)
		(end 210.959192 -66.09842)
		(stroke
			(width 0.2)
			(type default)
		)
		(layer "In6.Cu")
	)
	(gr_line
		(start 211.767674 -65.290446)
		(end 211.76742 -65.290192)
		(stroke
			(width 0.2)
			(type default)
		)
		(layer "In6.Cu")
	)
	(gr_line
		(start 212.137498 -63.385954)
		(end 212.137498 -63.3857)
		(stroke
			(width 0.2)
			(type default)
		)
		(layer "In6.Cu")
	)
	(gr_arc
		(start 212.137498 -63.3857)
		(mid 212.137498 -62.84722)
		(end 211.599018 -62.84722)
		(stroke
			(width 0.2)
			(type default)
		)
		(layer "In6.Cu")
	)
	(gr_line
		(start 212.306154 -65.82918)
		(end 212.306154 -65.828926)
		(stroke
			(width 0.2)
			(type default)
		)
		(layer "In6.Cu")
	)
	(gr_arc
		(start 212.306154 -65.828926)
		(mid 212.306154 -65.290446)
		(end 211.767674 -65.290446)
		(stroke
			(width 0.2)
			(type default)
		)
		(layer "In6.Cu")
	)
	(gr_line
		(start 212.432392 -67.74942)
		(end 212.432646 -67.749674)
		(stroke
			(width 0.2)
			(type default)
		)
		(layer "In6.Cu")
	)
	(gr_arc
		(start 212.432646 -67.749674)
		(mid 212.432646 -68.288154)
		(end 212.971126 -68.288154)
		(stroke
			(width 0.2)
			(type default)
		)
		(layer "In6.Cu")
	)
	(gr_line
		(start 212.971126 -68.288154)
		(end 212.97138 -68.288408)
		(stroke
			(width 0.2)
			(type default)
		)
		(layer "In6.Cu")
	)
	(gr_line
		(start 212.97138 -68.288408)
		(end 213.779354 -67.48018)
		(stroke
			(width 0.2)
			(type default)
		)
		(layer "In6.Cu")
	)
	(gr_line
		(start 213.24062 -66.941192)
		(end 212.432392 -67.74942)
		(stroke
			(width 0.2)
			(type default)
		)
		(layer "In6.Cu")
	)
	(gr_line
		(start 213.240874 -66.941446)
		(end 213.24062 -66.941192)
		(stroke
			(width 0.2)
			(type default)
		)
		(layer "In6.Cu")
	)
	(gr_line
		(start 213.448392 -72.52462)
		(end 213.448646 -72.524874)
		(stroke
			(width 0.2)
			(type default)
		)
		(layer "In6.Cu")
	)
	(gr_arc
		(start 213.448646 -72.524874)
		(mid 213.448646 -73.063354)
		(end 213.987126 -73.063354)
		(stroke
			(width 0.2)
			(type default)
		)
		(layer "In6.Cu")
	)
	(gr_line
		(start 213.779354 -67.48018)
		(end 213.779354 -67.479926)
		(stroke
			(width 0.2)
			(type default)
		)
		(layer "In6.Cu")
	)
	(gr_arc
		(start 213.779354 -67.479926)
		(mid 213.779354 -66.941446)
		(end 213.240874 -66.941446)
		(stroke
			(width 0.2)
			(type default)
		)
		(layer "In6.Cu")
	)
	(gr_line
		(start 213.956392 -69.22262)
		(end 213.956646 -69.222874)
		(stroke
			(width 0.2)
			(type default)
		)
		(layer "In6.Cu")
	)
	(gr_arc
		(start 213.956646 -69.222874)
		(mid 213.956646 -69.761354)
		(end 214.495126 -69.761354)
		(stroke
			(width 0.2)
			(type default)
		)
		(layer "In6.Cu")
	)
	(gr_line
		(start 213.987126 -73.063354)
		(end 213.98738 -73.063608)
		(stroke
			(width 0.2)
			(type default)
		)
		(layer "In6.Cu")
	)
	(gr_line
		(start 213.98738 -73.063608)
		(end 214.795354 -72.25538)
		(stroke
			(width 0.2)
			(type default)
		)
		(layer "In6.Cu")
	)
	(gr_line
		(start 214.25662 -71.716392)
		(end 213.448392 -72.52462)
		(stroke
			(width 0.2)
			(type default)
		)
		(layer "In6.Cu")
	)
	(gr_line
		(start 214.256874 -71.716646)
		(end 214.25662 -71.716392)
		(stroke
			(width 0.2)
			(type default)
		)
		(layer "In6.Cu")
	)
	(gr_line
		(start 214.495126 -69.761354)
		(end 214.49538 -69.761608)
		(stroke
			(width 0.2)
			(type default)
		)
		(layer "In6.Cu")
	)
	(gr_line
		(start 214.49538 -69.761608)
		(end 215.303354 -68.95338)
		(stroke
			(width 0.2)
			(type default)
		)
		(layer "In6.Cu")
	)
	(gr_line
		(start 214.76462 -68.414392)
		(end 213.956392 -69.22262)
		(stroke
			(width 0.2)
			(type default)
		)
		(layer "In6.Cu")
	)
	(gr_line
		(start 214.764874 -68.414646)
		(end 214.76462 -68.414392)
		(stroke
			(width 0.2)
			(type default)
		)
		(layer "In6.Cu")
	)
	(gr_line
		(start 214.795354 -72.25538)
		(end 214.795354 -72.255126)
		(stroke
			(width 0.2)
			(type default)
		)
		(layer "In6.Cu")
	)
	(gr_arc
		(start 214.795354 -72.255126)
		(mid 214.795354 -71.716646)
		(end 214.256874 -71.716646)
		(stroke
			(width 0.2)
			(type default)
		)
		(layer "In6.Cu")
	)
	(gr_line
		(start 214.845392 -73.92162)
		(end 214.845646 -73.921874)
		(stroke
			(width 0.2)
			(type default)
		)
		(layer "In6.Cu")
	)
	(gr_arc
		(start 214.845646 -73.921874)
		(mid 214.845646 -74.460354)
		(end 215.384126 -74.460354)
		(stroke
			(width 0.2)
			(type default)
		)
		(layer "In6.Cu")
	)
	(gr_line
		(start 215.226392 -79.38262)
		(end 215.226646 -79.382874)
		(stroke
			(width 0.2)
			(type default)
		)
		(layer "In6.Cu")
	)
	(gr_arc
		(start 215.226646 -79.382874)
		(mid 215.226646 -79.921354)
		(end 215.765126 -79.921354)
		(stroke
			(width 0.2)
			(type default)
		)
		(layer "In6.Cu")
	)
	(gr_line
		(start 215.303354 -68.95338)
		(end 215.303354 -68.953126)
		(stroke
			(width 0.2)
			(type default)
		)
		(layer "In6.Cu")
	)
	(gr_arc
		(start 215.303354 -68.953126)
		(mid 215.303354 -68.414646)
		(end 214.764874 -68.414646)
		(stroke
			(width 0.2)
			(type default)
		)
		(layer "In6.Cu")
	)
	(gr_line
		(start 215.384126 -74.460354)
		(end 215.38438 -74.460608)
		(stroke
			(width 0.2)
			(type default)
		)
		(layer "In6.Cu")
	)
	(gr_line
		(start 215.38438 -74.460608)
		(end 216.192354 -73.65238)
		(stroke
			(width 0.2)
			(type default)
		)
		(layer "In6.Cu")
	)
	(gr_line
		(start 215.65362 -73.113392)
		(end 214.845392 -73.92162)
		(stroke
			(width 0.2)
			(type default)
		)
		(layer "In6.Cu")
	)
	(gr_line
		(start 215.653874 -73.113646)
		(end 215.65362 -73.113392)
		(stroke
			(width 0.2)
			(type default)
		)
		(layer "In6.Cu")
	)
	(gr_line
		(start 215.765126 -79.921354)
		(end 215.76538 -79.921608)
		(stroke
			(width 0.2)
			(type default)
		)
		(layer "In6.Cu")
	)
	(gr_line
		(start 215.76538 -79.921608)
		(end 216.573354 -79.11338)
		(stroke
			(width 0.2)
			(type default)
		)
		(layer "In6.Cu")
	)
	(gr_line
		(start 216.03462 -78.574392)
		(end 215.226392 -79.38262)
		(stroke
			(width 0.2)
			(type default)
		)
		(layer "In6.Cu")
	)
	(gr_line
		(start 216.034874 -78.574646)
		(end 216.03462 -78.574392)
		(stroke
			(width 0.2)
			(type default)
		)
		(layer "In6.Cu")
	)
	(gr_line
		(start 216.192354 -73.65238)
		(end 216.192354 -73.652126)
		(stroke
			(width 0.2)
			(type default)
		)
		(layer "In6.Cu")
	)
	(gr_arc
		(start 216.192354 -73.652126)
		(mid 216.192354 -73.113646)
		(end 215.653874 -73.113646)
		(stroke
			(width 0.2)
			(type default)
		)
		(layer "In6.Cu")
	)
	(gr_line
		(start 216.369392 -75.44562)
		(end 216.369646 -75.445874)
		(stroke
			(width 0.2)
			(type default)
		)
		(layer "In6.Cu")
	)
	(gr_arc
		(start 216.369646 -75.445874)
		(mid 216.369646 -75.984354)
		(end 216.908126 -75.984354)
		(stroke
			(width 0.2)
			(type default)
		)
		(layer "In6.Cu")
	)
	(gr_line
		(start 216.573354 -79.11338)
		(end 216.573354 -79.113126)
		(stroke
			(width 0.2)
			(type default)
		)
		(layer "In6.Cu")
	)
	(gr_arc
		(start 216.573354 -79.113126)
		(mid 216.573354 -78.574646)
		(end 216.034874 -78.574646)
		(stroke
			(width 0.2)
			(type default)
		)
		(layer "In6.Cu")
	)
	(gr_line
		(start 216.908126 -75.984354)
		(end 216.90838 -75.984608)
		(stroke
			(width 0.2)
			(type default)
		)
		(layer "In6.Cu")
	)
	(gr_line
		(start 216.90838 -75.984608)
		(end 217.716354 -75.17638)
		(stroke
			(width 0.2)
			(type default)
		)
		(layer "In6.Cu")
	)
	(gr_line
		(start 217.17762 -74.637392)
		(end 216.369392 -75.44562)
		(stroke
			(width 0.2)
			(type default)
		)
		(layer "In6.Cu")
	)
	(gr_line
		(start 217.177874 -74.637646)
		(end 217.17762 -74.637392)
		(stroke
			(width 0.2)
			(type default)
		)
		(layer "In6.Cu")
	)
	(gr_line
		(start 217.716354 -75.17638)
		(end 217.716354 -75.176126)
		(stroke
			(width 0.2)
			(type default)
		)
		(layer "In6.Cu")
	)
	(gr_arc
		(start 217.716354 -75.176126)
		(mid 217.716354 -74.637646)
		(end 217.177874 -74.637646)
		(stroke
			(width 0.2)
			(type default)
		)
		(layer "In6.Cu")
	)
	(gr_line
		(start 229.382066 -194.00012)
		(end 149.917912 -194.00012)
		(stroke
			(width 1.524)
			(type default)
		)
		(layer "In6.Cu")
	)
	(gr_arc
		(start 229.382066 -194.00012)
		(mid 229.907793 -193.850701)
		(end 230.2764 -193.447162)
		(stroke
			(width 1.524)
			(type default)
		)
		(layer "In6.Cu")
	)
	(gr_line
		(start 234.894374 -184.211214)
		(end 230.2764 -193.447162)
		(stroke
			(width 1.524)
			(type default)
		)
		(layer "In6.Cu")
	)
	(gr_arc
		(start 234.894374 -184.211214)
		(mid 234.97328 -183.993726)
		(end 235.000038 -183.76392)
		(stroke
			(width 1.524)
			(type default)
		)
		(layer "In6.Cu")
	)
	(gr_arc
		(start 235.000038 -0.999998)
		(mid 234.707147 -0.29288)
		(end 234.00004 0)
		(stroke
			(width 1.524)
			(type default)
		)
		(layer "In6.Cu")
	)
	(gr_line
		(start 235.000038 -0.999998)
		(end 235.000038 -183.76392)
		(stroke
			(width 1.524)
			(type default)
		)
		(layer "In6.Cu")
	)
	(gr_line
		(start 0 -183.76392)
		(end 0 -0.999998)
		(stroke
			(width 0.05)
			(type default)
		)
		(layer "Edge.Cuts")
	)
	(gr_arc
		(start 0 -183.76392)
		(mid 0.026807 -183.993715)
		(end 0.105664 -184.211214)
		(stroke
			(width 0.05)
			(type default)
		)
		(layer "Edge.Cuts")
	)
	(gr_arc
		(start 0.999998 0)
		(mid 0.292893 -0.292893)
		(end 0 -0.999998)
		(stroke
			(width 0.05)
			(type default)
		)
		(layer "Edge.Cuts")
	)
	(gr_line
		(start 0.999998 0)
		(end 29.53004 0)
		(stroke
			(width 0.05)
			(type default)
		)
		(layer "Edge.Cuts")
	)
	(gr_line
		(start 4.723638 -193.447162)
		(end 0.105664 -184.211214)
		(stroke
			(width 0.05)
			(type default)
		)
		(layer "Edge.Cuts")
	)
	(gr_arc
		(start 4.723638 -193.447162)
		(mid 5.092281 -193.850645)
		(end 5.617972 -194.00012)
		(stroke
			(width 0.05)
			(type default)
		)
		(layer "Edge.Cuts")
	)
	(gr_arc
		(start 10.500106 -187.999878)
		(mid 12.500102 -189.999874)
		(end 14.500098 -187.999878)
		(stroke
			(width 0.05)
			(type default)
		)
		(layer "Edge.Cuts")
	)
	(gr_arc
		(start 14.500098 -187.999878)
		(mid 12.500102 -185.999882)
		(end 10.500106 -187.999878)
		(stroke
			(width 0.05)
			(type default)
		)
		(layer "Edge.Cuts")
	)
	(gr_arc
		(start 16.249904 -120.000014)
		(mid 17.999964 -121.750074)
		(end 19.750024 -120.000014)
		(stroke
			(width 0.05)
			(type default)
		)
		(layer "Edge.Cuts")
	)
	(gr_arc
		(start 16.249904 -24.99995)
		(mid 17.999964 -26.75001)
		(end 19.750024 -24.99995)
		(stroke
			(width 0.05)
			(type default)
		)
		(layer "Edge.Cuts")
	)
	(gr_arc
		(start 19.750024 -120.000014)
		(mid 17.999964 -118.249954)
		(end 16.249904 -120.000014)
		(stroke
			(width 0.05)
			(type default)
		)
		(layer "Edge.Cuts")
	)
	(gr_arc
		(start 19.750024 -24.99995)
		(mid 17.999964 -23.24989)
		(end 16.249904 -24.99995)
		(stroke
			(width 0.05)
			(type default)
		)
		(layer "Edge.Cuts")
	)
	(gr_line
		(start 21.100034 -62.250066)
		(end 24.500078 -62.250066)
		(stroke
			(width 0.05)
			(type default)
		)
		(layer "Edge.Cuts")
	)
	(gr_arc
		(start 21.100034 -58.850022)
		(mid 19.400012 -60.550044)
		(end 21.100034 -62.250066)
		(stroke
			(width 0.05)
			(type default)
		)
		(layer "Edge.Cuts")
	)
	(gr_arc
		(start 21.249894 -105.050082)
		(mid 22.900132 -106.70032)
		(end 24.550116 -105.050082)
		(stroke
			(width 0.05)
			(type default)
		)
		(layer "Edge.Cuts")
	)
	(gr_arc
		(start 24.500078 -62.250066)
		(mid 26.2001 -60.550044)
		(end 24.500078 -58.850022)
		(stroke
			(width 0.05)
			(type default)
		)
		(layer "Edge.Cuts")
	)
	(gr_line
		(start 24.500078 -58.850022)
		(end 21.100034 -58.850022)
		(stroke
			(width 0.05)
			(type default)
		)
		(layer "Edge.Cuts")
	)
	(gr_arc
		(start 24.550116 -105.050082)
		(mid 22.900132 -103.400098)
		(end 21.249894 -105.050082)
		(stroke
			(width 0.05)
			(type default)
		)
		(layer "Edge.Cuts")
	)
	(gr_arc
		(start 30.530038 -109.050074)
		(mid 30.822931 -109.757179)
		(end 31.530036 -110.050072)
		(stroke
			(width 0.05)
			(type default)
		)
		(layer "Edge.Cuts")
	)
	(gr_arc
		(start 30.530038 -0.999998)
		(mid 30.237147 -0.29288)
		(end 29.53004 0)
		(stroke
			(width 0.05)
			(type default)
		)
		(layer "Edge.Cuts")
	)
	(gr_line
		(start 30.530038 -0.999998)
		(end 30.530038 -109.050074)
		(stroke
			(width 0.05)
			(type default)
		)
		(layer "Edge.Cuts")
	)
	(gr_line
		(start 31.530036 -110.050072)
		(end 72.030082 -110.050072)
		(stroke
			(width 0.05)
			(type default)
		)
		(layer "Edge.Cuts")
	)
	(gr_arc
		(start 39.349934 -169.999914)
		(mid 41.450006 -172.099986)
		(end 43.550078 -169.999914)
		(stroke
			(width 0.05)
			(type default)
		)
		(layer "Edge.Cuts")
	)
	(gr_arc
		(start 43.550078 -169.999914)
		(mid 41.450006 -167.899842)
		(end 39.349934 -169.999914)
		(stroke
			(width 0.05)
			(type default)
		)
		(layer "Edge.Cuts")
	)
	(gr_arc
		(start 72.030082 -110.050072)
		(mid 72.737187 -109.757179)
		(end 73.03008 -109.050074)
		(stroke
			(width 0.05)
			(type default)
		)
		(layer "Edge.Cuts")
	)
	(gr_line
		(start 73.03008 -109.050074)
		(end 73.03008 -0.999998)
		(stroke
			(width 0.05)
			(type default)
		)
		(layer "Edge.Cuts")
	)
	(gr_arc
		(start 74.030078 0)
		(mid 73.322986 -0.2929)
		(end 73.03008 -0.999998)
		(stroke
			(width 0.05)
			(type default)
		)
		(layer "Edge.Cuts")
	)
	(gr_line
		(start 74.030078 0)
		(end 234.00004 0)
		(stroke
			(width 0.05)
			(type default)
		)
		(layer "Edge.Cuts")
	)
	(gr_line
		(start 76.849986 -106.750104)
		(end 80.25003 -106.750104)
		(stroke
			(width 0.05)
			(type default)
		)
		(layer "Edge.Cuts")
	)
	(gr_arc
		(start 76.849986 -103.35006)
		(mid 75.149964 -105.050082)
		(end 76.849986 -106.750104)
		(stroke
			(width 0.05)
			(type default)
		)
		(layer "Edge.Cuts")
	)
	(gr_arc
		(start 76.849986 -40.049958)
		(mid 78.49997 -41.699942)
		(end 80.149954 -40.049958)
		(stroke
			(width 0.05)
			(type default)
		)
		(layer "Edge.Cuts")
	)
	(gr_arc
		(start 78.250034 -120.000014)
		(mid 80.000094 -121.750074)
		(end 81.7499 -120.000014)
		(stroke
			(width 0.05)
			(type default)
		)
		(layer "Edge.Cuts")
	)
	(gr_arc
		(start 80.149954 -40.049958)
		(mid 78.49997 -38.399974)
		(end 76.849986 -40.049958)
		(stroke
			(width 0.05)
			(type default)
		)
		(layer "Edge.Cuts")
	)
	(gr_arc
		(start 80.25003 -106.750104)
		(mid 81.950052 -105.050082)
		(end 80.25003 -103.35006)
		(stroke
			(width 0.05)
			(type default)
		)
		(layer "Edge.Cuts")
	)
	(gr_line
		(start 80.25003 -103.35006)
		(end 76.849986 -103.35006)
		(stroke
			(width 0.05)
			(type default)
		)
		(layer "Edge.Cuts")
	)
	(gr_arc
		(start 81.7499 -120.000014)
		(mid 80.000094 -118.250208)
		(end 78.250034 -120.000014)
		(stroke
			(width 0.05)
			(type default)
		)
		(layer "Edge.Cuts")
	)
	(gr_arc
		(start 90.749882 -187.999878)
		(mid 92.499942 -189.749938)
		(end 94.250002 -187.999878)
		(stroke
			(width 0.05)
			(type default)
		)
		(layer "Edge.Cuts")
	)
	(gr_arc
		(start 94.250002 -187.999878)
		(mid 92.499942 -186.249818)
		(end 90.749882 -187.999878)
		(stroke
			(width 0.05)
			(type default)
		)
		(layer "Edge.Cuts")
	)
	(gr_line
		(start 98.081846 -194.00012)
		(end 5.617972 -194.00012)
		(stroke
			(width 0.05)
			(type default)
		)
		(layer "Edge.Cuts")
	)
	(gr_arc
		(start 98.081846 -194.00012)
		(mid 98.607706 -193.850755)
		(end 98.976434 -193.447162)
		(stroke
			(width 0.05)
			(type default)
		)
		(layer "Edge.Cuts")
	)
	(gr_arc
		(start 101.249988 -9.99998)
		(mid 103.000048 -11.75004)
		(end 104.750108 -9.99998)
		(stroke
			(width 0.05)
			(type default)
		)
		(layer "Edge.Cuts")
	)
	(gr_line
		(start 103.594408 -184.211214)
		(end 98.976434 -193.447162)
		(stroke
			(width 0.05)
			(type default)
		)
		(layer "Edge.Cuts")
	)
	(gr_arc
		(start 103.594408 -184.211214)
		(mid 103.673311 -183.993725)
		(end 103.700072 -183.76392)
		(stroke
			(width 0.05)
			(type default)
		)
		(layer "Edge.Cuts")
	)
	(gr_line
		(start 103.700072 -47.999904)
		(end 103.700072 -183.76392)
		(stroke
			(width 0.05)
			(type default)
		)
		(layer "Edge.Cuts")
	)
	(gr_arc
		(start 104.70007 -47.999904)
		(mid 104.200198 -47.500032)
		(end 103.700072 -47.999904)
		(stroke
			(width 0.05)
			(type default)
		)
		(layer "Edge.Cuts")
	)
	(gr_arc
		(start 104.750108 -9.99998)
		(mid 103.000048 -8.24992)
		(end 101.249988 -9.99998)
		(stroke
			(width 0.05)
			(type default)
		)
		(layer "Edge.Cuts")
	)
	(gr_arc
		(start 122.890026 -34.854896)
		(mid 124.165106 -36.129976)
		(end 125.440186 -34.854896)
		(stroke
			(width 0.05)
			(type default)
		)
		(layer "Edge.Cuts")
	)
	(gr_arc
		(start 122.96013 -41.844976)
		(mid 124.165106 -43.049952)
		(end 125.370082 -41.844976)
		(stroke
			(width 0.05)
			(type default)
		)
		(layer "Edge.Cuts")
	)
	(gr_arc
		(start 125.370082 -41.844976)
		(mid 124.165106 -40.64)
		(end 122.96013 -41.844976)
		(stroke
			(width 0.05)
			(type default)
		)
		(layer "Edge.Cuts")
	)
	(gr_arc
		(start 125.440186 -34.854896)
		(mid 124.165106 -33.579816)
		(end 122.890026 -34.854896)
		(stroke
			(width 0.05)
			(type default)
		)
		(layer "Edge.Cuts")
	)
	(gr_line
		(start 143.299942 -47.999904)
		(end 104.70007 -47.999904)
		(stroke
			(width 0.05)
			(type default)
		)
		(layer "Edge.Cuts")
	)
	(gr_line
		(start 144.29994 -183.76392)
		(end 144.29994 -47.999904)
		(stroke
			(width 0.05)
			(type default)
		)
		(layer "Edge.Cuts")
	)
	(gr_arc
		(start 144.29994 -183.76392)
		(mid 144.326755 -183.993712)
		(end 144.405604 -184.211214)
		(stroke
			(width 0.05)
			(type default)
		)
		(layer "Edge.Cuts")
	)
	(gr_arc
		(start 144.29994 -47.999904)
		(mid 143.800068 -47.500032)
		(end 143.299942 -47.999904)
		(stroke
			(width 0.05)
			(type default)
		)
		(layer "Edge.Cuts")
	)
	(gr_line
		(start 149.023578 -193.447162)
		(end 144.405604 -184.211214)
		(stroke
			(width 0.05)
			(type default)
		)
		(layer "Edge.Cuts")
	)
	(gr_arc
		(start 149.023578 -193.447162)
		(mid 149.392225 -193.85063)
		(end 149.917912 -194.00012)
		(stroke
			(width 0.05)
			(type default)
		)
		(layer "Edge.Cuts")
	)
	(gr_arc
		(start 153.75001 -187.999878)
		(mid 155.50007 -189.749938)
		(end 157.249876 -187.999878)
		(stroke
			(width 0.05)
			(type default)
		)
		(layer "Edge.Cuts")
	)
	(gr_arc
		(start 153.75001 -110.000034)
		(mid 155.50007 -111.750094)
		(end 157.249876 -110.000034)
		(stroke
			(width 0.05)
			(type default)
		)
		(layer "Edge.Cuts")
	)
	(gr_arc
		(start 157.249876 -187.999878)
		(mid 155.50007 -186.250072)
		(end 153.75001 -187.999878)
		(stroke
			(width 0.05)
			(type default)
		)
		(layer "Edge.Cuts")
	)
	(gr_arc
		(start 157.249876 -110.000034)
		(mid 155.50007 -108.250228)
		(end 153.75001 -110.000034)
		(stroke
			(width 0.05)
			(type default)
		)
		(layer "Edge.Cuts")
	)
	(gr_arc
		(start 158.900114 -14.699996)
		(mid 160.000188 -15.80007)
		(end 161.100008 -14.699996)
		(stroke
			(width 0.05)
			(type default)
		)
		(layer "Edge.Cuts")
	)
	(gr_arc
		(start 161.100008 -14.699996)
		(mid 160.000188 -13.600176)
		(end 158.900114 -14.699996)
		(stroke
			(width 0.05)
			(type default)
		)
		(layer "Edge.Cuts")
	)
	(gr_arc
		(start 164.2999 -45.72)
		(mid 165.800024 -47.220124)
		(end 167.299894 -45.72)
		(stroke
			(width 0.05)
			(type default)
		)
		(layer "Edge.Cuts")
	)
	(gr_arc
		(start 167.299894 -45.72)
		(mid 165.800024 -44.22013)
		(end 164.2999 -45.72)
		(stroke
			(width 0.05)
			(type default)
		)
		(layer "Edge.Cuts")
	)
	(gr_arc
		(start 178.900074 -14.699996)
		(mid 180.000148 -15.80007)
		(end 181.099968 -14.699996)
		(stroke
			(width 0.05)
			(type default)
		)
		(layer "Edge.Cuts")
	)
	(gr_arc
		(start 181.099968 -14.699996)
		(mid 180.000148 -13.600176)
		(end 178.900074 -14.699996)
		(stroke
			(width 0.05)
			(type default)
		)
		(layer "Edge.Cuts")
	)
	(gr_arc
		(start 218.300046 -84.479892)
		(mid 219.80017 -85.980016)
		(end 221.30004 -84.479892)
		(stroke
			(width 0.05)
			(type default)
		)
		(layer "Edge.Cuts")
	)
	(gr_arc
		(start 220.49994 -14.99997)
		(mid 222.499936 -16.999966)
		(end 224.499932 -14.99997)
		(stroke
			(width 0.05)
			(type default)
		)
		(layer "Edge.Cuts")
	)
	(gr_arc
		(start 220.749876 -187.999878)
		(mid 222.499936 -189.749938)
		(end 224.249996 -187.999878)
		(stroke
			(width 0.05)
			(type default)
		)
		(layer "Edge.Cuts")
	)
	(gr_arc
		(start 220.749876 -110.000034)
		(mid 222.499936 -111.750094)
		(end 224.249996 -110.000034)
		(stroke
			(width 0.05)
			(type default)
		)
		(layer "Edge.Cuts")
	)
	(gr_arc
		(start 221.30004 -84.479892)
		(mid 219.80017 -82.980022)
		(end 218.300046 -84.479892)
		(stroke
			(width 0.05)
			(type default)
		)
		(layer "Edge.Cuts")
	)
	(gr_arc
		(start 224.249996 -187.999878)
		(mid 222.499936 -186.249818)
		(end 220.749876 -187.999878)
		(stroke
			(width 0.05)
			(type default)
		)
		(layer "Edge.Cuts")
	)
	(gr_arc
		(start 224.249996 -110.000034)
		(mid 222.499936 -108.249974)
		(end 220.749876 -110.000034)
		(stroke
			(width 0.05)
			(type default)
		)
		(layer "Edge.Cuts")
	)
	(gr_arc
		(start 224.499932 -14.99997)
		(mid 222.499936 -12.999974)
		(end 220.49994 -14.99997)
		(stroke
			(width 0.05)
			(type default)
		)
		(layer "Edge.Cuts")
	)
	(gr_line
		(start 229.382066 -194.00012)
		(end 149.917912 -194.00012)
		(stroke
			(width 0.05)
			(type default)
		)
		(layer "Edge.Cuts")
	)
	(gr_arc
		(start 229.382066 -194.00012)
		(mid 229.907793 -193.850701)
		(end 230.2764 -193.447162)
		(stroke
			(width 0.05)
			(type default)
		)
		(layer "Edge.Cuts")
	)
	(gr_line
		(start 234.894374 -184.211214)
		(end 230.2764 -193.447162)
		(stroke
			(width 0.05)
			(type default)
		)
		(layer "Edge.Cuts")
	)
	(gr_arc
		(start 234.894374 -184.211214)
		(mid 234.97328 -183.993726)
		(end 235.000038 -183.76392)
		(stroke
			(width 0.05)
			(type default)
		)
		(layer "Edge.Cuts")
	)
	(gr_arc
		(start 235.000038 -0.999998)
		(mid 234.707147 -0.29288)
		(end 234.00004 0)
		(stroke
			(width 0.05)
			(type default)
		)
		(layer "Edge.Cuts")
	)
	(gr_line
		(start 235.000038 -0.999998)
		(end 235.000038 -183.76392)
		(stroke
			(width 0.05)
			(type default)
		)
		(layer "Edge.Cuts")
	)
	(via
		(at 159.49422 -50.419)
		(size 0.6096)
		(drill 0.3048)
		(layers "F.Cu" "B.Cu")
		(net "BYTE_N")
	)
	(segment
		(start 159.49422 -49.73828)
		(end 159.49422 -50.419)
		(width 0.127)
		(layer "B.Cu")
		(net "BYTE_N")
	)
	(segment
		(start 159.49422 -50.419)
		(end 159.49422 -53.6575)
		(width 0.127)
		(layer "B.Cu")
		(net "BYTE_N")
	)
	(segment
		(start 159.893 -49.3395)
		(end 159.49422 -49.73828)
		(width 0.127)
		(layer "B.Cu")
		(net "BYTE_N")
	)
	(segment
		(start 161.036 -49.3395)
		(end 159.893 -49.3395)
		(width 0.127)
		(layer "B.Cu")
		(net "BYTE_N")
	)
	(segment
		(start 50.500026 -137.40003)
		(end 50.099976 -137.80008)
		(width 0.127)
		(layer "F.Cu")
		(net "TP_M2_2_ALERT#")
	)
	(via
		(at 50.099976 -137.80008)
		(size 0.4572)
		(drill 0.2032)
		(layers "F.Cu" "B.Cu")
		(net "TP_M2_2_ALERT#")
	)
	(segment
		(start 45.2374 -139.3698)
		(end 45.600366 -139.006834)
		(width 0.127)
		(layer "B.Cu")
		(net "TP_M2_2_ALERT#")
	)
	(segment
		(start 45.600366 -139.006834)
		(end 47.378366 -139.006834)
		(width 0.127)
		(layer "B.Cu")
		(net "TP_M2_2_ALERT#")
	)
	(segment
		(start 47.378366 -139.006834)
		(end 48.191674 -138.193526)
		(width 0.127)
		(layer "B.Cu")
		(net "TP_M2_2_ALERT#")
	)
	(segment
		(start 49.791874 -138.193526)
		(end 50.099976 -137.885424)
		(width 0.127)
		(layer "B.Cu")
		(net "TP_M2_2_ALERT#")
	)
	(segment
		(start 50.099976 -137.885424)
		(end 50.099976 -137.80008)
		(width 0.127)
		(layer "B.Cu")
		(net "TP_M2_2_ALERT#")
	)
	(segment
		(start 48.191674 -138.193526)
		(end 49.791874 -138.193526)
		(width 0.127)
		(layer "B.Cu")
		(net "TP_M2_2_ALERT#")
	)
	(segment
		(start 49.699926 -138.199876)
		(end 49.299876 -138.599926)
		(width 0.127)
		(layer "F.Cu")
		(net "TP_M2_1_ALERT#")
	)
	(via
		(at 49.299876 -138.599926)
		(size 0.4572)
		(drill 0.2032)
		(layers "F.Cu" "B.Cu")
		(net "TP_M2_1_ALERT#")
	)
	(segment
		(start 48.936402 -138.9634)
		(end 49.299876 -138.599926)
		(width 0.127)
		(layer "B.Cu")
		(net "TP_M2_1_ALERT#")
	)
	(segment
		(start 48.387 -138.9634)
		(end 48.936402 -138.9634)
		(width 0.127)
		(layer "B.Cu")
		(net "TP_M2_1_ALERT#")
	)
	(segment
		(start 213.68258 -15.5702)
		(end 213.6902 -15.57782)
		(width 0.127)
		(layer "F.Cu")
		(net "BMC_ML_PWR_BLUE_LED_L")
	)
	(segment
		(start 208.462118 -15.5702)
		(end 207.776318 -14.8844)
		(width 0.127)
		(layer "F.Cu")
		(net "BMC_ML_PWR_BLUE_LED_L")
	)
	(segment
		(start 206.248 -13.7414)
		(end 206.463392 -13.526008)
		(width 0.127)
		(layer "F.Cu")
		(net "BMC_ML_PWR_BLUE_LED_L")
	)
	(segment
		(start 206.248 -14.5288)
		(end 206.248 -13.7414)
		(width 0.127)
		(layer "F.Cu")
		(net "BMC_ML_PWR_BLUE_LED_L")
	)
	(segment
		(start 206.6036 -14.8844)
		(end 206.248 -14.5288)
		(width 0.127)
		(layer "F.Cu")
		(net "BMC_ML_PWR_BLUE_LED_L")
	)
	(segment
		(start 207.776318 -14.8844)
		(end 206.6036 -14.8844)
		(width 0.127)
		(layer "F.Cu")
		(net "BMC_ML_PWR_BLUE_LED_L")
	)
	(segment
		(start 206.463392 -13.526008)
		(end 207.029304 -13.526008)
		(width 0.127)
		(layer "F.Cu")
		(net "BMC_ML_PWR_BLUE_LED_L")
	)
	(segment
		(start 212.4456 -15.5702)
		(end 213.68258 -15.5702)
		(width 0.127)
		(layer "F.Cu")
		(net "BMC_ML_PWR_BLUE_LED_L")
	)
	(segment
		(start 210.81238 -15.5702)
		(end 208.462118 -15.5702)
		(width 0.127)
		(layer "F.Cu")
		(net "BMC_ML_PWR_BLUE_LED_L")
	)
	(segment
		(start 210.81238 -15.5702)
		(end 212.4456 -15.5702)
		(width 0.127)
		(layer "F.Cu")
		(net "BMC_ML_PWR_BLUE_LED_L")
	)
	(via
		(at 212.4456 -15.5702)
		(size 0.6604)
		(drill 0.3302)
		(layers "F.Cu" "B.Cu")
		(net "BMC_ML_PWR_BLUE_LED_L")
	)
	(segment
		(start 189.12332 -114.9858)
		(end 189.12332 -115.7732)
		(width 0.508)
		(layer "F.Cu")
		(net "N62640349")
	)
	(segment
		(start 189.12332 -115.7732)
		(end 188.6458 -116.25072)
		(width 0.508)
		(layer "F.Cu")
		(net "N62640349")
	)
	(segment
		(start 89.53246 -131.040632)
		(end 89.53246 -131.03606)
		(width 0.127)
		(layer "F.Cu")
		(net "UART_SEL_MUX")
	)
	(segment
		(start 89.232994 -127.929894)
		(end 89.2175 -127.9144)
		(width 0.127)
		(layer "F.Cu")
		(net "UART_SEL_MUX")
	)
	(segment
		(start 79.395828 -135.980424)
		(end 79.396082 -135.980678)
		(width 0.127)
		(layer "F.Cu")
		(net "UART_SEL_MUX")
	)
	(segment
		(start 89.2175 -127.9144)
		(end 89.2175 -127.624332)
		(width 0.127)
		(layer "F.Cu")
		(net "UART_SEL_MUX")
	)
	(segment
		(start 78.814168 -135.160512)
		(end 78.359254 -135.615426)
		(width 0.127)
		(layer "F.Cu")
		(net "UART_SEL_MUX")
	)
	(segment
		(start 91.805506 -128.507236)
		(end 92.693236 -128.507236)
		(width 0.127)
		(layer "F.Cu")
		(net "UART_SEL_MUX")
	)
	(segment
		(start 90.671904 -131.0894)
		(end 89.5858 -131.0894)
		(width 0.127)
		(layer "F.Cu")
		(net "UART_SEL_MUX")
	)
	(segment
		(start 89.232994 -128.989074)
		(end 89.232994 -127.929894)
		(width 0.127)
		(layer "F.Cu")
		(net "UART_SEL_MUX")
	)
	(segment
		(start 89.2175 -130.0226)
		(end 89.2175 -129.004568)
		(width 0.127)
		(layer "F.Cu")
		(net "UART_SEL_MUX")
	)
	(segment
		(start 89.5858 -131.0894)
		(end 89.537032 -131.040632)
		(width 0.127)
		(layer "F.Cu")
		(net "UART_SEL_MUX")
	)
	(segment
		(start 89.53246 -131.03606)
		(end 89.2175 -130.7211)
		(width 0.127)
		(layer "F.Cu")
		(net "UART_SEL_MUX")
	)
	(segment
		(start 92.693236 -128.507236)
		(end 92.8624 -128.6764)
		(width 0.127)
		(layer "F.Cu")
		(net "UART_SEL_MUX")
	)
	(segment
		(start 92.8624 -128.6764)
		(end 92.8624 -130.2258)
		(width 0.127)
		(layer "F.Cu")
		(net "UART_SEL_MUX")
	)
	(segment
		(start 91.255088 -130.506216)
		(end 90.671904 -131.0894)
		(width 0.127)
		(layer "F.Cu")
		(net "UART_SEL_MUX")
	)
	(segment
		(start 89.2175 -127.624332)
		(end 88.668352 -127.075184)
		(width 0.127)
		(layer "F.Cu")
		(net "UART_SEL_MUX")
	)
	(segment
		(start 78.359254 -135.980424)
		(end 79.395828 -135.980424)
		(width 0.127)
		(layer "F.Cu")
		(net "UART_SEL_MUX")
	)
	(segment
		(start 89.2175 -129.004568)
		(end 89.232994 -128.989074)
		(width 0.127)
		(layer "F.Cu")
		(net "UART_SEL_MUX")
	)
	(segment
		(start 92.581984 -130.506216)
		(end 91.805506 -130.506216)
		(width 0.127)
		(layer "F.Cu")
		(net "UART_SEL_MUX")
	)
	(segment
		(start 78.359254 -135.615426)
		(end 78.359254 -135.980424)
		(width 0.127)
		(layer "F.Cu")
		(net "UART_SEL_MUX")
	)
	(segment
		(start 89.537032 -131.040632)
		(end 89.53246 -131.040632)
		(width 0.127)
		(layer "F.Cu")
		(net "UART_SEL_MUX")
	)
	(segment
		(start 92.8624 -130.2258)
		(end 92.581984 -130.506216)
		(width 0.127)
		(layer "F.Cu")
		(net "UART_SEL_MUX")
	)
	(segment
		(start 91.805506 -130.506216)
		(end 91.255088 -130.506216)
		(width 0.127)
		(layer "F.Cu")
		(net "UART_SEL_MUX")
	)
	(segment
		(start 89.2175 -130.7211)
		(end 89.2175 -130.0226)
		(width 0.127)
		(layer "F.Cu")
		(net "UART_SEL_MUX")
	)
	(via
		(at 78.814168 -135.160512)
		(size 0.508)
		(drill 0.254)
		(layers "F.Cu" "B.Cu")
		(net "UART_SEL_MUX")
	)
	(via
		(at 88.668352 -127.075184)
		(size 0.508)
		(drill 0.254)
		(layers "F.Cu" "B.Cu")
		(net "UART_SEL_MUX")
	)
	(via
		(at 89.53246 -131.040632)
		(size 0.6604)
		(drill 0.3302)
		(layers "F.Cu" "B.Cu")
		(net "UART_SEL_MUX")
	)
	(segment
		(start 83.928966 -133.720332)
		(end 81.862422 -133.720332)
		(width 0.127)
		(layer "B.Cu")
		(net "UART_SEL_MUX")
	)
	(segment
		(start 88.490044 -127.075184)
		(end 87.79256 -126.3777)
		(width 0.127)
		(layer "B.Cu")
		(net "UART_SEL_MUX")
	)
	(segment
		(start 87.21344 -126.3777)
		(end 86.8045 -126.78664)
		(width 0.127)
		(layer "B.Cu")
		(net "UART_SEL_MUX")
	)
	(segment
		(start 81.862422 -133.720332)
		(end 80.422242 -135.160512)
		(width 0.127)
		(layer "B.Cu")
		(net "UART_SEL_MUX")
	)
	(segment
		(start 86.8045 -126.78664)
		(end 86.8045 -128.588516)
		(width 0.127)
		(layer "B.Cu")
		(net "UART_SEL_MUX")
	)
	(segment
		(start 80.422242 -135.160512)
		(end 78.814168 -135.160512)
		(width 0.127)
		(layer "B.Cu")
		(net "UART_SEL_MUX")
	)
	(segment
		(start 87.0839 -130.565398)
		(end 83.928966 -133.720332)
		(width 0.127)
		(layer "B.Cu")
		(net "UART_SEL_MUX")
	)
	(segment
		(start 86.8045 -128.588516)
		(end 87.0839 -128.867916)
		(width 0.127)
		(layer "B.Cu")
		(net "UART_SEL_MUX")
	)
	(segment
		(start 88.668352 -127.075184)
		(end 88.490044 -127.075184)
		(width 0.127)
		(layer "B.Cu")
		(net "UART_SEL_MUX")
	)
	(segment
		(start 87.0839 -128.867916)
		(end 87.0839 -130.565398)
		(width 0.127)
		(layer "B.Cu")
		(net "UART_SEL_MUX")
	)
	(segment
		(start 87.79256 -126.3777)
		(end 87.21344 -126.3777)
		(width 0.127)
		(layer "B.Cu")
		(net "UART_SEL_MUX")
	)
	(segment
		(start 160.089088 -93.20276)
		(end 159.627316 -92.740988)
		(width 0.254)
		(layer "F.Cu")
		(net "U43_VREF2")
	)
	(segment
		(start 159.110172 -90.230452)
		(end 158.977076 -90.363548)
		(width 0.254)
		(layer "F.Cu")
		(net "U43_VREF2")
	)
	(segment
		(start 159.627316 -92.740988)
		(end 159.627316 -91.5924)
		(width 0.254)
		(layer "F.Cu")
		(net "U43_VREF2")
	)
	(segment
		(start 159.070548 -95.542608)
		(end 159.070548 -95.89516)
		(width 0.254)
		(layer "F.Cu")
		(net "U43_VREF2")
	)
	(segment
		(start 159.469328 -90.230452)
		(end 159.110172 -90.230452)
		(width 0.254)
		(layer "F.Cu")
		(net "U43_VREF2")
	)
	(segment
		(start 159.262826 -96.416114)
		(end 160.089088 -96.416114)
		(width 0.254)
		(layer "F.Cu")
		(net "U43_VREF2")
	)
	(segment
		(start 160.089088 -95.32747)
		(end 159.285686 -95.32747)
		(width 0.254)
		(layer "F.Cu")
		(net "U43_VREF2")
	)
	(segment
		(start 158.977076 -90.363548)
		(end 158.977076 -91.5924)
		(width 0.254)
		(layer "F.Cu")
		(net "U43_VREF2")
	)
	(segment
		(start 160.089088 -93.504512)
		(end 160.089088 -95.32747)
		(width 0.254)
		(layer "F.Cu")
		(net "U43_VREF2")
	)
	(segment
		(start 159.070548 -96.223836)
		(end 159.262826 -96.416114)
		(width 0.254)
		(layer "F.Cu")
		(net "U43_VREF2")
	)
	(segment
		(start 159.627316 -91.5924)
		(end 159.627316 -90.38844)
		(width 0.254)
		(layer "F.Cu")
		(net "U43_VREF2")
	)
	(segment
		(start 160.089088 -93.504512)
		(end 160.089088 -93.20276)
		(width 0.254)
		(layer "F.Cu")
		(net "U43_VREF2")
	)
	(segment
		(start 159.627316 -90.38844)
		(end 159.469328 -90.230452)
		(width 0.254)
		(layer "F.Cu")
		(net "U43_VREF2")
	)
	(segment
		(start 159.070548 -95.89516)
		(end 159.070548 -96.223836)
		(width 0.254)
		(layer "F.Cu")
		(net "U43_VREF2")
	)
	(segment
		(start 159.285686 -95.32747)
		(end 159.070548 -95.542608)
		(width 0.254)
		(layer "F.Cu")
		(net "U43_VREF2")
	)
	(via
		(at 159.070548 -95.89516)
		(size 0.6604)
		(drill 0.3302)
		(layers "F.Cu" "B.Cu")
		(net "U43_VREF2")
	)
	(segment
		(start 59.186318 -140.29563)
		(end 56.937148 -142.5448)
		(width 0.127)
		(layer "F.Cu")
		(net "TP_BMC_GPIOA0")
	)
	(segment
		(start 56.937148 -142.5448)
		(end 55.755032 -142.5448)
		(width 0.127)
		(layer "F.Cu")
		(net "TP_BMC_GPIOA0")
	)
	(segment
		(start 55.755032 -142.5448)
		(end 55.299864 -142.999968)
		(width 0.127)
		(layer "F.Cu")
		(net "TP_BMC_GPIOA0")
	)
	(segment
		(start 59.191144 -139.939268)
		(end 59.186318 -139.944094)
		(width 0.127)
		(layer "F.Cu")
		(net "TP_BMC_GPIOA0")
	)
	(segment
		(start 59.186318 -139.944094)
		(end 59.186318 -140.29563)
		(width 0.127)
		(layer "F.Cu")
		(net "TP_BMC_GPIOA0")
	)
	(via
		(at 59.191144 -139.939268)
		(size 0.508)
		(drill 0.254)
		(layers "F.Cu" "B.Cu")
		(net "TP_BMC_GPIOA0")
	)
	(via
		(at 59.886088 -137.749534)
		(size 0.6096)
		(drill 0.3048)
		(layers "F.Cu" "B.Cu")
		(net "TP_BMC_GPIOA0")
	)
	(segment
		(start 60.9981 -136.906)
		(end 60.729622 -136.906)
		(width 0.127)
		(layer "B.Cu")
		(net "TP_BMC_GPIOA0")
	)
	(segment
		(start 60.9981 -136.906)
		(end 60.9981 -137.4394)
		(width 0.127)
		(layer "B.Cu")
		(net "TP_BMC_GPIOA0")
	)
	(segment
		(start 60.729622 -136.906)
		(end 59.886088 -137.749534)
		(width 0.127)
		(layer "B.Cu")
		(net "TP_BMC_GPIOA0")
	)
	(segment
		(start 59.886088 -137.749534)
		(end 59.4868 -138.148822)
		(width 0.127)
		(layer "B.Cu")
		(net "TP_BMC_GPIOA0")
	)
	(segment
		(start 60.9981 -137.4394)
		(end 61.5061 -137.9474)
		(width 0.127)
		(layer "B.Cu")
		(net "TP_BMC_GPIOA0")
	)
	(segment
		(start 59.4868 -138.148822)
		(end 59.4868 -139.091416)
		(width 0.127)
		(layer "B.Cu")
		(net "TP_BMC_GPIOA0")
	)
	(segment
		(start 59.4868 -139.091416)
		(end 59.191144 -139.387072)
		(width 0.127)
		(layer "B.Cu")
		(net "TP_BMC_GPIOA0")
	)
	(segment
		(start 59.191144 -139.387072)
		(end 59.191144 -139.939268)
		(width 0.127)
		(layer "B.Cu")
		(net "TP_BMC_GPIOA0")
	)
	(segment
		(start 40.099996 -137.40003)
		(end 39.7002 -137.000234)
		(width 0.127)
		(layer "F.Cu")
		(net "PLTRST_R")
	)
	(via
		(at 39.7002 -137.000234)
		(size 0.4572)
		(drill 0.2032)
		(layers "F.Cu" "B.Cu")
		(net "PLTRST_R")
	)
	(via
		(at 48.413162 -131.960874)
		(size 0.6096)
		(drill 0.3048)
		(layers "F.Cu" "B.Cu")
		(net "PLTRST_R")
	)
	(via
		(at 48.69815 -132.860796)
		(size 0.508)
		(drill 0.254)
		(layers "F.Cu" "B.Cu")
		(net "PLTRST_R")
	)
	(segment
		(start 48.69815 -132.860796)
		(end 48.69815 -132.245862)
		(width 0.127)
		(layer "B.Cu")
		(net "PLTRST_R")
	)
	(segment
		(start 48.413162 -131.960874)
		(end 47.449994 -131.960874)
		(width 0.127)
		(layer "B.Cu")
		(net "PLTRST_R")
	)
	(segment
		(start 48.69815 -132.245862)
		(end 48.413162 -131.960874)
		(width 0.127)
		(layer "B.Cu")
		(net "PLTRST_R")
	)
	(segment
		(start 47.449994 -131.960874)
		(end 47.272194 -132.138674)
		(width 0.127)
		(layer "B.Cu")
		(net "PLTRST_R")
	)
	(segment
		(start 41.706546 -139.236704)
		(end 41.706546 -140.036296)
		(width 0.127)
		(layer "In2.Cu")
		(net "PLTRST_R")
	)
	(segment
		(start 39.7002 -137.000234)
		(end 40.106346 -137.40638)
		(width 0.127)
		(layer "In2.Cu")
		(net "PLTRST_R")
	)
	(segment
		(start 41.937178 -140.59408)
		(end 46.382178 -140.59408)
		(width 0.127)
		(layer "In2.Cu")
		(net "PLTRST_R")
	)
	(segment
		(start 47.990252 -134.71398)
		(end 47.990252 -133.30555)
		(width 0.127)
		(layer "In2.Cu")
		(net "PLTRST_R")
	)
	(segment
		(start 41.706546 -140.036296)
		(end 41.706292 -140.03655)
		(width 0.127)
		(layer "In2.Cu")
		(net "PLTRST_R")
	)
	(segment
		(start 47.990252 -133.30555)
		(end 48.360838 -132.934964)
		(width 0.127)
		(layer "In2.Cu")
		(net "PLTRST_R")
	)
	(segment
		(start 40.106346 -138.763756)
		(end 40.336724 -138.994134)
		(width 0.127)
		(layer "In2.Cu")
		(net "PLTRST_R")
	)
	(segment
		(start 48.623982 -132.934964)
		(end 48.69815 -132.860796)
		(width 0.127)
		(layer "In2.Cu")
		(net "PLTRST_R")
	)
	(segment
		(start 46.382178 -140.59408)
		(end 47.460154 -139.516104)
		(width 0.127)
		(layer "In2.Cu")
		(net "PLTRST_R")
	)
	(segment
		(start 40.336724 -138.994134)
		(end 41.463976 -138.994134)
		(width 0.127)
		(layer "In2.Cu")
		(net "PLTRST_R")
	)
	(segment
		(start 48.360838 -132.934964)
		(end 48.623982 -132.934964)
		(width 0.127)
		(layer "In2.Cu")
		(net "PLTRST_R")
	)
	(segment
		(start 47.460154 -139.516104)
		(end 47.460154 -135.244078)
		(width 0.127)
		(layer "In2.Cu")
		(net "PLTRST_R")
	)
	(segment
		(start 41.706292 -140.363194)
		(end 41.937178 -140.59408)
		(width 0.127)
		(layer "In2.Cu")
		(net "PLTRST_R")
	)
	(segment
		(start 41.706292 -140.03655)
		(end 41.706292 -140.363194)
		(width 0.127)
		(layer "In2.Cu")
		(net "PLTRST_R")
	)
	(segment
		(start 47.460154 -135.244078)
		(end 47.990252 -134.71398)
		(width 0.127)
		(layer "In2.Cu")
		(net "PLTRST_R")
	)
	(segment
		(start 41.463976 -138.994134)
		(end 41.706546 -139.236704)
		(width 0.127)
		(layer "In2.Cu")
		(net "PLTRST_R")
	)
	(segment
		(start 40.106346 -137.40638)
		(end 40.106346 -138.763756)
		(width 0.127)
		(layer "In2.Cu")
		(net "PLTRST_R")
	)
	(segment
		(start 208.540096 -6.199886)
		(end 208.540096 -10.668)
		(width 0.254)
		(layer "F.Cu")
		(net "ML_PWR_YELLOW_LED_R")
	)
	(segment
		(start 210.064096 -11.550904)
		(end 209.3468 -12.2682)
		(width 0.254)
		(layer "F.Cu")
		(net "ML_PWR_YELLOW_LED")
	)
	(segment
		(start 210.064096 -10.668)
		(end 210.064096 -11.550904)
		(width 0.254)
		(layer "F.Cu")
		(net "ML_PWR_YELLOW_LED")
	)
	(segment
		(start 207.438752 -14.176248)
		(end 209.3468 -12.2682)
		(width 0.254)
		(layer "F.Cu")
		(net "ML_PWR_YELLOW_LED")
	)
	(segment
		(start 207.029304 -14.176248)
		(end 207.438752 -14.176248)
		(width 0.254)
		(layer "F.Cu")
		(net "ML_PWR_YELLOW_LED")
	)
	(via
		(at 209.3468 -12.2682)
		(size 0.6604)
		(drill 0.3302)
		(layers "F.Cu" "B.Cu")
		(net "ML_PWR_YELLOW_LED")
	)
	(segment
		(start 203.460096 -6.199886)
		(end 203.460096 -10.668)
		(width 0.254)
		(layer "F.Cu")
		(net "ML_PWR_BLUE_LED_R")
	)
	(segment
		(start 203.121768 -12.875768)
		(end 202.565 -12.319)
		(width 0.254)
		(layer "F.Cu")
		(net "ML_PWR_BLUE_LED")
	)
	(segment
		(start 202.565 -12.319)
		(end 201.936096 -11.690096)
		(width 0.254)
		(layer "F.Cu")
		(net "ML_PWR_BLUE_LED")
	)
	(segment
		(start 204.979524 -12.875768)
		(end 203.121768 -12.875768)
		(width 0.254)
		(layer "F.Cu")
		(net "ML_PWR_BLUE_LED")
	)
	(segment
		(start 201.936096 -11.690096)
		(end 201.936096 -10.668)
		(width 0.254)
		(layer "F.Cu")
		(net "ML_PWR_BLUE_LED")
	)
	(via
		(at 202.565 -12.319)
		(size 0.6604)
		(drill 0.3302)
		(layers "F.Cu" "B.Cu")
		(net "ML_PWR_BLUE_LED")
	)
	(segment
		(start 76.508864 -135.891016)
		(end 76.980542 -135.891016)
		(width 0.127)
		(layer "F.Cu")
		(net "D_FLIP_Q#")
	)
	(segment
		(start 77.06995 -135.980424)
		(end 77.470254 -135.980424)
		(width 0.127)
		(layer "F.Cu")
		(net "D_FLIP_Q#")
	)
	(segment
		(start 76.508864 -135.891016)
		(end 75.48245 -135.891016)
		(width 0.127)
		(layer "F.Cu")
		(net "D_FLIP_Q#")
	)
	(segment
		(start 77.737208 -137.76579)
		(end 76.95819 -137.76579)
		(width 0.127)
		(layer "F.Cu")
		(net "D_FLIP_Q#")
	)
	(segment
		(start 76.217272 -136.625838)
		(end 75.48245 -135.891016)
		(width 0.127)
		(layer "F.Cu")
		(net "D_FLIP_Q#")
	)
	(segment
		(start 76.980542 -135.891016)
		(end 77.06995 -135.980424)
		(width 0.127)
		(layer "F.Cu")
		(net "D_FLIP_Q#")
	)
	(segment
		(start 76.217272 -137.024872)
		(end 76.217272 -136.625838)
		(width 0.127)
		(layer "F.Cu")
		(net "D_FLIP_Q#")
	)
	(segment
		(start 76.95819 -137.76579)
		(end 76.217272 -137.024872)
		(width 0.127)
		(layer "F.Cu")
		(net "D_FLIP_Q#")
	)
	(via
		(at 76.508864 -135.891016)
		(size 0.6604)
		(drill 0.3302)
		(layers "F.Cu" "B.Cu")
		(net "D_FLIP_Q#")
	)
	(segment
		(start 81.287874 -136.058402)
		(end 81.562956 -136.333484)
		(width 0.127)
		(layer "F.Cu")
		(net "D_FLIP_Q")
	)
	(segment
		(start 81.562956 -136.333484)
		(end 81.562956 -136.867392)
		(width 0.127)
		(layer "F.Cu")
		(net "D_FLIP_Q")
	)
	(segment
		(start 80.285082 -135.980678)
		(end 81.21015 -135.980678)
		(width 0.127)
		(layer "F.Cu")
		(net "D_FLIP_Q")
	)
	(segment
		(start 81.562956 -136.867392)
		(end 81.164938 -137.26541)
		(width 0.127)
		(layer "F.Cu")
		(net "D_FLIP_Q")
	)
	(segment
		(start 81.21015 -135.980678)
		(end 81.287874 -136.058402)
		(width 0.127)
		(layer "F.Cu")
		(net "D_FLIP_Q")
	)
	(segment
		(start 81.164938 -137.26541)
		(end 80.074008 -137.26541)
		(width 0.127)
		(layer "F.Cu")
		(net "D_FLIP_Q")
	)
	(via
		(at 81.287874 -136.058402)
		(size 0.6604)
		(drill 0.3302)
		(layers "F.Cu" "B.Cu")
		(net "D_FLIP_Q")
	)
	(segment
		(start 82.734658 -138.26617)
		(end 81.917794 -138.26617)
		(width 0.127)
		(layer "F.Cu")
		(net "D_FLIP_PRE#")
	)
	(segment
		(start 82.871564 -138.129264)
		(end 82.734658 -138.26617)
		(width 0.127)
		(layer "F.Cu")
		(net "D_FLIP_PRE#")
	)
	(segment
		(start 81.917794 -138.26617)
		(end 80.074008 -138.26617)
		(width 0.127)
		(layer "F.Cu")
		(net "D_FLIP_PRE#")
	)
	(via
		(at 81.917794 -138.26617)
		(size 0.6604)
		(drill 0.3302)
		(layers "F.Cu" "B.Cu")
		(net "D_FLIP_PRE#")
	)
	(segment
		(start 75.48245 -136.780016)
		(end 75.48245 -137.350246)
		(width 0.127)
		(layer "F.Cu")
		(net "D_FLIP_D")
	)
	(segment
		(start 76.919582 -138.26617)
		(end 77.737208 -138.26617)
		(width 0.127)
		(layer "F.Cu")
		(net "D_FLIP_D")
	)
	(segment
		(start 76.020676 -137.888472)
		(end 76.183998 -138.051794)
		(width 0.127)
		(layer "F.Cu")
		(net "D_FLIP_D")
	)
	(segment
		(start 76.705206 -138.051794)
		(end 76.919582 -138.26617)
		(width 0.127)
		(layer "F.Cu")
		(net "D_FLIP_D")
	)
	(segment
		(start 76.183998 -138.051794)
		(end 76.705206 -138.051794)
		(width 0.127)
		(layer "F.Cu")
		(net "D_FLIP_D")
	)
	(segment
		(start 75.48245 -137.350246)
		(end 76.020676 -137.888472)
		(width 0.127)
		(layer "F.Cu")
		(net "D_FLIP_D")
	)
	(via
		(at 76.020676 -137.888472)
		(size 0.6604)
		(drill 0.3302)
		(layers "F.Cu" "B.Cu")
		(net "D_FLIP_D")
	)
	(segment
		(start 82.284824 -137.062464)
		(end 81.93405 -137.062464)
		(width 0.127)
		(layer "F.Cu")
		(net "D_FLIP_CLR#")
	)
	(segment
		(start 81.93405 -137.062464)
		(end 81.230724 -137.76579)
		(width 0.127)
		(layer "F.Cu")
		(net "D_FLIP_CLR#")
	)
	(segment
		(start 84.43341 -137.060686)
		(end 83.479386 -137.060686)
		(width 0.127)
		(layer "F.Cu")
		(net "D_FLIP_CLR#")
	)
	(segment
		(start 83.479386 -137.060686)
		(end 82.286602 -137.060686)
		(width 0.127)
		(layer "F.Cu")
		(net "D_FLIP_CLR#")
	)
	(segment
		(start 82.286602 -137.060686)
		(end 82.284824 -137.062464)
		(width 0.127)
		(layer "F.Cu")
		(net "D_FLIP_CLR#")
	)
	(segment
		(start 81.230724 -137.76579)
		(end 80.074008 -137.76579)
		(width 0.127)
		(layer "F.Cu")
		(net "D_FLIP_CLR#")
	)
	(via
		(at 82.284824 -137.062464)
		(size 0.6604)
		(drill 0.3302)
		(layers "F.Cu" "B.Cu")
		(net "D_FLIP_CLR#")
	)
	(segment
		(start 78.591918 -149.733)
		(end 79.801974 -149.733)
		(width 0.127)
		(layer "F.Cu")
		(net "COMP_TO_BMC_RESET_R")
	)
	(segment
		(start 79.801974 -149.733)
		(end 81.4705 -149.733)
		(width 0.127)
		(layer "F.Cu")
		(net "COMP_TO_BMC_RESET_R")
	)
	(segment
		(start 78.591918 -149.733)
		(end 77.4573 -149.733)
		(width 0.127)
		(layer "F.Cu")
		(net "COMP_TO_BMC_RESET_R")
	)
	(segment
		(start 77.4573 -149.733)
		(end 77.2922 -149.8981)
		(width 0.127)
		(layer "F.Cu")
		(net "COMP_TO_BMC_RESET_R")
	)
	(via
		(at 78.591918 -149.733)
		(size 0.6604)
		(drill 0.3302)
		(layers "F.Cu" "B.Cu")
		(net "COMP_TO_BMC_RESET_R")
	)
	(segment
		(start 78.156562 -150.7871)
		(end 78.2828 -150.660862)
		(width 0.127)
		(layer "F.Cu")
		(net "COMP_TO_BMC_RESET")
	)
	(segment
		(start 77.2922 -150.7871)
		(end 78.156562 -150.7871)
		(width 0.127)
		(layer "F.Cu")
		(net "COMP_TO_BMC_RESET")
	)
	(via
		(at 78.2828 -150.660862)
		(size 0.508)
		(drill 0.254)
		(layers "F.Cu" "B.Cu")
		(net "COMP_TO_BMC_RESET")
	)
	(via
		(at 100.053648 -146.99107)
		(size 0.508)
		(drill 0.254)
		(layers "F.Cu" "B.Cu")
		(net "COMP_TO_BMC_RESET")
	)
	(segment
		(start 100.388166 -128.306068)
		(end 100.388166 -140.477494)
		(width 0.127)
		(layer "In2.Cu")
		(net "COMP_TO_BMC_RESET")
	)
	(segment
		(start 99.579938 -146.51736)
		(end 100.053648 -146.99107)
		(width 0.127)
		(layer "In2.Cu")
		(net "COMP_TO_BMC_RESET")
	)
	(segment
		(start 100.566474 -113.052606)
		(end 100.566474 -123.48083)
		(width 0.127)
		(layer "In2.Cu")
		(net "COMP_TO_BMC_RESET")
	)
	(segment
		(start 106.985054 -30.328616)
		(end 105.3338 -31.97987)
		(width 0.127)
		(layer "In2.Cu")
		(net "COMP_TO_BMC_RESET")
	)
	(segment
		(start 100.388166 -140.477494)
		(end 100.057458 -140.808202)
		(width 0.127)
		(layer "In2.Cu")
		(net "COMP_TO_BMC_RESET")
	)
	(segment
		(start 100.566474 -123.48083)
		(end 100.007166 -124.040138)
		(width 0.127)
		(layer "In2.Cu")
		(net "COMP_TO_BMC_RESET")
	)
	(segment
		(start 111.333026 -31.924752)
		(end 109.73689 -30.328616)
		(width 0.127)
		(layer "In2.Cu")
		(net "COMP_TO_BMC_RESET")
	)
	(segment
		(start 100.007166 -124.040138)
		(end 100.007166 -127.925068)
		(width 0.127)
		(layer "In2.Cu")
		(net "COMP_TO_BMC_RESET")
	)
	(segment
		(start 100.120958 -46.378622)
		(end 100.120958 -84.17814)
		(width 0.127)
		(layer "In2.Cu")
		(net "COMP_TO_BMC_RESET")
	)
	(segment
		(start 112.499902 -44.200064)
		(end 111.333026 -43.033188)
		(width 0.127)
		(layer "In2.Cu")
		(net "COMP_TO_BMC_RESET")
	)
	(segment
		(start 99.579938 -143.743172)
		(end 99.579938 -146.51736)
		(width 0.127)
		(layer "In2.Cu")
		(net "COMP_TO_BMC_RESET")
	)
	(segment
		(start 100.007166 -127.925068)
		(end 100.388166 -128.306068)
		(width 0.127)
		(layer "In2.Cu")
		(net "COMP_TO_BMC_RESET")
	)
	(segment
		(start 99.774502 -112.260634)
		(end 100.566474 -113.052606)
		(width 0.127)
		(layer "In2.Cu")
		(net "COMP_TO_BMC_RESET")
	)
	(segment
		(start 111.333026 -43.033188)
		(end 111.333026 -31.924752)
		(width 0.127)
		(layer "In2.Cu")
		(net "COMP_TO_BMC_RESET")
	)
	(segment
		(start 109.73689 -30.328616)
		(end 106.985054 -30.328616)
		(width 0.127)
		(layer "In2.Cu")
		(net "COMP_TO_BMC_RESET")
	)
	(segment
		(start 100.120958 -84.17814)
		(end 99.774502 -84.524596)
		(width 0.127)
		(layer "In2.Cu")
		(net "COMP_TO_BMC_RESET")
	)
	(segment
		(start 105.3338 -31.97987)
		(end 105.3338 -41.16578)
		(width 0.127)
		(layer "In2.Cu")
		(net "COMP_TO_BMC_RESET")
	)
	(segment
		(start 99.774502 -84.524596)
		(end 99.774502 -112.260634)
		(width 0.127)
		(layer "In2.Cu")
		(net "COMP_TO_BMC_RESET")
	)
	(segment
		(start 100.057458 -140.808202)
		(end 100.057458 -143.265652)
		(width 0.127)
		(layer "In2.Cu")
		(net "COMP_TO_BMC_RESET")
	)
	(segment
		(start 100.057458 -143.265652)
		(end 99.579938 -143.743172)
		(width 0.127)
		(layer "In2.Cu")
		(net "COMP_TO_BMC_RESET")
	)
	(segment
		(start 105.3338 -41.16578)
		(end 100.120958 -46.378622)
		(width 0.127)
		(layer "In2.Cu")
		(net "COMP_TO_BMC_RESET")
	)
	(segment
		(start 91.294966 -147.597622)
		(end 91.294966 -147.54352)
		(width 0.127)
		(layer "In5.Cu")
		(net "COMP_TO_BMC_RESET")
	)
	(segment
		(start 88.276938 -148.276056)
		(end 88.666574 -148.276056)
		(width 0.127)
		(layer "In5.Cu")
		(net "COMP_TO_BMC_RESET")
	)
	(segment
		(start 88.790018 -148.3995)
		(end 90.493088 -148.3995)
		(width 0.127)
		(layer "In5.Cu")
		(net "COMP_TO_BMC_RESET")
	)
	(segment
		(start 90.493088 -148.3995)
		(end 91.294966 -147.597622)
		(width 0.127)
		(layer "In5.Cu")
		(net "COMP_TO_BMC_RESET")
	)
	(segment
		(start 78.2828 -150.660862)
		(end 78.2828 -150.500842)
		(width 0.127)
		(layer "In5.Cu")
		(net "COMP_TO_BMC_RESET")
	)
	(segment
		(start 91.294966 -147.54352)
		(end 91.570048 -147.268438)
		(width 0.127)
		(layer "In5.Cu")
		(net "COMP_TO_BMC_RESET")
	)
	(segment
		(start 93.025722 -147.268438)
		(end 94.465648 -148.708364)
		(width 0.127)
		(layer "In5.Cu")
		(net "COMP_TO_BMC_RESET")
	)
	(segment
		(start 91.570048 -147.268438)
		(end 93.025722 -147.268438)
		(width 0.127)
		(layer "In5.Cu")
		(net "COMP_TO_BMC_RESET")
	)
	(segment
		(start 99.705414 -146.99107)
		(end 100.053648 -146.99107)
		(width 0.127)
		(layer "In5.Cu")
		(net "COMP_TO_BMC_RESET")
	)
	(segment
		(start 88.166194 -148.3868)
		(end 88.276938 -148.276056)
		(width 0.127)
		(layer "In5.Cu")
		(net "COMP_TO_BMC_RESET")
	)
	(segment
		(start 86.491318 -149.797008)
		(end 87.901526 -148.3868)
		(width 0.127)
		(layer "In5.Cu")
		(net "COMP_TO_BMC_RESET")
	)
	(segment
		(start 78.2828 -150.500842)
		(end 78.826106 -149.957536)
		(width 0.127)
		(layer "In5.Cu")
		(net "COMP_TO_BMC_RESET")
	)
	(segment
		(start 83.533996 -149.957536)
		(end 83.694524 -149.797008)
		(width 0.127)
		(layer "In5.Cu")
		(net "COMP_TO_BMC_RESET")
	)
	(segment
		(start 87.901526 -148.3868)
		(end 88.166194 -148.3868)
		(width 0.127)
		(layer "In5.Cu")
		(net "COMP_TO_BMC_RESET")
	)
	(segment
		(start 94.465648 -148.708364)
		(end 97.98812 -148.708364)
		(width 0.127)
		(layer "In5.Cu")
		(net "COMP_TO_BMC_RESET")
	)
	(segment
		(start 97.98812 -148.708364)
		(end 99.705414 -146.99107)
		(width 0.127)
		(layer "In5.Cu")
		(net "COMP_TO_BMC_RESET")
	)
	(segment
		(start 83.694524 -149.797008)
		(end 86.491318 -149.797008)
		(width 0.127)
		(layer "In5.Cu")
		(net "COMP_TO_BMC_RESET")
	)
	(segment
		(start 78.826106 -149.957536)
		(end 83.533996 -149.957536)
		(width 0.127)
		(layer "In5.Cu")
		(net "COMP_TO_BMC_RESET")
	)
	(segment
		(start 88.666574 -148.276056)
		(end 88.790018 -148.3995)
		(width 0.127)
		(layer "In5.Cu")
		(net "COMP_TO_BMC_RESET")
	)
	(segment
		(start 86.9569 -127.6731)
		(end 86.5632 -128.0668)
		(width 0.127)
		(layer "F.Cu")
		(net "BMC_UART_SEL_OUT")
	)
	(segment
		(start 85.3694 -129.2606)
		(end 85.0011 -129.2606)
		(width 0.127)
		(layer "F.Cu")
		(net "BMC_UART_SEL_OUT")
	)
	(segment
		(start 88.0872 -127.6731)
		(end 86.9569 -127.6731)
		(width 0.127)
		(layer "F.Cu")
		(net "BMC_UART_SEL_OUT")
	)
	(segment
		(start 88.3285 -127.9144)
		(end 88.0872 -127.6731)
		(width 0.127)
		(layer "F.Cu")
		(net "BMC_UART_SEL_OUT")
	)
	(segment
		(start 42.900092 -138.599926)
		(end 43.299888 -138.999722)
		(width 0.127)
		(layer "F.Cu")
		(net "BMC_UART_SEL_OUT")
	)
	(segment
		(start 86.5632 -128.0668)
		(end 85.3694 -129.2606)
		(width 0.127)
		(layer "F.Cu")
		(net "BMC_UART_SEL_OUT")
	)
	(segment
		(start 43.299888 -138.999722)
		(end 43.299888 -138.999976)
		(width 0.127)
		(layer "F.Cu")
		(net "BMC_UART_SEL_OUT")
	)
	(via
		(at 86.739222 -137.4775)
		(size 0.508)
		(drill 0.254)
		(layers "F.Cu" "B.Cu")
		(net "BMC_UART_SEL_OUT")
	)
	(via
		(at 85.0011 -129.2606)
		(size 0.508)
		(drill 0.254)
		(layers "F.Cu" "B.Cu")
		(net "BMC_UART_SEL_OUT")
	)
	(via
		(at 86.5632 -128.0668)
		(size 0.6604)
		(drill 0.3302)
		(layers "F.Cu" "B.Cu")
		(net "BMC_UART_SEL_OUT")
	)
	(via
		(at 42.900092 -138.599926)
		(size 0.4572)
		(drill 0.2032)
		(layers "F.Cu" "B.Cu")
		(net "BMC_UART_SEL_OUT")
	)
	(segment
		(start 86.739222 -137.4775)
		(end 86.308946 -137.047224)
		(width 0.127)
		(layer "In2.Cu")
		(net "BMC_UART_SEL_OUT")
	)
	(segment
		(start 85.66785 -134.695438)
		(end 85.66785 -133.561836)
		(width 0.127)
		(layer "In2.Cu")
		(net "BMC_UART_SEL_OUT")
	)
	(segment
		(start 86.308946 -135.336534)
		(end 85.66785 -134.695438)
		(width 0.127)
		(layer "In2.Cu")
		(net "BMC_UART_SEL_OUT")
	)
	(segment
		(start 85.011006 -129.270506)
		(end 85.0011 -129.2606)
		(width 0.127)
		(layer "In2.Cu")
		(net "BMC_UART_SEL_OUT")
	)
	(segment
		(start 86.308946 -137.047224)
		(end 86.308946 -135.336534)
		(width 0.127)
		(layer "In2.Cu")
		(net "BMC_UART_SEL_OUT")
	)
	(segment
		(start 85.66785 -133.561836)
		(end 85.011006 -132.904992)
		(width 0.127)
		(layer "In2.Cu")
		(net "BMC_UART_SEL_OUT")
	)
	(segment
		(start 85.011006 -132.904992)
		(end 85.011006 -129.270506)
		(width 0.127)
		(layer "In2.Cu")
		(net "BMC_UART_SEL_OUT")
	)
	(segment
		(start 44.349416 -138.194034)
		(end 44.0944 -138.44905)
		(width 0.127)
		(layer "In5.Cu")
		(net "BMC_UART_SEL_OUT")
	)
	(segment
		(start 43.855132 -138.974576)
		(end 43.274742 -138.974576)
		(width 0.0889)
		(layer "In5.Cu")
		(net "BMC_UART_SEL_OUT")
	)
	(segment
		(start 71.663052 -136.362948)
		(end 71.501 -136.525)
		(width 0.127)
		(layer "In5.Cu")
		(net "BMC_UART_SEL_OUT")
	)
	(segment
		(start 43.274742 -138.974576)
		(end 42.900092 -138.599926)
		(width 0.0889)
		(layer "In5.Cu")
		(net "BMC_UART_SEL_OUT")
	)
	(segment
		(start 61.7982 -135.582406)
		(end 60.776612 -136.603994)
		(width 0.127)
		(layer "In5.Cu")
		(net "BMC_UART_SEL_OUT")
	)
	(segment
		(start 72.836024 -136.362948)
		(end 71.663052 -136.362948)
		(width 0.127)
		(layer "In5.Cu")
		(net "BMC_UART_SEL_OUT")
	)
	(segment
		(start 55.288434 -136.37768)
		(end 46.479714 -136.37768)
		(width 0.127)
		(layer "In5.Cu")
		(net "BMC_UART_SEL_OUT")
	)
	(segment
		(start 44.0944 -138.476228)
		(end 44.0944 -138.735308)
		(width 0.0889)
		(layer "In5.Cu")
		(net "BMC_UART_SEL_OUT")
	)
	(segment
		(start 44.0944 -138.735308)
		(end 43.855132 -138.974576)
		(width 0.0889)
		(layer "In5.Cu")
		(net "BMC_UART_SEL_OUT")
	)
	(segment
		(start 55.514748 -136.603994)
		(end 55.288434 -136.37768)
		(width 0.127)
		(layer "In5.Cu")
		(net "BMC_UART_SEL_OUT")
	)
	(segment
		(start 69.812916 -135.582406)
		(end 61.7982 -135.582406)
		(width 0.127)
		(layer "In5.Cu")
		(net "BMC_UART_SEL_OUT")
	)
	(segment
		(start 70.75551 -136.525)
		(end 69.812916 -135.582406)
		(width 0.127)
		(layer "In5.Cu")
		(net "BMC_UART_SEL_OUT")
	)
	(segment
		(start 86.739222 -137.4775)
		(end 86.458044 -137.196322)
		(width 0.127)
		(layer "In5.Cu")
		(net "BMC_UART_SEL_OUT")
	)
	(segment
		(start 71.501 -136.525)
		(end 70.75551 -136.525)
		(width 0.127)
		(layer "In5.Cu")
		(net "BMC_UART_SEL_OUT")
	)
	(segment
		(start 46.479714 -136.37768)
		(end 44.66336 -138.194034)
		(width 0.127)
		(layer "In5.Cu")
		(net "BMC_UART_SEL_OUT")
	)
	(segment
		(start 86.458044 -137.196322)
		(end 73.669398 -137.196322)
		(width 0.127)
		(layer "In5.Cu")
		(net "BMC_UART_SEL_OUT")
	)
	(segment
		(start 44.0944 -138.44905)
		(end 44.0944 -138.476228)
		(width 0.127)
		(layer "In5.Cu")
		(net "BMC_UART_SEL_OUT")
	)
	(segment
		(start 73.669398 -137.196322)
		(end 72.836024 -136.362948)
		(width 0.127)
		(layer "In5.Cu")
		(net "BMC_UART_SEL_OUT")
	)
	(segment
		(start 60.776612 -136.603994)
		(end 55.514748 -136.603994)
		(width 0.127)
		(layer "In5.Cu")
		(net "BMC_UART_SEL_OUT")
	)
	(segment
		(start 44.66336 -138.194034)
		(end 44.349416 -138.194034)
		(width 0.127)
		(layer "In5.Cu")
		(net "BMC_UART_SEL_OUT")
	)
	(segment
		(start 70.470014 -137.130028)
		(end 70.473062 -137.12698)
		(width 0.127)
		(layer "F.Cu")
		(net "BMC_UART_SEL_IN")
	)
	(segment
		(start 71.157084 -137.12698)
		(end 71.414132 -136.869932)
		(width 0.127)
		(layer "F.Cu")
		(net "BMC_UART_SEL_IN")
	)
	(segment
		(start 44.899834 -139.800076)
		(end 44.89958 -139.800076)
		(width 0.127)
		(layer "F.Cu")
		(net "BMC_UART_SEL_IN")
	)
	(segment
		(start 70.473062 -137.12698)
		(end 71.157084 -137.12698)
		(width 0.127)
		(layer "F.Cu")
		(net "BMC_UART_SEL_IN")
	)
	(segment
		(start 73.4187 -135.9535)
		(end 72.330564 -135.9535)
		(width 0.127)
		(layer "F.Cu")
		(net "BMC_UART_SEL_IN")
	)
	(segment
		(start 72.330564 -135.9535)
		(end 71.414132 -136.869932)
		(width 0.127)
		(layer "F.Cu")
		(net "BMC_UART_SEL_IN")
	)
	(segment
		(start 44.89958 -139.800076)
		(end 44.500038 -139.400534)
		(width 0.127)
		(layer "F.Cu")
		(net "BMC_UART_SEL_IN")
	)
	(via
		(at 44.500038 -139.400534)
		(size 0.4572)
		(drill 0.2032)
		(layers "F.Cu" "B.Cu")
		(net "BMC_UART_SEL_IN")
	)
	(via
		(at 71.414132 -136.869932)
		(size 0.6604)
		(drill 0.3302)
		(layers "F.Cu" "B.Cu")
		(net "BMC_UART_SEL_IN")
	)
	(via
		(at 70.470014 -137.130028)
		(size 0.508)
		(drill 0.254)
		(layers "F.Cu" "B.Cu")
		(net "BMC_UART_SEL_IN")
	)
	(segment
		(start 54.84368 -136.60628)
		(end 46.736508 -136.60628)
		(width 0.127)
		(layer "In5.Cu")
		(net "BMC_UART_SEL_IN")
	)
	(segment
		(start 46.736508 -136.60628)
		(end 44.8818 -138.460988)
		(width 0.127)
		(layer "In5.Cu")
		(net "BMC_UART_SEL_IN")
	)
	(segment
		(start 61.956188 -135.963406)
		(end 60.886594 -137.033)
		(width 0.127)
		(layer "In5.Cu")
		(net "BMC_UART_SEL_IN")
	)
	(segment
		(start 70.470014 -137.130028)
		(end 69.303392 -135.963406)
		(width 0.127)
		(layer "In5.Cu")
		(net "BMC_UART_SEL_IN")
	)
	(segment
		(start 60.886594 -137.033)
		(end 55.2704 -137.033)
		(width 0.127)
		(layer "In5.Cu")
		(net "BMC_UART_SEL_IN")
	)
	(segment
		(start 44.8818 -138.488166)
		(end 44.8818 -138.938)
		(width 0.0889)
		(layer "In5.Cu")
		(net "BMC_UART_SEL_IN")
	)
	(segment
		(start 44.500038 -139.319762)
		(end 44.500038 -139.400534)
		(width 0.0889)
		(layer "In5.Cu")
		(net "BMC_UART_SEL_IN")
	)
	(segment
		(start 44.8818 -138.460988)
		(end 44.8818 -138.488166)
		(width 0.127)
		(layer "In5.Cu")
		(net "BMC_UART_SEL_IN")
	)
	(segment
		(start 69.303392 -135.963406)
		(end 61.956188 -135.963406)
		(width 0.127)
		(layer "In5.Cu")
		(net "BMC_UART_SEL_IN")
	)
	(segment
		(start 44.8818 -138.938)
		(end 44.500038 -139.319762)
		(width 0.0889)
		(layer "In5.Cu")
		(net "BMC_UART_SEL_IN")
	)
	(segment
		(start 55.2704 -137.033)
		(end 54.84368 -136.60628)
		(width 0.127)
		(layer "In5.Cu")
		(net "BMC_UART_SEL_IN")
	)
	(segment
		(start 205.486 -16.421354)
		(end 205.574646 -16.51)
		(width 0.127)
		(layer "F.Cu")
		(net "BMC_ML_PWR_YELLOW_LED_R")
	)
	(segment
		(start 205.844902 -13.676884)
		(end 205.844902 -14.478)
		(width 0.127)
		(layer "F.Cu")
		(net "BMC_ML_PWR_YELLOW_LED_R")
	)
	(segment
		(start 205.486 -15.748)
		(end 205.486 -16.421354)
		(width 0.127)
		(layer "F.Cu")
		(net "BMC_ML_PWR_YELLOW_LED_R")
	)
	(segment
		(start 204.979524 -13.526008)
		(end 205.694026 -13.526008)
		(width 0.127)
		(layer "F.Cu")
		(net "BMC_ML_PWR_YELLOW_LED_R")
	)
	(segment
		(start 205.694026 -13.526008)
		(end 205.844902 -13.676884)
		(width 0.127)
		(layer "F.Cu")
		(net "BMC_ML_PWR_YELLOW_LED_R")
	)
	(segment
		(start 205.486 -14.836902)
		(end 205.486 -15.748)
		(width 0.127)
		(layer "F.Cu")
		(net "BMC_ML_PWR_YELLOW_LED_R")
	)
	(segment
		(start 205.844902 -14.478)
		(end 205.486 -14.836902)
		(width 0.127)
		(layer "F.Cu")
		(net "BMC_ML_PWR_YELLOW_LED_R")
	)
	(segment
		(start 205.574646 -16.51)
		(end 205.574646 -16.912844)
		(width 0.127)
		(layer "F.Cu")
		(net "BMC_ML_PWR_YELLOW_LED_R")
	)
	(via
		(at 205.486 -15.748)
		(size 0.6604)
		(drill 0.3302)
		(layers "F.Cu" "B.Cu")
		(net "BMC_ML_PWR_YELLOW_LED_R")
	)
	(segment
		(start 38.809168 -137.709148)
		(end 39.299896 -138.199876)
		(width 0.127)
		(layer "F.Cu")
		(net "BMC_ML_PWR_YELLOW_LED")
	)
	(segment
		(start 38.71341 -137.163556)
		(end 38.809168 -137.259314)
		(width 0.127)
		(layer "F.Cu")
		(net "BMC_ML_PWR_YELLOW_LED")
	)
	(segment
		(start 38.809168 -137.259314)
		(end 38.809168 -137.709148)
		(width 0.127)
		(layer "F.Cu")
		(net "BMC_ML_PWR_YELLOW_LED")
	)
	(segment
		(start 205.574646 -17.801844)
		(end 205.574646 -18.592038)
		(width 0.127)
		(layer "F.Cu")
		(net "BMC_ML_PWR_YELLOW_LED")
	)
	(via
		(at 54.323996 -113.087404)
		(size 0.4572)
		(drill 0.2032)
		(layers "F.Cu" "B.Cu")
		(net "BMC_ML_PWR_YELLOW_LED")
	)
	(via
		(at 205.574646 -18.592038)
		(size 0.508)
		(drill 0.254)
		(layers "F.Cu" "B.Cu")
		(net "BMC_ML_PWR_YELLOW_LED")
	)
	(via
		(at 98.7298 -22.8092)
		(size 0.508)
		(drill 0.254)
		(layers "F.Cu" "B.Cu")
		(net "BMC_ML_PWR_YELLOW_LED")
	)
	(via
		(at 93.337634 -93.75648)
		(size 0.508)
		(drill 0.254)
		(layers "F.Cu" "B.Cu")
		(net "BMC_ML_PWR_YELLOW_LED")
	)
	(via
		(at 37.869622 -137.520172)
		(size 0.6096)
		(drill 0.3048)
		(layers "F.Cu" "B.Cu")
		(net "BMC_ML_PWR_YELLOW_LED")
	)
	(via
		(at 129.643632 -21.787866)
		(size 0.508)
		(drill 0.254)
		(layers "F.Cu" "B.Cu")
		(net "BMC_ML_PWR_YELLOW_LED")
	)
	(via
		(at 38.71341 -137.163556)
		(size 0.508)
		(drill 0.254)
		(layers "F.Cu" "B.Cu")
		(net "BMC_ML_PWR_YELLOW_LED")
	)
	(via
		(at 37.725858 -131.950714)
		(size 0.508)
		(drill 0.254)
		(layers "F.Cu" "B.Cu")
		(net "BMC_ML_PWR_YELLOW_LED")
	)
	(segment
		(start 38.186614 -131.489958)
		(end 37.725858 -131.950714)
		(width 0.127)
		(layer "B.Cu")
		(net "BMC_ML_PWR_YELLOW_LED")
	)
	(segment
		(start 62.242192 -121.0056)
		(end 70.2056 -121.0056)
		(width 0.127)
		(layer "B.Cu")
		(net "BMC_ML_PWR_YELLOW_LED")
	)
	(segment
		(start 109.420406 -20.55114)
		(end 109.647482 -20.778216)
		(width 0.127)
		(layer "B.Cu")
		(net "BMC_ML_PWR_YELLOW_LED")
	)
	(segment
		(start 38.356794 -137.520172)
		(end 38.71341 -137.163556)
		(width 0.127)
		(layer "B.Cu")
		(net "BMC_ML_PWR_YELLOW_LED")
	)
	(segment
		(start 98.7298 -21.857462)
		(end 99.161854 -21.425408)
		(width 0.127)
		(layer "B.Cu")
		(net "BMC_ML_PWR_YELLOW_LED")
	)
	(segment
		(start 98.7298 -22.8092)
		(end 98.7298 -21.857462)
		(width 0.127)
		(layer "B.Cu")
		(net "BMC_ML_PWR_YELLOW_LED")
	)
	(segment
		(start 70.9676 -120.2436)
		(end 70.9676 -119.271542)
		(width 0.127)
		(layer "B.Cu")
		(net "BMC_ML_PWR_YELLOW_LED")
	)
	(segment
		(start 93.820742 -93.75648)
		(end 93.337634 -93.75648)
		(width 0.127)
		(layer "B.Cu")
		(net "BMC_ML_PWR_YELLOW_LED")
	)
	(segment
		(start 95.653352 -107.45724)
		(end 95.653352 -95.58909)
		(width 0.127)
		(layer "B.Cu")
		(net "BMC_ML_PWR_YELLOW_LED")
	)
	(segment
		(start 129.908554 -24.63673)
		(end 129.908554 -22.052788)
		(width 0.127)
		(layer "B.Cu")
		(net "BMC_ML_PWR_YELLOW_LED")
	)
	(segment
		(start 121.34469 -26.608024)
		(end 127.93726 -26.608024)
		(width 0.127)
		(layer "B.Cu")
		(net "BMC_ML_PWR_YELLOW_LED")
	)
	(segment
		(start 99.161854 -21.425408)
		(end 99.87915 -21.425408)
		(width 0.127)
		(layer "B.Cu")
		(net "BMC_ML_PWR_YELLOW_LED")
	)
	(segment
		(start 77.056742 -113.1824)
		(end 77.064362 -113.1824)
		(width 0.127)
		(layer "B.Cu")
		(net "BMC_ML_PWR_YELLOW_LED")
	)
	(segment
		(start 39.092632 -131.489958)
		(end 38.186614 -131.489958)
		(width 0.127)
		(layer "B.Cu")
		(net "BMC_ML_PWR_YELLOW_LED")
	)
	(segment
		(start 109.647482 -20.778216)
		(end 115.514882 -20.778216)
		(width 0.127)
		(layer "B.Cu")
		(net "BMC_ML_PWR_YELLOW_LED")
	)
	(segment
		(start 77.064362 -113.1824)
		(end 77.142848 -113.103914)
		(width 0.127)
		(layer "B.Cu")
		(net "BMC_ML_PWR_YELLOW_LED")
	)
	(segment
		(start 115.514882 -20.778216)
		(end 121.34469 -26.608024)
		(width 0.127)
		(layer "B.Cu")
		(net "BMC_ML_PWR_YELLOW_LED")
	)
	(segment
		(start 70.9676 -119.271542)
		(end 77.056742 -113.1824)
		(width 0.127)
		(layer "B.Cu")
		(net "BMC_ML_PWR_YELLOW_LED")
	)
	(segment
		(start 77.142848 -113.103914)
		(end 90.006678 -113.103914)
		(width 0.127)
		(layer "B.Cu")
		(net "BMC_ML_PWR_YELLOW_LED")
	)
	(segment
		(start 37.869622 -137.520172)
		(end 38.356794 -137.520172)
		(width 0.127)
		(layer "B.Cu")
		(net "BMC_ML_PWR_YELLOW_LED")
	)
	(segment
		(start 37.446966 -133.135624)
		(end 39.092632 -131.489958)
		(width 0.127)
		(layer "B.Cu")
		(net "BMC_ML_PWR_YELLOW_LED")
	)
	(segment
		(start 95.653352 -95.58909)
		(end 93.820742 -93.75648)
		(width 0.127)
		(layer "B.Cu")
		(net "BMC_ML_PWR_YELLOW_LED")
	)
	(segment
		(start 54.323996 -113.087404)
		(end 62.242192 -121.0056)
		(width 0.127)
		(layer "B.Cu")
		(net "BMC_ML_PWR_YELLOW_LED")
	)
	(segment
		(start 90.006678 -113.103914)
		(end 95.653352 -107.45724)
		(width 0.127)
		(layer "B.Cu")
		(net "BMC_ML_PWR_YELLOW_LED")
	)
	(segment
		(start 70.2056 -121.0056)
		(end 70.9676 -120.2436)
		(width 0.127)
		(layer "B.Cu")
		(net "BMC_ML_PWR_YELLOW_LED")
	)
	(segment
		(start 37.446966 -137.097516)
		(end 37.446966 -133.135624)
		(width 0.127)
		(layer "B.Cu")
		(net "BMC_ML_PWR_YELLOW_LED")
	)
	(segment
		(start 37.869622 -137.520172)
		(end 37.446966 -137.097516)
		(width 0.127)
		(layer "B.Cu")
		(net "BMC_ML_PWR_YELLOW_LED")
	)
	(segment
		(start 100.753418 -20.55114)
		(end 109.420406 -20.55114)
		(width 0.127)
		(layer "B.Cu")
		(net "BMC_ML_PWR_YELLOW_LED")
	)
	(segment
		(start 127.93726 -26.608024)
		(end 129.908554 -24.63673)
		(width 0.127)
		(layer "B.Cu")
		(net "BMC_ML_PWR_YELLOW_LED")
	)
	(segment
		(start 99.87915 -21.425408)
		(end 100.753418 -20.55114)
		(width 0.127)
		(layer "B.Cu")
		(net "BMC_ML_PWR_YELLOW_LED")
	)
	(segment
		(start 129.908554 -22.052788)
		(end 129.643632 -21.787866)
		(width 0.127)
		(layer "B.Cu")
		(net "BMC_ML_PWR_YELLOW_LED")
	)
	(segment
		(start 37.725858 -131.950714)
		(end 37.725858 -131.286504)
		(width 0.127)
		(layer "In2.Cu")
		(net "BMC_ML_PWR_YELLOW_LED")
	)
	(segment
		(start 36.59251 -130.153156)
		(end 36.59251 -126.59233)
		(width 0.127)
		(layer "In2.Cu")
		(net "BMC_ML_PWR_YELLOW_LED")
	)
	(segment
		(start 93.337634 -93.75648)
		(end 93.336872 -93.755718)
		(width 0.127)
		(layer "In2.Cu")
		(net "BMC_ML_PWR_YELLOW_LED")
	)
	(segment
		(start 94.659958 -43.565826)
		(end 94.659958 -41.810432)
		(width 0.127)
		(layer "In2.Cu")
		(net "BMC_ML_PWR_YELLOW_LED")
	)
	(segment
		(start 94.659958 -41.810432)
		(end 95.053658 -41.416732)
		(width 0.127)
		(layer "In2.Cu")
		(net "BMC_ML_PWR_YELLOW_LED")
	)
	(segment
		(start 98.7298 -23.368)
		(end 98.7298 -22.8092)
		(width 0.127)
		(layer "In2.Cu")
		(net "BMC_ML_PWR_YELLOW_LED")
	)
	(segment
		(start 52.959 -114.4524)
		(end 54.323996 -113.087404)
		(width 0.127)
		(layer "In2.Cu")
		(net "BMC_ML_PWR_YELLOW_LED")
	)
	(segment
		(start 95.053658 -30.21076)
		(end 98.240596 -27.023822)
		(width 0.127)
		(layer "In2.Cu")
		(net "BMC_ML_PWR_YELLOW_LED")
	)
	(segment
		(start 98.923856 -23.930356)
		(end 98.923856 -23.562056)
		(width 0.127)
		(layer "In2.Cu")
		(net "BMC_ML_PWR_YELLOW_LED")
	)
	(segment
		(start 37.725858 -131.286504)
		(end 36.59251 -130.153156)
		(width 0.127)
		(layer "In2.Cu")
		(net "BMC_ML_PWR_YELLOW_LED")
	)
	(segment
		(start 93.336872 -44.888912)
		(end 94.659958 -43.565826)
		(width 0.127)
		(layer "In2.Cu")
		(net "BMC_ML_PWR_YELLOW_LED")
	)
	(segment
		(start 35.819588 -125.819408)
		(end 35.819588 -116.778024)
		(width 0.127)
		(layer "In2.Cu")
		(net "BMC_ML_PWR_YELLOW_LED")
	)
	(segment
		(start 98.240596 -27.023822)
		(end 98.240596 -24.613616)
		(width 0.127)
		(layer "In2.Cu")
		(net "BMC_ML_PWR_YELLOW_LED")
	)
	(segment
		(start 95.053658 -41.416732)
		(end 95.053658 -30.21076)
		(width 0.127)
		(layer "In2.Cu")
		(net "BMC_ML_PWR_YELLOW_LED")
	)
	(segment
		(start 35.819588 -116.778024)
		(end 38.145212 -114.4524)
		(width 0.127)
		(layer "In2.Cu")
		(net "BMC_ML_PWR_YELLOW_LED")
	)
	(segment
		(start 36.59251 -126.59233)
		(end 35.819588 -125.819408)
		(width 0.127)
		(layer "In2.Cu")
		(net "BMC_ML_PWR_YELLOW_LED")
	)
	(segment
		(start 98.923856 -23.562056)
		(end 98.7298 -23.368)
		(width 0.127)
		(layer "In2.Cu")
		(net "BMC_ML_PWR_YELLOW_LED")
	)
	(segment
		(start 93.336872 -93.755718)
		(end 93.336872 -44.888912)
		(width 0.127)
		(layer "In2.Cu")
		(net "BMC_ML_PWR_YELLOW_LED")
	)
	(segment
		(start 38.145212 -114.4524)
		(end 52.959 -114.4524)
		(width 0.127)
		(layer "In2.Cu")
		(net "BMC_ML_PWR_YELLOW_LED")
	)
	(segment
		(start 98.240596 -24.613616)
		(end 98.923856 -23.930356)
		(width 0.127)
		(layer "In2.Cu")
		(net "BMC_ML_PWR_YELLOW_LED")
	)
	(segment
		(start 203.656946 -16.098012)
		(end 200.52157 -12.962636)
		(width 0.127)
		(layer "In5.Cu")
		(net "BMC_ML_PWR_YELLOW_LED")
	)
	(segment
		(start 205.74 -19.431)
		(end 204.47 -19.431)
		(width 0.127)
		(layer "In5.Cu")
		(net "BMC_ML_PWR_YELLOW_LED")
	)
	(segment
		(start 205.574646 -18.592038)
		(end 205.867 -18.884392)
		(width 0.127)
		(layer "In5.Cu")
		(net "BMC_ML_PWR_YELLOW_LED")
	)
	(segment
		(start 136.028176 -17.489932)
		(end 132.877814 -20.640294)
		(width 0.127)
		(layer "In5.Cu")
		(net "BMC_ML_PWR_YELLOW_LED")
	)
	(segment
		(start 204.47 -19.431)
		(end 203.656946 -18.617946)
		(width 0.127)
		(layer "In5.Cu")
		(net "BMC_ML_PWR_YELLOW_LED")
	)
	(segment
		(start 205.867 -19.304)
		(end 205.74 -19.431)
		(width 0.127)
		(layer "In5.Cu")
		(net "BMC_ML_PWR_YELLOW_LED")
	)
	(segment
		(start 194.270122 -14.32814)
		(end 190.851282 -10.9093)
		(width 0.127)
		(layer "In5.Cu")
		(net "BMC_ML_PWR_YELLOW_LED")
	)
	(segment
		(start 131.23799 -21.23313)
		(end 130.151632 -21.23313)
		(width 0.127)
		(layer "In5.Cu")
		(net "BMC_ML_PWR_YELLOW_LED")
	)
	(segment
		(start 153.494486 -9.720834)
		(end 141.68374 -9.720834)
		(width 0.127)
		(layer "In5.Cu")
		(net "BMC_ML_PWR_YELLOW_LED")
	)
	(segment
		(start 154.66695 -8.54837)
		(end 153.494486 -9.720834)
		(width 0.127)
		(layer "In5.Cu")
		(net "BMC_ML_PWR_YELLOW_LED")
	)
	(segment
		(start 184.146444 -8.54837)
		(end 154.66695 -8.54837)
		(width 0.127)
		(layer "In5.Cu")
		(net "BMC_ML_PWR_YELLOW_LED")
	)
	(segment
		(start 186.507374 -10.9093)
		(end 184.146444 -8.54837)
		(width 0.127)
		(layer "In5.Cu")
		(net "BMC_ML_PWR_YELLOW_LED")
	)
	(segment
		(start 205.867 -18.884392)
		(end 205.867 -19.304)
		(width 0.127)
		(layer "In5.Cu")
		(net "BMC_ML_PWR_YELLOW_LED")
	)
	(segment
		(start 195.726304 -14.32814)
		(end 194.270122 -14.32814)
		(width 0.127)
		(layer "In5.Cu")
		(net "BMC_ML_PWR_YELLOW_LED")
	)
	(segment
		(start 190.851282 -10.9093)
		(end 186.507374 -10.9093)
		(width 0.127)
		(layer "In5.Cu")
		(net "BMC_ML_PWR_YELLOW_LED")
	)
	(segment
		(start 129.643632 -21.74113)
		(end 129.643632 -21.787866)
		(width 0.127)
		(layer "In5.Cu")
		(net "BMC_ML_PWR_YELLOW_LED")
	)
	(segment
		(start 136.028176 -15.376398)
		(end 136.028176 -17.489932)
		(width 0.127)
		(layer "In5.Cu")
		(net "BMC_ML_PWR_YELLOW_LED")
	)
	(segment
		(start 197.091808 -12.962636)
		(end 195.726304 -14.32814)
		(width 0.127)
		(layer "In5.Cu")
		(net "BMC_ML_PWR_YELLOW_LED")
	)
	(segment
		(start 203.656946 -18.617946)
		(end 203.656946 -16.098012)
		(width 0.127)
		(layer "In5.Cu")
		(net "BMC_ML_PWR_YELLOW_LED")
	)
	(segment
		(start 132.877814 -20.640294)
		(end 131.830826 -20.640294)
		(width 0.127)
		(layer "In5.Cu")
		(net "BMC_ML_PWR_YELLOW_LED")
	)
	(segment
		(start 141.68374 -9.720834)
		(end 136.028176 -15.376398)
		(width 0.127)
		(layer "In5.Cu")
		(net "BMC_ML_PWR_YELLOW_LED")
	)
	(segment
		(start 130.151632 -21.23313)
		(end 129.643632 -21.74113)
		(width 0.127)
		(layer "In5.Cu")
		(net "BMC_ML_PWR_YELLOW_LED")
	)
	(segment
		(start 131.830826 -20.640294)
		(end 131.23799 -21.23313)
		(width 0.127)
		(layer "In5.Cu")
		(net "BMC_ML_PWR_YELLOW_LED")
	)
	(segment
		(start 200.52157 -12.962636)
		(end 197.091808 -12.962636)
		(width 0.127)
		(layer "In5.Cu")
		(net "BMC_ML_PWR_YELLOW_LED")
	)
	(segment
		(start 206.616046 -16.065754)
		(end 206.9846 -15.6972)
		(width 0.127)
		(layer "F.Cu")
		(net "BMC_ML_PWR_BLUE_LED_R")
	)
	(segment
		(start 208.90738 -16.55445)
		(end 208.05013 -15.6972)
		(width 0.127)
		(layer "F.Cu")
		(net "BMC_ML_PWR_BLUE_LED_R")
	)
	(segment
		(start 206.616046 -16.912844)
		(end 206.616046 -16.065754)
		(width 0.127)
		(layer "F.Cu")
		(net "BMC_ML_PWR_BLUE_LED_R")
	)
	(segment
		(start 208.05013 -15.6972)
		(end 206.9846 -15.6972)
		(width 0.127)
		(layer "F.Cu")
		(net "BMC_ML_PWR_BLUE_LED_R")
	)
	(via
		(at 206.9846 -15.6972)
		(size 0.6604)
		(drill 0.3302)
		(layers "F.Cu" "B.Cu")
		(net "BMC_ML_PWR_BLUE_LED_R")
	)
	(segment
		(start 39.299896 -137.157206)
		(end 39.299896 -137.40003)
		(width 0.127)
		(layer "F.Cu")
		(net "BMC_ML_PWR_BLUE_LED")
	)
	(segment
		(start 38.756336 -135.362188)
		(end 38.46195 -135.656574)
		(width 0.127)
		(layer "F.Cu")
		(net "BMC_ML_PWR_BLUE_LED")
	)
	(segment
		(start 38.46195 -136.31926)
		(end 39.299896 -137.157206)
		(width 0.127)
		(layer "F.Cu")
		(net "BMC_ML_PWR_BLUE_LED")
	)
	(segment
		(start 38.46195 -135.656574)
		(end 38.46195 -136.31926)
		(width 0.127)
		(layer "F.Cu")
		(net "BMC_ML_PWR_BLUE_LED")
	)
	(segment
		(start 206.616046 -17.801844)
		(end 206.616046 -18.552668)
		(width 0.127)
		(layer "F.Cu")
		(net "BMC_ML_PWR_BLUE_LED")
	)
	(segment
		(start 206.616046 -18.552668)
		(end 206.590646 -18.578068)
		(width 0.127)
		(layer "F.Cu")
		(net "BMC_ML_PWR_BLUE_LED")
	)
	(via
		(at 39.100252 -133.72846)
		(size 0.6096)
		(drill 0.3048)
		(layers "F.Cu" "B.Cu")
		(net "BMC_ML_PWR_BLUE_LED")
	)
	(via
		(at 55.8292 -113.2078)
		(size 0.4572)
		(drill 0.2032)
		(layers "F.Cu" "B.Cu")
		(net "BMC_ML_PWR_BLUE_LED")
	)
	(via
		(at 206.590646 -18.578068)
		(size 0.508)
		(drill 0.254)
		(layers "F.Cu" "B.Cu")
		(net "BMC_ML_PWR_BLUE_LED")
	)
	(via
		(at 38.141148 -133.587998)
		(size 0.508)
		(drill 0.254)
		(layers "F.Cu" "B.Cu")
		(net "BMC_ML_PWR_BLUE_LED")
	)
	(via
		(at 130.532886 -21.805646)
		(size 0.508)
		(drill 0.254)
		(layers "F.Cu" "B.Cu")
		(net "BMC_ML_PWR_BLUE_LED")
	)
	(via
		(at 99.304856 -22.155404)
		(size 0.508)
		(drill 0.254)
		(layers "F.Cu" "B.Cu")
		(net "BMC_ML_PWR_BLUE_LED")
	)
	(via
		(at 38.756336 -135.362188)
		(size 0.508)
		(drill 0.254)
		(layers "F.Cu" "B.Cu")
		(net "BMC_ML_PWR_BLUE_LED")
	)
	(via
		(at 93.308932 -94.622874)
		(size 0.508)
		(drill 0.254)
		(layers "F.Cu" "B.Cu")
		(net "BMC_ML_PWR_BLUE_LED")
	)
	(segment
		(start 38.141148 -133.188456)
		(end 38.707568 -132.622036)
		(width 0.127)
		(layer "B.Cu")
		(net "BMC_ML_PWR_BLUE_LED")
	)
	(segment
		(start 95.272352 -95.747078)
		(end 94.148148 -94.622874)
		(width 0.127)
		(layer "B.Cu")
		(net "BMC_ML_PWR_BLUE_LED")
	)
	(segment
		(start 99.688142 -22.155404)
		(end 99.304856 -22.155404)
		(width 0.127)
		(layer "B.Cu")
		(net "BMC_ML_PWR_BLUE_LED")
	)
	(segment
		(start 100.911406 -20.93214)
		(end 99.688142 -22.155404)
		(width 0.127)
		(layer "B.Cu")
		(net "BMC_ML_PWR_BLUE_LED")
	)
	(segment
		(start 128.095248 -26.989024)
		(end 121.186702 -26.989024)
		(width 0.127)
		(layer "B.Cu")
		(net "BMC_ML_PWR_BLUE_LED")
	)
	(segment
		(start 130.532886 -21.805646)
		(end 130.289554 -22.048978)
		(width 0.127)
		(layer "B.Cu")
		(net "BMC_ML_PWR_BLUE_LED")
	)
	(segment
		(start 130.289554 -24.794718)
		(end 128.095248 -26.989024)
		(width 0.127)
		(layer "B.Cu")
		(net "BMC_ML_PWR_BLUE_LED")
	)
	(segment
		(start 89.84869 -112.722914)
		(end 95.272352 -107.299252)
		(width 0.127)
		(layer "B.Cu")
		(net "BMC_ML_PWR_BLUE_LED")
	)
	(segment
		(start 62.5475 -119.9261)
		(end 70.146418 -119.9261)
		(width 0.127)
		(layer "B.Cu")
		(net "BMC_ML_PWR_BLUE_LED")
	)
	(segment
		(start 95.272352 -107.299252)
		(end 95.272352 -95.747078)
		(width 0.127)
		(layer "B.Cu")
		(net "BMC_ML_PWR_BLUE_LED")
	)
	(segment
		(start 70.4215 -119.651018)
		(end 70.4215 -119.278654)
		(width 0.127)
		(layer "B.Cu")
		(net "BMC_ML_PWR_BLUE_LED")
	)
	(segment
		(start 94.148148 -94.622874)
		(end 93.308932 -94.622874)
		(width 0.127)
		(layer "B.Cu")
		(net "BMC_ML_PWR_BLUE_LED")
	)
	(segment
		(start 39.100252 -135.018272)
		(end 39.100252 -133.72846)
		(width 0.127)
		(layer "B.Cu")
		(net "BMC_ML_PWR_BLUE_LED")
	)
	(segment
		(start 38.707568 -132.622036)
		(end 39.100252 -132.622036)
		(width 0.127)
		(layer "B.Cu")
		(net "BMC_ML_PWR_BLUE_LED")
	)
	(segment
		(start 38.756336 -135.362188)
		(end 39.100252 -135.018272)
		(width 0.127)
		(layer "B.Cu")
		(net "BMC_ML_PWR_BLUE_LED")
	)
	(segment
		(start 70.4215 -119.278654)
		(end 76.898754 -112.8014)
		(width 0.127)
		(layer "B.Cu")
		(net "BMC_ML_PWR_BLUE_LED")
	)
	(segment
		(start 109.262418 -20.93214)
		(end 100.911406 -20.93214)
		(width 0.127)
		(layer "B.Cu")
		(net "BMC_ML_PWR_BLUE_LED")
	)
	(segment
		(start 130.289554 -22.048978)
		(end 130.289554 -24.794718)
		(width 0.127)
		(layer "B.Cu")
		(net "BMC_ML_PWR_BLUE_LED")
	)
	(segment
		(start 121.186702 -26.989024)
		(end 115.356894 -21.159216)
		(width 0.127)
		(layer "B.Cu")
		(net "BMC_ML_PWR_BLUE_LED")
	)
	(segment
		(start 39.100252 -132.622036)
		(end 39.100252 -133.72846)
		(width 0.127)
		(layer "B.Cu")
		(net "BMC_ML_PWR_BLUE_LED")
	)
	(segment
		(start 76.906374 -112.8014)
		(end 76.98486 -112.722914)
		(width 0.127)
		(layer "B.Cu")
		(net "BMC_ML_PWR_BLUE_LED")
	)
	(segment
		(start 115.356894 -21.159216)
		(end 109.489494 -21.159216)
		(width 0.127)
		(layer "B.Cu")
		(net "BMC_ML_PWR_BLUE_LED")
	)
	(segment
		(start 76.98486 -112.722914)
		(end 89.84869 -112.722914)
		(width 0.127)
		(layer "B.Cu")
		(net "BMC_ML_PWR_BLUE_LED")
	)
	(segment
		(start 55.8292 -113.2078)
		(end 62.5475 -119.9261)
		(width 0.127)
		(layer "B.Cu")
		(net "BMC_ML_PWR_BLUE_LED")
	)
	(segment
		(start 76.898754 -112.8014)
		(end 76.906374 -112.8014)
		(width 0.127)
		(layer "B.Cu")
		(net "BMC_ML_PWR_BLUE_LED")
	)
	(segment
		(start 70.146418 -119.9261)
		(end 70.4215 -119.651018)
		(width 0.127)
		(layer "B.Cu")
		(net "BMC_ML_PWR_BLUE_LED")
	)
	(segment
		(start 38.141148 -133.587998)
		(end 38.141148 -133.188456)
		(width 0.127)
		(layer "B.Cu")
		(net "BMC_ML_PWR_BLUE_LED")
	)
	(segment
		(start 109.489494 -21.159216)
		(end 109.262418 -20.93214)
		(width 0.127)
		(layer "B.Cu")
		(net "BMC_ML_PWR_BLUE_LED")
	)
	(segment
		(start 36.200588 -116.936012)
		(end 38.227 -114.9096)
		(width 0.127)
		(layer "In2.Cu")
		(net "BMC_ML_PWR_BLUE_LED")
	)
	(segment
		(start 95.040958 -41.96842)
		(end 95.434658 -41.57472)
		(width 0.127)
		(layer "In2.Cu")
		(net "BMC_ML_PWR_BLUE_LED")
	)
	(segment
		(start 93.807534 -44.957238)
		(end 95.040958 -43.723814)
		(width 0.127)
		(layer "In2.Cu")
		(net "BMC_ML_PWR_BLUE_LED")
	)
	(segment
		(start 95.434658 -30.368748)
		(end 98.621596 -27.18181)
		(width 0.127)
		(layer "In2.Cu")
		(net "BMC_ML_PWR_BLUE_LED")
	)
	(segment
		(start 37.773102 -127.233934)
		(end 36.200588 -125.66142)
		(width 0.127)
		(layer "In2.Cu")
		(net "BMC_ML_PWR_BLUE_LED")
	)
	(segment
		(start 98.621596 -24.771604)
		(end 99.304856 -24.088344)
		(width 0.127)
		(layer "In2.Cu")
		(net "BMC_ML_PWR_BLUE_LED")
	)
	(segment
		(start 99.304856 -24.088344)
		(end 99.304856 -22.155404)
		(width 0.127)
		(layer "In2.Cu")
		(net "BMC_ML_PWR_BLUE_LED")
	)
	(segment
		(start 54.1274 -114.9096)
		(end 55.8292 -113.2078)
		(width 0.127)
		(layer "In2.Cu")
		(net "BMC_ML_PWR_BLUE_LED")
	)
	(segment
		(start 93.807534 -94.124272)
		(end 93.807534 -44.957238)
		(width 0.127)
		(layer "In2.Cu")
		(net "BMC_ML_PWR_BLUE_LED")
	)
	(segment
		(start 38.227 -114.9096)
		(end 54.1274 -114.9096)
		(width 0.127)
		(layer "In2.Cu")
		(net "BMC_ML_PWR_BLUE_LED")
	)
	(segment
		(start 98.621596 -27.18181)
		(end 98.621596 -24.771604)
		(width 0.127)
		(layer "In2.Cu")
		(net "BMC_ML_PWR_BLUE_LED")
	)
	(segment
		(start 95.434658 -41.57472)
		(end 95.434658 -30.368748)
		(width 0.127)
		(layer "In2.Cu")
		(net "BMC_ML_PWR_BLUE_LED")
	)
	(segment
		(start 38.141148 -133.587998)
		(end 38.141148 -133.188456)
		(width 0.127)
		(layer "In2.Cu")
		(net "BMC_ML_PWR_BLUE_LED")
	)
	(segment
		(start 38.603428 -132.726176)
		(end 38.603428 -131.468114)
		(width 0.127)
		(layer "In2.Cu")
		(net "BMC_ML_PWR_BLUE_LED")
	)
	(segment
		(start 95.040958 -43.723814)
		(end 95.040958 -41.96842)
		(width 0.127)
		(layer "In2.Cu")
		(net "BMC_ML_PWR_BLUE_LED")
	)
	(segment
		(start 36.200588 -125.66142)
		(end 36.200588 -116.936012)
		(width 0.127)
		(layer "In2.Cu")
		(net "BMC_ML_PWR_BLUE_LED")
	)
	(segment
		(start 37.773102 -130.637788)
		(end 37.773102 -127.233934)
		(width 0.127)
		(layer "In2.Cu")
		(net "BMC_ML_PWR_BLUE_LED")
	)
	(segment
		(start 93.308932 -94.622874)
		(end 93.807534 -94.124272)
		(width 0.127)
		(layer "In2.Cu")
		(net "BMC_ML_PWR_BLUE_LED")
	)
	(segment
		(start 38.141148 -133.188456)
		(end 38.603428 -132.726176)
		(width 0.127)
		(layer "In2.Cu")
		(net "BMC_ML_PWR_BLUE_LED")
	)
	(segment
		(start 38.603428 -131.468114)
		(end 37.773102 -130.637788)
		(width 0.127)
		(layer "In2.Cu")
		(net "BMC_ML_PWR_BLUE_LED")
	)
	(segment
		(start 197.249796 -13.343636)
		(end 195.884292 -14.70914)
		(width 0.127)
		(layer "In5.Cu")
		(net "BMC_ML_PWR_BLUE_LED")
	)
	(segment
		(start 131.204462 -21.805646)
		(end 130.532886 -21.805646)
		(width 0.127)
		(layer "In5.Cu")
		(net "BMC_ML_PWR_BLUE_LED")
	)
	(segment
		(start 204.312012 -19.812)
		(end 203.275946 -18.775934)
		(width 0.127)
		(layer "In5.Cu")
		(net "BMC_ML_PWR_BLUE_LED")
	)
	(segment
		(start 183.988456 -8.92937)
		(end 154.824938 -8.92937)
		(width 0.127)
		(layer "In5.Cu")
		(net "BMC_ML_PWR_BLUE_LED")
	)
	(segment
		(start 206.590646 -18.578068)
		(end 206.248 -18.920714)
		(width 0.127)
		(layer "In5.Cu")
		(net "BMC_ML_PWR_BLUE_LED")
	)
	(segment
		(start 133.035802 -21.021294)
		(end 131.988814 -21.021294)
		(width 0.127)
		(layer "In5.Cu")
		(net "BMC_ML_PWR_BLUE_LED")
	)
	(segment
		(start 200.363582 -13.343636)
		(end 197.249796 -13.343636)
		(width 0.127)
		(layer "In5.Cu")
		(net "BMC_ML_PWR_BLUE_LED")
	)
	(segment
		(start 194.112134 -14.70914)
		(end 190.693294 -11.2903)
		(width 0.127)
		(layer "In5.Cu")
		(net "BMC_ML_PWR_BLUE_LED")
	)
	(segment
		(start 206.248 -18.920714)
		(end 206.248 -19.461988)
		(width 0.127)
		(layer "In5.Cu")
		(net "BMC_ML_PWR_BLUE_LED")
	)
	(segment
		(start 131.988814 -21.021294)
		(end 131.204462 -21.805646)
		(width 0.127)
		(layer "In5.Cu")
		(net "BMC_ML_PWR_BLUE_LED")
	)
	(segment
		(start 195.884292 -14.70914)
		(end 194.112134 -14.70914)
		(width 0.127)
		(layer "In5.Cu")
		(net "BMC_ML_PWR_BLUE_LED")
	)
	(segment
		(start 186.349386 -11.2903)
		(end 183.988456 -8.92937)
		(width 0.127)
		(layer "In5.Cu")
		(net "BMC_ML_PWR_BLUE_LED")
	)
	(segment
		(start 203.275946 -16.256)
		(end 200.363582 -13.343636)
		(width 0.127)
		(layer "In5.Cu")
		(net "BMC_ML_PWR_BLUE_LED")
	)
	(segment
		(start 153.652474 -10.101834)
		(end 141.841728 -10.101834)
		(width 0.127)
		(layer "In5.Cu")
		(net "BMC_ML_PWR_BLUE_LED")
	)
	(segment
		(start 154.824938 -8.92937)
		(end 153.652474 -10.101834)
		(width 0.127)
		(layer "In5.Cu")
		(net "BMC_ML_PWR_BLUE_LED")
	)
	(segment
		(start 205.897988 -19.812)
		(end 204.312012 -19.812)
		(width 0.127)
		(layer "In5.Cu")
		(net "BMC_ML_PWR_BLUE_LED")
	)
	(segment
		(start 190.693294 -11.2903)
		(end 186.349386 -11.2903)
		(width 0.127)
		(layer "In5.Cu")
		(net "BMC_ML_PWR_BLUE_LED")
	)
	(segment
		(start 136.409176 -15.534386)
		(end 136.409176 -17.64792)
		(width 0.127)
		(layer "In5.Cu")
		(net "BMC_ML_PWR_BLUE_LED")
	)
	(segment
		(start 141.841728 -10.101834)
		(end 136.409176 -15.534386)
		(width 0.127)
		(layer "In5.Cu")
		(net "BMC_ML_PWR_BLUE_LED")
	)
	(segment
		(start 206.248 -19.461988)
		(end 205.897988 -19.812)
		(width 0.127)
		(layer "In5.Cu")
		(net "BMC_ML_PWR_BLUE_LED")
	)
	(segment
		(start 203.275946 -18.775934)
		(end 203.275946 -16.256)
		(width 0.127)
		(layer "In5.Cu")
		(net "BMC_ML_PWR_BLUE_LED")
	)
	(segment
		(start 136.409176 -17.64792)
		(end 133.035802 -21.021294)
		(width 0.127)
		(layer "In5.Cu")
		(net "BMC_ML_PWR_BLUE_LED")
	)
	(segment
		(start 68.8975 -150.368)
		(end 67.9704 -150.368)
		(width 0.127)
		(layer "F.Cu")
		(net "U30_Q1")
	)
	(segment
		(start 70.8406 -152.3111)
		(end 68.8975 -150.368)
		(width 0.127)
		(layer "F.Cu")
		(net "U30_Q1")
	)
	(segment
		(start 70.8406 -153.0858)
		(end 70.8406 -152.3111)
		(width 0.127)
		(layer "F.Cu")
		(net "U30_Q1")
	)
	(segment
		(start 60.5028 -133.428232)
		(end 58.929524 -135.001508)
		(width 0.127)
		(layer "F.Cu")
		(net "TP_BMC_EXT2_LED_B")
	)
	(segment
		(start 58.648092 -135.001508)
		(end 57.94502 -135.70458)
		(width 0.127)
		(layer "F.Cu")
		(net "TP_BMC_EXT2_LED_B")
	)
	(segment
		(start 58.929524 -135.001508)
		(end 58.648092 -135.001508)
		(width 0.127)
		(layer "F.Cu")
		(net "TP_BMC_EXT2_LED_B")
	)
	(segment
		(start 57.94502 -136.35482)
		(end 56.099964 -138.199876)
		(width 0.127)
		(layer "F.Cu")
		(net "TP_BMC_EXT2_LED_B")
	)
	(segment
		(start 60.5028 -133.2484)
		(end 60.5028 -133.428232)
		(width 0.127)
		(layer "F.Cu")
		(net "TP_BMC_EXT2_LED_B")
	)
	(segment
		(start 57.94502 -135.70458)
		(end 57.94502 -136.35482)
		(width 0.127)
		(layer "F.Cu")
		(net "TP_BMC_EXT2_LED_B")
	)
	(segment
		(start 52.899818 -139.800076)
		(end 53.299868 -139.400026)
		(width 0.127)
		(layer "F.Cu")
		(net "TP_BMC_EXT1_LED_B")
	)
	(via
		(at 53.299868 -139.400026)
		(size 0.4572)
		(drill 0.2032)
		(layers "F.Cu" "B.Cu")
		(net "TP_BMC_EXT1_LED_B")
	)
	(segment
		(start 55.1688 -138.206226)
		(end 55.169308 -138.20648)
		(width 0.127)
		(layer "B.Cu")
		(net "TP_BMC_EXT1_LED_B")
	)
	(segment
		(start 53.299868 -139.400026)
		(end 53.380132 -139.400026)
		(width 0.127)
		(layer "B.Cu")
		(net "TP_BMC_EXT1_LED_B")
	)
	(segment
		(start 57.82056 -136.960102)
		(end 58.746898 -136.960102)
		(width 0.127)
		(layer "B.Cu")
		(net "TP_BMC_EXT1_LED_B")
	)
	(segment
		(start 59.69 -134.9248)
		(end 60.7568 -133.858)
		(width 0.127)
		(layer "B.Cu")
		(net "TP_BMC_EXT1_LED_B")
	)
	(segment
		(start 58.746898 -136.960102)
		(end 59.69 -136.017)
		(width 0.127)
		(layer "B.Cu")
		(net "TP_BMC_EXT1_LED_B")
	)
	(segment
		(start 54.736746 -138.206226)
		(end 55.1688 -138.206226)
		(width 0.127)
		(layer "B.Cu")
		(net "TP_BMC_EXT1_LED_B")
	)
	(segment
		(start 57.392062 -137.3886)
		(end 57.82056 -136.960102)
		(width 0.127)
		(layer "B.Cu")
		(net "TP_BMC_EXT1_LED_B")
	)
	(segment
		(start 55.169308 -138.20648)
		(end 55.987188 -137.3886)
		(width 0.127)
		(layer "B.Cu")
		(net "TP_BMC_EXT1_LED_B")
	)
	(segment
		(start 54.493668 -138.81735)
		(end 54.493668 -138.449304)
		(width 0.127)
		(layer "B.Cu")
		(net "TP_BMC_EXT1_LED_B")
	)
	(segment
		(start 54.304692 -139.006326)
		(end 54.493668 -138.81735)
		(width 0.127)
		(layer "B.Cu")
		(net "TP_BMC_EXT1_LED_B")
	)
	(segment
		(start 53.380132 -139.400026)
		(end 53.773832 -139.006326)
		(width 0.127)
		(layer "B.Cu")
		(net "TP_BMC_EXT1_LED_B")
	)
	(segment
		(start 53.773832 -139.006326)
		(end 54.304692 -139.006326)
		(width 0.127)
		(layer "B.Cu")
		(net "TP_BMC_EXT1_LED_B")
	)
	(segment
		(start 55.987188 -137.3886)
		(end 57.392062 -137.3886)
		(width 0.127)
		(layer "B.Cu")
		(net "TP_BMC_EXT1_LED_B")
	)
	(segment
		(start 59.69 -136.017)
		(end 59.69 -134.9248)
		(width 0.127)
		(layer "B.Cu")
		(net "TP_BMC_EXT1_LED_B")
	)
	(segment
		(start 54.493668 -138.449304)
		(end 54.736746 -138.206226)
		(width 0.127)
		(layer "B.Cu")
		(net "TP_BMC_EXT1_LED_B")
	)
	(segment
		(start 145.6944 -15.96009)
		(end 145.6944 -17.10182)
		(width 0.127)
		(layer "F.Cu")
		(net "EXT2_LED_YELLOW_G1")
	)
	(segment
		(start 145.988786 -17.396206)
		(end 146.9136 -18.32102)
		(width 0.127)
		(layer "F.Cu")
		(net "EXT2_LED_YELLOW_G1")
	)
	(segment
		(start 145.6944 -17.10182)
		(end 145.988786 -17.396206)
		(width 0.127)
		(layer "F.Cu")
		(net "EXT2_LED_YELLOW_G1")
	)
	(segment
		(start 146.9136 -18.32102)
		(end 146.9136 -18.923)
		(width 0.127)
		(layer "F.Cu")
		(net "EXT2_LED_YELLOW_G1")
	)
	(via
		(at 145.988786 -17.396206)
		(size 0.6604)
		(drill 0.3302)
		(layers "F.Cu" "B.Cu")
		(net "EXT2_LED_YELLOW_G1")
	)
	(via
		(at 146.9136 -18.923)
		(size 0.508)
		(drill 0.254)
		(layers "F.Cu" "B.Cu")
		(net "EXT2_LED_YELLOW_G1")
	)
	(segment
		(start 147.3835 -18.4531)
		(end 146.9136 -18.923)
		(width 0.127)
		(layer "B.Cu")
		(net "EXT2_LED_YELLOW_G1")
	)
	(segment
		(start 147.3835 -17.79524)
		(end 147.3835 -18.4531)
		(width 0.127)
		(layer "B.Cu")
		(net "EXT2_LED_YELLOW_G1")
	)
	(segment
		(start 146.34464 -14.65834)
		(end 146.61642 -14.93012)
		(width 0.254)
		(layer "F.Cu")
		(net "EXT2_LED_YELLOW_D1")
	)
	(segment
		(start 146.61642 -14.93012)
		(end 147.85086 -14.93012)
		(width 0.254)
		(layer "F.Cu")
		(net "EXT2_LED_YELLOW_D1")
	)
	(segment
		(start 147.85086 -13.88872)
		(end 147.85086 -14.93012)
		(width 0.254)
		(layer "F.Cu")
		(net "EXT2_LED_YELLOW_D1")
	)
	(segment
		(start 146.34464 -13.91031)
		(end 146.34464 -14.65834)
		(width 0.254)
		(layer "F.Cu")
		(net "EXT2_LED_YELLOW_D1")
	)
	(via
		(at 147.85086 -14.93012)
		(size 0.6604)
		(drill 0.3302)
		(layers "F.Cu" "B.Cu")
		(net "EXT2_LED_YELLOW_D1")
	)
	(segment
		(start 197.80504 -31.2801)
		(end 197.85965 -31.33471)
		(width 0.127)
		(layer "F.Cu")
		(net "EXT2_LED_BLUE_G2")
	)
	(segment
		(start 199.176894 -31.33471)
		(end 199.176894 -30.235906)
		(width 0.127)
		(layer "F.Cu")
		(net "EXT2_LED_BLUE_G2")
	)
	(segment
		(start 199.176894 -30.235906)
		(end 199.5424 -29.8704)
		(width 0.127)
		(layer "F.Cu")
		(net "EXT2_LED_BLUE_G2")
	)
	(segment
		(start 197.3199 -29.2227)
		(end 197.3199 -30.79496)
		(width 0.127)
		(layer "F.Cu")
		(net "EXT2_LED_BLUE_G2")
	)
	(segment
		(start 145.6944 -13.91031)
		(end 145.6944 -12.6365)
		(width 0.127)
		(layer "F.Cu")
		(net "EXT2_LED_BLUE_G2")
	)
	(segment
		(start 197.85965 -31.33471)
		(end 199.176894 -31.33471)
		(width 0.127)
		(layer "F.Cu")
		(net "EXT2_LED_BLUE_G2")
	)
	(segment
		(start 197.3199 -30.79496)
		(end 197.80504 -31.2801)
		(width 0.127)
		(layer "F.Cu")
		(net "EXT2_LED_BLUE_G2")
	)
	(via
		(at 197.80504 -31.2801)
		(size 0.6604)
		(drill 0.3302)
		(layers "F.Cu" "B.Cu")
		(net "EXT2_LED_BLUE_G2")
	)
	(via
		(at 197.3199 -29.2227)
		(size 0.508)
		(drill 0.254)
		(layers "F.Cu" "B.Cu")
		(net "EXT2_LED_BLUE_G2")
	)
	(via
		(at 145.6944 -12.6365)
		(size 0.508)
		(drill 0.254)
		(layers "F.Cu" "B.Cu")
		(net "EXT2_LED_BLUE_G2")
	)
	(segment
		(start 145.808192 -12.522708)
		(end 154.46502 -12.522708)
		(width 0.127)
		(layer "In5.Cu")
		(net "EXT2_LED_BLUE_G2")
	)
	(segment
		(start 191.9224 -16.740378)
		(end 196.3039 -21.121878)
		(width 0.127)
		(layer "In5.Cu")
		(net "EXT2_LED_BLUE_G2")
	)
	(segment
		(start 196.3039 -21.121878)
		(end 196.3039 -24.214582)
		(width 0.127)
		(layer "In5.Cu")
		(net "EXT2_LED_BLUE_G2")
	)
	(segment
		(start 183.17591 -11.350244)
		(end 188.566044 -16.740378)
		(width 0.127)
		(layer "In5.Cu")
		(net "EXT2_LED_BLUE_G2")
	)
	(segment
		(start 197.3199 -27.11196)
		(end 197.3199 -29.2227)
		(width 0.127)
		(layer "In5.Cu")
		(net "EXT2_LED_BLUE_G2")
	)
	(segment
		(start 145.6944 -12.6365)
		(end 145.808192 -12.522708)
		(width 0.127)
		(layer "In5.Cu")
		(net "EXT2_LED_BLUE_G2")
	)
	(segment
		(start 154.46502 -12.522708)
		(end 155.637484 -11.350244)
		(width 0.127)
		(layer "In5.Cu")
		(net "EXT2_LED_BLUE_G2")
	)
	(segment
		(start 155.637484 -11.350244)
		(end 183.17591 -11.350244)
		(width 0.127)
		(layer "In5.Cu")
		(net "EXT2_LED_BLUE_G2")
	)
	(segment
		(start 195.9229 -24.595582)
		(end 195.9229 -25.71496)
		(width 0.127)
		(layer "In5.Cu")
		(net "EXT2_LED_BLUE_G2")
	)
	(segment
		(start 196.3039 -24.214582)
		(end 195.9229 -24.595582)
		(width 0.127)
		(layer "In5.Cu")
		(net "EXT2_LED_BLUE_G2")
	)
	(segment
		(start 188.566044 -16.740378)
		(end 191.9224 -16.740378)
		(width 0.127)
		(layer "In5.Cu")
		(net "EXT2_LED_BLUE_G2")
	)
	(segment
		(start 195.9229 -25.71496)
		(end 197.3199 -27.11196)
		(width 0.127)
		(layer "In5.Cu")
		(net "EXT2_LED_BLUE_G2")
	)
	(segment
		(start 196.2912 -27.3558)
		(end 196.9008 -27.9654)
		(width 0.127)
		(layer "F.Cu")
		(net "EXT2_LED_BLUE_G_Q27")
	)
	(segment
		(start 197.1802 -27.9654)
		(end 198.55815 -27.9654)
		(width 0.127)
		(layer "F.Cu")
		(net "EXT2_LED_BLUE_G_Q27")
	)
	(segment
		(start 196.2912 -27.3177)
		(end 196.2912 -27.3558)
		(width 0.127)
		(layer "F.Cu")
		(net "EXT2_LED_BLUE_G_Q27")
	)
	(segment
		(start 196.9008 -27.9654)
		(end 197.1802 -27.9654)
		(width 0.127)
		(layer "F.Cu")
		(net "EXT2_LED_BLUE_G_Q27")
	)
	(via
		(at 197.1802 -27.9654)
		(size 0.6604)
		(drill 0.3302)
		(layers "F.Cu" "B.Cu")
		(net "EXT2_LED_BLUE_G_Q27")
	)
	(via
		(at 138.9634 -20.2946)
		(size 0.508)
		(drill 0.254)
		(layers "F.Cu" "B.Cu")
		(net "EXT2_LED_BLUE_G_Q27")
	)
	(via
		(at 196.2912 -27.3177)
		(size 0.508)
		(drill 0.254)
		(layers "F.Cu" "B.Cu")
		(net "EXT2_LED_BLUE_G_Q27")
	)
	(segment
		(start 138.9634 -20.300188)
		(end 139.464288 -19.7993)
		(width 0.127)
		(layer "B.Cu")
		(net "EXT2_LED_BLUE_G_Q27")
	)
	(segment
		(start 141.6685 -19.4691)
		(end 141.6685 -19.06524)
		(width 0.127)
		(layer "B.Cu")
		(net "EXT2_LED_BLUE_G_Q27")
	)
	(segment
		(start 141.3383 -19.7993)
		(end 141.6685 -19.4691)
		(width 0.127)
		(layer "B.Cu")
		(net "EXT2_LED_BLUE_G_Q27")
	)
	(segment
		(start 139.464288 -19.7993)
		(end 141.3383 -19.7993)
		(width 0.127)
		(layer "B.Cu")
		(net "EXT2_LED_BLUE_G_Q27")
	)
	(segment
		(start 138.9634 -20.2946)
		(end 138.9634 -20.300188)
		(width 0.127)
		(layer "B.Cu")
		(net "EXT2_LED_BLUE_G_Q27")
	)
	(segment
		(start 195.5419 -26.5684)
		(end 195.5419 -24.437594)
		(width 0.127)
		(layer "In5.Cu")
		(net "EXT2_LED_BLUE_G_Q27")
	)
	(segment
		(start 196.2912 -27.3177)
		(end 195.5419 -26.5684)
		(width 0.127)
		(layer "In5.Cu")
		(net "EXT2_LED_BLUE_G_Q27")
	)
	(segment
		(start 152.3619 -15.5448)
		(end 142.8242 -15.5448)
		(width 0.127)
		(layer "In5.Cu")
		(net "EXT2_LED_BLUE_G_Q27")
	)
	(segment
		(start 156.175456 -11.731244)
		(end 152.3619 -15.5448)
		(width 0.127)
		(layer "In5.Cu")
		(net "EXT2_LED_BLUE_G_Q27")
	)
	(segment
		(start 140.462 -18.796)
		(end 138.9634 -20.2946)
		(width 0.127)
		(layer "In5.Cu")
		(net "EXT2_LED_BLUE_G_Q27")
	)
	(segment
		(start 192.778634 -18.1356)
		(end 189.2046 -18.1356)
		(width 0.127)
		(layer "In5.Cu")
		(net "EXT2_LED_BLUE_G_Q27")
	)
	(segment
		(start 195.5419 -24.437594)
		(end 195.9229 -24.056594)
		(width 0.127)
		(layer "In5.Cu")
		(net "EXT2_LED_BLUE_G_Q27")
	)
	(segment
		(start 140.462 -17.907)
		(end 140.462 -18.796)
		(width 0.127)
		(layer "In5.Cu")
		(net "EXT2_LED_BLUE_G_Q27")
	)
	(segment
		(start 142.8242 -15.5448)
		(end 140.462 -17.907)
		(width 0.127)
		(layer "In5.Cu")
		(net "EXT2_LED_BLUE_G_Q27")
	)
	(segment
		(start 195.9229 -21.279866)
		(end 192.778634 -18.1356)
		(width 0.127)
		(layer "In5.Cu")
		(net "EXT2_LED_BLUE_G_Q27")
	)
	(segment
		(start 195.9229 -24.056594)
		(end 195.9229 -21.279866)
		(width 0.127)
		(layer "In5.Cu")
		(net "EXT2_LED_BLUE_G_Q27")
	)
	(segment
		(start 182.800244 -11.731244)
		(end 156.175456 -11.731244)
		(width 0.127)
		(layer "In5.Cu")
		(net "EXT2_LED_BLUE_G_Q27")
	)
	(segment
		(start 189.2046 -18.1356)
		(end 182.800244 -11.731244)
		(width 0.127)
		(layer "In5.Cu")
		(net "EXT2_LED_BLUE_G_Q27")
	)
	(segment
		(start 193.4464 -18.0086)
		(end 193.4464 -17.3482)
		(width 0.127)
		(layer "F.Cu")
		(net "EXT1_LED_YELLOW_G1")
	)
	(segment
		(start 193.7258 -14.75232)
		(end 193.7258 -16.45666)
		(width 0.127)
		(layer "F.Cu")
		(net "EXT1_LED_YELLOW_G1")
	)
	(segment
		(start 194.80276 -18.3515)
		(end 193.7893 -18.3515)
		(width 0.127)
		(layer "F.Cu")
		(net "EXT1_LED_YELLOW_G1")
	)
	(segment
		(start 193.7893 -18.3515)
		(end 193.4464 -18.0086)
		(width 0.127)
		(layer "F.Cu")
		(net "EXT1_LED_YELLOW_G1")
	)
	(segment
		(start 193.4464 -16.73606)
		(end 193.4464 -17.3482)
		(width 0.127)
		(layer "F.Cu")
		(net "EXT1_LED_YELLOW_G1")
	)
	(segment
		(start 193.7258 -16.45666)
		(end 193.4464 -16.73606)
		(width 0.127)
		(layer "F.Cu")
		(net "EXT1_LED_YELLOW_G1")
	)
	(via
		(at 193.4464 -17.3482)
		(size 0.6604)
		(drill 0.3302)
		(layers "F.Cu" "B.Cu")
		(net "EXT1_LED_YELLOW_G1")
	)
	(segment
		(start 194.701668 -11.195304)
		(end 194.37604 -11.520932)
		(width 0.254)
		(layer "F.Cu")
		(net "EXT1_LED_YELLOW_D1")
	)
	(segment
		(start 194.75577 -10.09269)
		(end 194.75577 -11.141202)
		(width 0.254)
		(layer "F.Cu")
		(net "EXT1_LED_YELLOW_D1")
	)
	(segment
		(start 194.75577 -11.141202)
		(end 194.701668 -11.195304)
		(width 0.254)
		(layer "F.Cu")
		(net "EXT1_LED_YELLOW_D1")
	)
	(segment
		(start 194.37604 -11.520932)
		(end 194.37604 -12.70254)
		(width 0.254)
		(layer "F.Cu")
		(net "EXT1_LED_YELLOW_D1")
	)
	(via
		(at 194.701668 -11.195304)
		(size 0.6604)
		(drill 0.3302)
		(layers "F.Cu" "B.Cu")
		(net "EXT1_LED_YELLOW_D1")
	)
	(segment
		(start 199.8345 -23.7617)
		(end 199.2376 -24.3586)
		(width 0.127)
		(layer "F.Cu")
		(net "EXT1_LED_BLUE_G2")
	)
	(segment
		(start 193.74231 -10.7188)
		(end 193.74231 -12.453874)
		(width 0.127)
		(layer "F.Cu")
		(net "EXT1_LED_BLUE_G2")
	)
	(segment
		(start 199.4281 -25.4)
		(end 199.2376 -25.2095)
		(width 0.127)
		(layer "F.Cu")
		(net "EXT1_LED_BLUE_G2")
	)
	(segment
		(start 200.406 -25.5016)
		(end 199.8599 -25.5016)
		(width 0.127)
		(layer "F.Cu")
		(net "EXT1_LED_BLUE_G2")
	)
	(segment
		(start 199.8599 -25.5016)
		(end 199.7583 -25.4)
		(width 0.127)
		(layer "F.Cu")
		(net "EXT1_LED_BLUE_G2")
	)
	(segment
		(start 193.74231 -12.453874)
		(end 193.7258 -12.470384)
		(width 0.127)
		(layer "F.Cu")
		(net "EXT1_LED_BLUE_G2")
	)
	(segment
		(start 201.0918 -25.5016)
		(end 201.3204 -25.7302)
		(width 0.127)
		(layer "F.Cu")
		(net "EXT1_LED_BLUE_G2")
	)
	(segment
		(start 199.7583 -25.4)
		(end 199.4281 -25.4)
		(width 0.127)
		(layer "F.Cu")
		(net "EXT1_LED_BLUE_G2")
	)
	(segment
		(start 193.7258 -12.470384)
		(end 193.7258 -12.70254)
		(width 0.127)
		(layer "F.Cu")
		(net "EXT1_LED_BLUE_G2")
	)
	(segment
		(start 200.406 -25.5016)
		(end 201.0918 -25.5016)
		(width 0.127)
		(layer "F.Cu")
		(net "EXT1_LED_BLUE_G2")
	)
	(segment
		(start 199.2376 -24.3586)
		(end 199.2376 -25.2095)
		(width 0.127)
		(layer "F.Cu")
		(net "EXT1_LED_BLUE_G2")
	)
	(via
		(at 193.74231 -10.7188)
		(size 0.508)
		(drill 0.254)
		(layers "F.Cu" "B.Cu")
		(net "EXT1_LED_BLUE_G2")
	)
	(via
		(at 200.406 -25.5016)
		(size 0.6604)
		(drill 0.3302)
		(layers "F.Cu" "B.Cu")
		(net "EXT1_LED_BLUE_G2")
	)
	(via
		(at 201.3204 -25.7302)
		(size 0.508)
		(drill 0.254)
		(layers "F.Cu" "B.Cu")
		(net "EXT1_LED_BLUE_G2")
	)
	(segment
		(start 193.74231 -10.7188)
		(end 198.1708 -10.7188)
		(width 0.127)
		(layer "In2.Cu")
		(net "EXT1_LED_BLUE_G2")
	)
	(segment
		(start 198.1708 -10.7188)
		(end 199.2249 -11.7729)
		(width 0.127)
		(layer "In2.Cu")
		(net "EXT1_LED_BLUE_G2")
	)
	(segment
		(start 201.3204 -23.7998)
		(end 201.3204 -25.7302)
		(width 0.127)
		(layer "In2.Cu")
		(net "EXT1_LED_BLUE_G2")
	)
	(segment
		(start 199.2249 -21.7043)
		(end 201.3204 -23.7998)
		(width 0.127)
		(layer "In2.Cu")
		(net "EXT1_LED_BLUE_G2")
	)
	(segment
		(start 199.2249 -11.7729)
		(end 199.2249 -21.7043)
		(width 0.127)
		(layer "In2.Cu")
		(net "EXT1_LED_BLUE_G2")
	)
	(segment
		(start 197.2818 -23.424896)
		(end 197.1548 -23.551896)
		(width 0.127)
		(layer "F.Cu")
		(net "EXT1_LED_BLUE_G_Q24")
	)
	(segment
		(start 195.7451 -26.9875)
		(end 197.1548 -25.5778)
		(width 0.127)
		(layer "F.Cu")
		(net "EXT1_LED_BLUE_G_Q24")
	)
	(segment
		(start 197.282054 -23.424896)
		(end 197.2818 -23.424896)
		(width 0.127)
		(layer "F.Cu")
		(net "EXT1_LED_BLUE_G_Q24")
	)
	(segment
		(start 198.85025 -21.8567)
		(end 197.282054 -23.424896)
		(width 0.127)
		(layer "F.Cu")
		(net "EXT1_LED_BLUE_G_Q24")
	)
	(segment
		(start 195.03644 -26.9875)
		(end 195.7451 -26.9875)
		(width 0.127)
		(layer "F.Cu")
		(net "EXT1_LED_BLUE_G_Q24")
	)
	(segment
		(start 197.1548 -25.5778)
		(end 197.1548 -23.6347)
		(width 0.127)
		(layer "F.Cu")
		(net "EXT1_LED_BLUE_G_Q24")
	)
	(segment
		(start 197.1548 -23.551896)
		(end 197.1548 -23.6347)
		(width 0.127)
		(layer "F.Cu")
		(net "EXT1_LED_BLUE_G_Q24")
	)
	(via
		(at 197.1548 -23.6347)
		(size 0.6604)
		(drill 0.3302)
		(layers "F.Cu" "B.Cu")
		(net "EXT1_LED_BLUE_G_Q24")
	)
	(segment
		(start 49.299876 -139.444476)
		(end 49.655476 -139.800076)
		(width 0.127)
		(layer "F.Cu")
		(net "SCC_RMT_FULLPWR_EN")
	)
	(segment
		(start 49.022 -128.975866)
		(end 49.626266 -129.580132)
		(width 0.127)
		(layer "F.Cu")
		(net "SCC_RMT_FULLPWR_EN")
	)
	(segment
		(start 49.655476 -139.800076)
		(end 49.699926 -139.800076)
		(width 0.127)
		(layer "F.Cu")
		(net "SCC_RMT_FULLPWR_EN")
	)
	(segment
		(start 49.022 -128.6383)
		(end 49.022 -128.975866)
		(width 0.127)
		(layer "F.Cu")
		(net "SCC_RMT_FULLPWR_EN")
	)
	(segment
		(start 49.299876 -139.40028)
		(end 49.299876 -139.444476)
		(width 0.127)
		(layer "F.Cu")
		(net "SCC_RMT_FULLPWR_EN")
	)
	(via
		(at 49.626266 -129.580132)
		(size 0.508)
		(drill 0.254)
		(layers "F.Cu" "B.Cu")
		(net "SCC_RMT_FULLPWR_EN")
	)
	(via
		(at 49.299876 -139.40028)
		(size 0.4572)
		(drill 0.2032)
		(layers "F.Cu" "B.Cu")
		(net "SCC_RMT_FULLPWR_EN")
	)
	(segment
		(start 50.474626 -136.84504)
		(end 50.474626 -138.75512)
		(width 0.0889)
		(layer "In2.Cu")
		(net "SCC_RMT_FULLPWR_EN")
	)
	(segment
		(start 50.17135 -136.541764)
		(end 50.474626 -136.84504)
		(width 0.0889)
		(layer "In2.Cu")
		(net "SCC_RMT_FULLPWR_EN")
	)
	(segment
		(start 50.037746 -129.991612)
		(end 50.037746 -136.40816)
		(width 0.127)
		(layer "In2.Cu")
		(net "SCC_RMT_FULLPWR_EN")
	)
	(segment
		(start 49.829466 -139.40028)
		(end 49.299876 -139.40028)
		(width 0.0889)
		(layer "In2.Cu")
		(net "SCC_RMT_FULLPWR_EN")
	)
	(segment
		(start 50.474626 -138.75512)
		(end 49.829466 -139.40028)
		(width 0.0889)
		(layer "In2.Cu")
		(net "SCC_RMT_FULLPWR_EN")
	)
	(segment
		(start 50.037746 -136.40816)
		(end 50.17135 -136.541764)
		(width 0.127)
		(layer "In2.Cu")
		(net "SCC_RMT_FULLPWR_EN")
	)
	(segment
		(start 49.626266 -129.580132)
		(end 50.037746 -129.991612)
		(width 0.127)
		(layer "In2.Cu")
		(net "SCC_RMT_FULLPWR_EN")
	)
	(segment
		(start 49.699926 -138.999976)
		(end 50.099976 -138.599926)
		(width 0.127)
		(layer "F.Cu")
		(net "SCC_LOC_FULLPWR_EN")
	)
	(via
		(at 49.6062 -126.7206)
		(size 0.508)
		(drill 0.254)
		(layers "F.Cu" "B.Cu")
		(net "SCC_LOC_FULLPWR_EN")
	)
	(via
		(at 50.099976 -138.599926)
		(size 0.4572)
		(drill 0.2032)
		(layers "F.Cu" "B.Cu")
		(net "SCC_LOC_FULLPWR_EN")
	)
	(via
		(at 49.7586 -127.9144)
		(size 0.6096)
		(drill 0.3048)
		(layers "F.Cu" "B.Cu")
		(net "SCC_LOC_FULLPWR_EN")
	)
	(segment
		(start 49.418494 -128.660906)
		(end 49.7586 -128.3208)
		(width 0.127)
		(layer "B.Cu")
		(net "SCC_LOC_FULLPWR_EN")
	)
	(segment
		(start 48.734726 -128.660906)
		(end 49.418494 -128.660906)
		(width 0.127)
		(layer "B.Cu")
		(net "SCC_LOC_FULLPWR_EN")
	)
	(segment
		(start 49.7586 -126.873)
		(end 49.7586 -127.9144)
		(width 0.127)
		(layer "B.Cu")
		(net "SCC_LOC_FULLPWR_EN")
	)
	(segment
		(start 49.7586 -128.3208)
		(end 49.7586 -127.9144)
		(width 0.127)
		(layer "B.Cu")
		(net "SCC_LOC_FULLPWR_EN")
	)
	(segment
		(start 49.6062 -126.7206)
		(end 49.7586 -126.873)
		(width 0.127)
		(layer "B.Cu")
		(net "SCC_LOC_FULLPWR_EN")
	)
	(segment
		(start 49.1871 -134.641336)
		(end 49.2506 -134.704836)
		(width 0.127)
		(layer "In2.Cu")
		(net "SCC_LOC_FULLPWR_EN")
	)
	(segment
		(start 49.6062 -126.7206)
		(end 49.6062 -128.2446)
		(width 0.127)
		(layer "In2.Cu")
		(net "SCC_LOC_FULLPWR_EN")
	)
	(segment
		(start 49.2506 -134.230364)
		(end 49.1871 -134.293864)
		(width 0.127)
		(layer "In2.Cu")
		(net "SCC_LOC_FULLPWR_EN")
	)
	(segment
		(start 49.2506 -130.840226)
		(end 49.2506 -134.230364)
		(width 0.127)
		(layer "In2.Cu")
		(net "SCC_LOC_FULLPWR_EN")
	)
	(segment
		(start 49.6062 -128.2446)
		(end 49.0982 -128.7526)
		(width 0.127)
		(layer "In2.Cu")
		(net "SCC_LOC_FULLPWR_EN")
	)
	(segment
		(start 49.693576 -138.193526)
		(end 50.099976 -138.599926)
		(width 0.127)
		(layer "In2.Cu")
		(net "SCC_LOC_FULLPWR_EN")
	)
	(segment
		(start 49.0982 -130.297682)
		(end 49.097946 -130.297936)
		(width 0.127)
		(layer "In2.Cu")
		(net "SCC_LOC_FULLPWR_EN")
	)
	(segment
		(start 49.1871 -134.293864)
		(end 49.1871 -134.641336)
		(width 0.127)
		(layer "In2.Cu")
		(net "SCC_LOC_FULLPWR_EN")
	)
	(segment
		(start 49.693576 -136.459976)
		(end 49.693576 -138.193526)
		(width 0.127)
		(layer "In2.Cu")
		(net "SCC_LOC_FULLPWR_EN")
	)
	(segment
		(start 49.0982 -128.7526)
		(end 49.0982 -130.297682)
		(width 0.127)
		(layer "In2.Cu")
		(net "SCC_LOC_FULLPWR_EN")
	)
	(segment
		(start 49.097946 -130.297936)
		(end 49.097946 -130.687572)
		(width 0.127)
		(layer "In2.Cu")
		(net "SCC_LOC_FULLPWR_EN")
	)
	(segment
		(start 49.2506 -136.017)
		(end 49.693576 -136.459976)
		(width 0.127)
		(layer "In2.Cu")
		(net "SCC_LOC_FULLPWR_EN")
	)
	(segment
		(start 49.097946 -130.687572)
		(end 49.2506 -130.840226)
		(width 0.127)
		(layer "In2.Cu")
		(net "SCC_LOC_FULLPWR_EN")
	)
	(segment
		(start 49.2506 -134.704836)
		(end 49.2506 -136.017)
		(width 0.127)
		(layer "In2.Cu")
		(net "SCC_LOC_FULLPWR_EN")
	)
	(via
		(at 122.3772 -18.0848)
		(size 0.508)
		(drill 0.254)
		(layers "F.Cu" "B.Cu")
		(net "IOM_MATED_N")
	)
	(via
		(at 122.197622 -17.187926)
		(size 0.6096)
		(drill 0.3048)
		(layers "F.Cu" "B.Cu")
		(net "IOM_MATED_N")
	)
	(segment
		(start 122.1105 -17.100804)
		(end 122.1105 -16.2052)
		(width 0.127)
		(layer "B.Cu")
		(net "IOM_MATED_N")
	)
	(segment
		(start 122.1994 -17.189704)
		(end 122.197622 -17.187926)
		(width 0.127)
		(layer "B.Cu")
		(net "IOM_MATED_N")
	)
	(segment
		(start 121.11355 -15.9766)
		(end 120.4087 -16.68145)
		(width 0.127)
		(layer "B.Cu")
		(net "IOM_MATED_N")
	)
	(segment
		(start 122.3772 -18.0848)
		(end 122.1994 -17.907)
		(width 0.127)
		(layer "B.Cu")
		(net "IOM_MATED_N")
	)
	(segment
		(start 122.1105 -16.2052)
		(end 121.8819 -15.9766)
		(width 0.127)
		(layer "B.Cu")
		(net "IOM_MATED_N")
	)
	(segment
		(start 121.8819 -15.9766)
		(end 121.11355 -15.9766)
		(width 0.127)
		(layer "B.Cu")
		(net "IOM_MATED_N")
	)
	(segment
		(start 122.1994 -17.907)
		(end 122.1994 -17.189704)
		(width 0.127)
		(layer "B.Cu")
		(net "IOM_MATED_N")
	)
	(segment
		(start 122.197622 -17.187926)
		(end 122.1105 -17.100804)
		(width 0.127)
		(layer "B.Cu")
		(net "IOM_MATED_N")
	)
	(segment
		(start 122.3772 -18.0848)
		(end 122.3772 -18.4912)
		(width 0.127)
		(layer "In2.Cu")
		(net "IOM_MATED_N")
	)
	(segment
		(start 140.223494 -39.52367)
		(end 141.299946 -40.600122)
		(width 0.127)
		(layer "In2.Cu")
		(net "IOM_MATED_N")
	)
	(segment
		(start 124.206 -20.32)
		(end 127.143764 -20.32)
		(width 0.127)
		(layer "In2.Cu")
		(net "IOM_MATED_N")
	)
	(segment
		(start 131.095242 -24.271478)
		(end 133.938518 -24.271478)
		(width 0.127)
		(layer "In2.Cu")
		(net "IOM_MATED_N")
	)
	(segment
		(start 140.223494 -30.556454)
		(end 140.223494 -39.52367)
		(width 0.127)
		(layer "In2.Cu")
		(net "IOM_MATED_N")
	)
	(segment
		(start 133.938518 -24.271478)
		(end 140.223494 -30.556454)
		(width 0.127)
		(layer "In2.Cu")
		(net "IOM_MATED_N")
	)
	(segment
		(start 122.3772 -18.4912)
		(end 124.206 -20.32)
		(width 0.127)
		(layer "In2.Cu")
		(net "IOM_MATED_N")
	)
	(segment
		(start 127.143764 -20.32)
		(end 131.095242 -24.271478)
		(width 0.127)
		(layer "In2.Cu")
		(net "IOM_MATED_N")
	)
	(via
		(at 116.7638 -16.764)
		(size 0.6096)
		(drill 0.3048)
		(layers "F.Cu" "B.Cu")
		(net "IOM_ADM1278_EN")
	)
	(segment
		(start 121.4628 -14.9606)
		(end 121.8819 -14.9606)
		(width 0.127)
		(layer "B.Cu")
		(net "IOM_ADM1278_EN")
	)
	(segment
		(start 116.2558 -16.764)
		(end 116.7638 -16.764)
		(width 0.127)
		(layer "B.Cu")
		(net "IOM_ADM1278_EN")
	)
	(segment
		(start 115.9383 -15.7226)
		(end 115.9383 -16.4465)
		(width 0.127)
		(layer "B.Cu")
		(net "IOM_ADM1278_EN")
	)
	(segment
		(start 115.9256 -14.6939)
		(end 115.9256 -15.7099)
		(width 0.127)
		(layer "B.Cu")
		(net "IOM_ADM1278_EN")
	)
	(segment
		(start 117.4369 -16.764)
		(end 118.5037 -15.6972)
		(width 0.127)
		(layer "B.Cu")
		(net "IOM_ADM1278_EN")
	)
	(segment
		(start 118.5037 -15.6972)
		(end 120.7262 -15.6972)
		(width 0.127)
		(layer "B.Cu")
		(net "IOM_ADM1278_EN")
	)
	(segment
		(start 116.7638 -16.764)
		(end 117.4369 -16.764)
		(width 0.127)
		(layer "B.Cu")
		(net "IOM_ADM1278_EN")
	)
	(segment
		(start 115.9383 -16.4465)
		(end 116.2558 -16.764)
		(width 0.127)
		(layer "B.Cu")
		(net "IOM_ADM1278_EN")
	)
	(segment
		(start 120.7262 -15.6972)
		(end 121.4628 -14.9606)
		(width 0.127)
		(layer "B.Cu")
		(net "IOM_ADM1278_EN")
	)
	(segment
		(start 115.9256 -15.7099)
		(end 115.9383 -15.7226)
		(width 0.127)
		(layer "B.Cu")
		(net "IOM_ADM1278_EN")
	)
	(via
		(at 79.8576 -128.4605)
		(size 0.508)
		(drill 0.254)
		(layers "F.Cu" "B.Cu")
		(net "BMC_TO_EXP_RESET_N")
	)
	(via
		(at 96.079818 -126.0094)
		(size 0.508)
		(drill 0.254)
		(layers "F.Cu" "B.Cu")
		(net "BMC_TO_EXP_RESET_N")
	)
	(segment
		(start 79.7941 -129.39776)
		(end 79.7941 -128.524)
		(width 0.127)
		(layer "B.Cu")
		(net "BMC_TO_EXP_RESET_N")
	)
	(segment
		(start 79.7941 -128.524)
		(end 79.8576 -128.4605)
		(width 0.127)
		(layer "B.Cu")
		(net "BMC_TO_EXP_RESET_N")
	)
	(segment
		(start 96.869504 -117.640608)
		(end 96.393 -118.117112)
		(width 0.127)
		(layer "In2.Cu")
		(net "BMC_TO_EXP_RESET_N")
	)
	(segment
		(start 98.250502 -83.713828)
		(end 98.250502 -112.305338)
		(width 0.127)
		(layer "In2.Cu")
		(net "BMC_TO_EXP_RESET_N")
	)
	(segment
		(start 96.197166 -121.086372)
		(end 96.197166 -125.892052)
		(width 0.127)
		(layer "In2.Cu")
		(net "BMC_TO_EXP_RESET_N")
	)
	(segment
		(start 117.243098 -43.05681)
		(end 117.243098 -30.069536)
		(width 0.127)
		(layer "In2.Cu")
		(net "BMC_TO_EXP_RESET_N")
	)
	(segment
		(start 96.869504 -113.686336)
		(end 96.869504 -117.640608)
		(width 0.127)
		(layer "In2.Cu")
		(net "BMC_TO_EXP_RESET_N")
	)
	(segment
		(start 117.827044 -29.48559)
		(end 117.827044 -27.974544)
		(width 0.127)
		(layer "In2.Cu")
		(net "BMC_TO_EXP_RESET_N")
	)
	(segment
		(start 117.827044 -27.974544)
		(end 115.973606 -26.121106)
		(width 0.127)
		(layer "In2.Cu")
		(net "BMC_TO_EXP_RESET_N")
	)
	(segment
		(start 98.596958 -83.367372)
		(end 98.250502 -83.713828)
		(width 0.127)
		(layer "In2.Cu")
		(net "BMC_TO_EXP_RESET_N")
	)
	(segment
		(start 98.250502 -112.305338)
		(end 96.869504 -113.686336)
		(width 0.127)
		(layer "In2.Cu")
		(net "BMC_TO_EXP_RESET_N")
	)
	(segment
		(start 98.596958 -43.546776)
		(end 98.596958 -83.367372)
		(width 0.127)
		(layer "In2.Cu")
		(net "BMC_TO_EXP_RESET_N")
	)
	(segment
		(start 115.973606 -26.121106)
		(end 104.712262 -26.121106)
		(width 0.127)
		(layer "In2.Cu")
		(net "BMC_TO_EXP_RESET_N")
	)
	(segment
		(start 99.895914 -30.937454)
		(end 99.895914 -42.24782)
		(width 0.127)
		(layer "In2.Cu")
		(net "BMC_TO_EXP_RESET_N")
	)
	(segment
		(start 96.393 -120.890538)
		(end 96.197166 -121.086372)
		(width 0.127)
		(layer "In2.Cu")
		(net "BMC_TO_EXP_RESET_N")
	)
	(segment
		(start 99.895914 -42.24782)
		(end 98.596958 -43.546776)
		(width 0.127)
		(layer "In2.Cu")
		(net "BMC_TO_EXP_RESET_N")
	)
	(segment
		(start 117.243098 -30.069536)
		(end 117.827044 -29.48559)
		(width 0.127)
		(layer "In2.Cu")
		(net "BMC_TO_EXP_RESET_N")
	)
	(segment
		(start 116.099844 -44.200064)
		(end 117.243098 -43.05681)
		(width 0.127)
		(layer "In2.Cu")
		(net "BMC_TO_EXP_RESET_N")
	)
	(segment
		(start 96.393 -118.117112)
		(end 96.393 -120.890538)
		(width 0.127)
		(layer "In2.Cu")
		(net "BMC_TO_EXP_RESET_N")
	)
	(segment
		(start 96.197166 -125.892052)
		(end 96.079818 -126.0094)
		(width 0.127)
		(layer "In2.Cu")
		(net "BMC_TO_EXP_RESET_N")
	)
	(segment
		(start 104.712262 -26.121106)
		(end 99.895914 -30.937454)
		(width 0.127)
		(layer "In2.Cu")
		(net "BMC_TO_EXP_RESET_N")
	)
	(segment
		(start 85.516212 -126.0094)
		(end 83.839812 -127.6858)
		(width 0.127)
		(layer "In5.Cu")
		(net "BMC_TO_EXP_RESET_N")
	)
	(segment
		(start 80.571086 -128.4605)
		(end 79.8576 -128.4605)
		(width 0.127)
		(layer "In5.Cu")
		(net "BMC_TO_EXP_RESET_N")
	)
	(segment
		(start 81.345786 -127.6858)
		(end 80.571086 -128.4605)
		(width 0.127)
		(layer "In5.Cu")
		(net "BMC_TO_EXP_RESET_N")
	)
	(segment
		(start 96.079818 -126.0094)
		(end 85.516212 -126.0094)
		(width 0.127)
		(layer "In5.Cu")
		(net "BMC_TO_EXP_RESET_N")
	)
	(segment
		(start 83.839812 -127.6858)
		(end 81.345786 -127.6858)
		(width 0.127)
		(layer "In5.Cu")
		(net "BMC_TO_EXP_RESET_N")
	)
	(segment
		(start 32.4104 -160.6042)
		(end 32.0421 -160.6042)
		(width 0.127)
		(layer "F.Cu")
		(net "IOM_TYPE3")
	)
	(segment
		(start 44.099988 -151.800306)
		(end 43.700192 -152.200102)
		(width 0.127)
		(layer "F.Cu")
		(net "IOM_TYPE3")
	)
	(segment
		(start 32.9692 -161.163)
		(end 32.4104 -160.6042)
		(width 0.127)
		(layer "F.Cu")
		(net "IOM_TYPE3")
	)
	(segment
		(start 32.0421 -161.6456)
		(end 32.0421 -160.6042)
		(width 0.127)
		(layer "F.Cu")
		(net "IOM_TYPE3")
	)
	(segment
		(start 44.099988 -151.800052)
		(end 44.099988 -151.800306)
		(width 0.127)
		(layer "F.Cu")
		(net "IOM_TYPE3")
	)
	(segment
		(start 32.995362 -161.163)
		(end 32.9692 -161.163)
		(width 0.127)
		(layer "F.Cu")
		(net "IOM_TYPE3")
	)
	(via
		(at 32.995362 -161.163)
		(size 0.508)
		(drill 0.254)
		(layers "F.Cu" "B.Cu")
		(net "IOM_TYPE3")
	)
	(via
		(at 43.700192 -152.200102)
		(size 0.4572)
		(drill 0.2032)
		(layers "F.Cu" "B.Cu")
		(net "IOM_TYPE3")
	)
	(segment
		(start 42.790618 -157.807406)
		(end 43.7134 -156.884624)
		(width 0.127)
		(layer "In2.Cu")
		(net "IOM_TYPE3")
	)
	(segment
		(start 43.85818 -156.211016)
		(end 43.85818 -152.35809)
		(width 0.127)
		(layer "In2.Cu")
		(net "IOM_TYPE3")
	)
	(segment
		(start 33.693862 -160.4645)
		(end 38.7985 -160.4645)
		(width 0.127)
		(layer "In2.Cu")
		(net "IOM_TYPE3")
	)
	(segment
		(start 32.995362 -161.163)
		(end 33.693862 -160.4645)
		(width 0.127)
		(layer "In2.Cu")
		(net "IOM_TYPE3")
	)
	(segment
		(start 43.7134 -156.884624)
		(end 43.7134 -156.355796)
		(width 0.127)
		(layer "In2.Cu")
		(net "IOM_TYPE3")
	)
	(segment
		(start 41.455594 -157.807406)
		(end 42.790618 -157.807406)
		(width 0.127)
		(layer "In2.Cu")
		(net "IOM_TYPE3")
	)
	(segment
		(start 43.85818 -152.35809)
		(end 43.700192 -152.200102)
		(width 0.127)
		(layer "In2.Cu")
		(net "IOM_TYPE3")
	)
	(segment
		(start 43.7134 -156.355796)
		(end 43.85818 -156.211016)
		(width 0.127)
		(layer "In2.Cu")
		(net "IOM_TYPE3")
	)
	(segment
		(start 38.7985 -160.4645)
		(end 41.455594 -157.807406)
		(width 0.127)
		(layer "In2.Cu")
		(net "IOM_TYPE3")
	)
	(segment
		(start 34.5694 -163.789614)
		(end 34.5694 -164.5793)
		(width 0.127)
		(layer "F.Cu")
		(net "IOM_TYPE2")
	)
	(segment
		(start 34.2138 -162.2044)
		(end 34.2138 -163.434014)
		(width 0.127)
		(layer "F.Cu")
		(net "IOM_TYPE2")
	)
	(segment
		(start 34.2138 -163.434014)
		(end 34.5694 -163.789614)
		(width 0.127)
		(layer "F.Cu")
		(net "IOM_TYPE2")
	)
	(segment
		(start 44.899834 -151.800052)
		(end 44.899834 -151.800306)
		(width 0.127)
		(layer "F.Cu")
		(net "IOM_TYPE2")
	)
	(segment
		(start 34.5694 -164.5793)
		(end 33.5534 -164.5793)
		(width 0.127)
		(layer "F.Cu")
		(net "IOM_TYPE2")
	)
	(segment
		(start 44.899834 -151.800306)
		(end 44.500038 -152.200102)
		(width 0.127)
		(layer "F.Cu")
		(net "IOM_TYPE2")
	)
	(via
		(at 34.2138 -162.2044)
		(size 0.508)
		(drill 0.254)
		(layers "F.Cu" "B.Cu")
		(net "IOM_TYPE2")
	)
	(via
		(at 44.500038 -152.200102)
		(size 0.4572)
		(drill 0.2032)
		(layers "F.Cu" "B.Cu")
		(net "IOM_TYPE2")
	)
	(via
		(at 34.2138 -163.434014)
		(size 0.6604)
		(drill 0.3302)
		(layers "F.Cu" "B.Cu")
		(net "IOM_TYPE2")
	)
	(segment
		(start 43.106594 -158.569406)
		(end 44.500038 -157.175962)
		(width 0.127)
		(layer "In2.Cu")
		(net "IOM_TYPE2")
	)
	(segment
		(start 44.500038 -157.175962)
		(end 44.500038 -152.200102)
		(width 0.127)
		(layer "In2.Cu")
		(net "IOM_TYPE2")
	)
	(segment
		(start 34.8234 -161.3408)
		(end 39.010082 -161.3408)
		(width 0.127)
		(layer "In2.Cu")
		(net "IOM_TYPE2")
	)
	(segment
		(start 39.010082 -161.3408)
		(end 41.781476 -158.569406)
		(width 0.127)
		(layer "In2.Cu")
		(net "IOM_TYPE2")
	)
	(segment
		(start 41.781476 -158.569406)
		(end 43.106594 -158.569406)
		(width 0.127)
		(layer "In2.Cu")
		(net "IOM_TYPE2")
	)
	(segment
		(start 34.2138 -162.2044)
		(end 34.2138 -161.9504)
		(width 0.127)
		(layer "In2.Cu")
		(net "IOM_TYPE2")
	)
	(segment
		(start 34.2138 -161.9504)
		(end 34.8234 -161.3408)
		(width 0.127)
		(layer "In2.Cu")
		(net "IOM_TYPE2")
	)
	(segment
		(start 44.899834 -150.999952)
		(end 44.899834 -151.000206)
		(width 0.127)
		(layer "F.Cu")
		(net "IOM_TYPE1")
	)
	(segment
		(start 44.899834 -151.000206)
		(end 44.500038 -151.400002)
		(width 0.127)
		(layer "F.Cu")
		(net "IOM_TYPE1")
	)
	(segment
		(start 32.4866 -163.42868)
		(end 32.4866 -162.8648)
		(width 0.127)
		(layer "F.Cu")
		(net "IOM_TYPE1")
	)
	(segment
		(start 32.4866 -164.5793)
		(end 31.4706 -164.5793)
		(width 0.127)
		(layer "F.Cu")
		(net "IOM_TYPE1")
	)
	(segment
		(start 32.4866 -163.42868)
		(end 32.4866 -164.5793)
		(width 0.127)
		(layer "F.Cu")
		(net "IOM_TYPE1")
	)
	(segment
		(start 32.4866 -162.8648)
		(end 33.147 -162.2044)
		(width 0.127)
		(layer "F.Cu")
		(net "IOM_TYPE1")
	)
	(via
		(at 32.4866 -163.42868)
		(size 0.6604)
		(drill 0.3302)
		(layers "F.Cu" "B.Cu")
		(net "IOM_TYPE1")
	)
	(via
		(at 33.147 -162.2044)
		(size 0.508)
		(drill 0.254)
		(layers "F.Cu" "B.Cu")
		(net "IOM_TYPE1")
	)
	(via
		(at 44.500038 -151.400002)
		(size 0.4572)
		(drill 0.2032)
		(layers "F.Cu" "B.Cu")
		(net "IOM_TYPE1")
	)
	(segment
		(start 38.877494 -160.9344)
		(end 41.623488 -158.188406)
		(width 0.127)
		(layer "In2.Cu")
		(net "IOM_TYPE1")
	)
	(segment
		(start 42.948606 -158.188406)
		(end 44.0944 -157.042612)
		(width 0.127)
		(layer "In2.Cu")
		(net "IOM_TYPE1")
	)
	(segment
		(start 44.500038 -151.64308)
		(end 44.500038 -151.400002)
		(width 0.127)
		(layer "In2.Cu")
		(net "IOM_TYPE1")
	)
	(segment
		(start 34.417 -160.9344)
		(end 38.877494 -160.9344)
		(width 0.127)
		(layer "In2.Cu")
		(net "IOM_TYPE1")
	)
	(segment
		(start 44.0944 -157.042612)
		(end 44.0944 -152.048718)
		(width 0.127)
		(layer "In2.Cu")
		(net "IOM_TYPE1")
	)
	(segment
		(start 33.147 -162.2044)
		(end 34.417 -160.9344)
		(width 0.127)
		(layer "In2.Cu")
		(net "IOM_TYPE1")
	)
	(segment
		(start 44.0944 -152.048718)
		(end 44.500038 -151.64308)
		(width 0.127)
		(layer "In2.Cu")
		(net "IOM_TYPE1")
	)
	(segment
		(start 41.623488 -158.188406)
		(end 42.948606 -158.188406)
		(width 0.127)
		(layer "In2.Cu")
		(net "IOM_TYPE1")
	)
	(segment
		(start 46.100238 -150.599902)
		(end 46.100238 -150.599648)
		(width 0.127)
		(layer "F.Cu")
		(net "IOM_TYPE0")
	)
	(segment
		(start 36.2712 -163.1188)
		(end 36.2712 -163.6776)
		(width 0.127)
		(layer "F.Cu")
		(net "IOM_TYPE0")
	)
	(segment
		(start 36.2712 -163.6776)
		(end 36.576 -163.9824)
		(width 0.127)
		(layer "F.Cu")
		(net "IOM_TYPE0")
	)
	(segment
		(start 46.100238 -150.599648)
		(end 46.500034 -150.199852)
		(width 0.127)
		(layer "F.Cu")
		(net "IOM_TYPE0")
	)
	(segment
		(start 35.179 -162.0266)
		(end 36.2712 -163.1188)
		(width 0.127)
		(layer "F.Cu")
		(net "IOM_TYPE0")
	)
	(segment
		(start 36.7792 -164.1856)
		(end 36.576 -163.9824)
		(width 0.127)
		(layer "F.Cu")
		(net "IOM_TYPE0")
	)
	(segment
		(start 35.7378 -165.1127)
		(end 36.7792 -165.1127)
		(width 0.127)
		(layer "F.Cu")
		(net "IOM_TYPE0")
	)
	(segment
		(start 36.7792 -165.1127)
		(end 36.7792 -164.1856)
		(width 0.127)
		(layer "F.Cu")
		(net "IOM_TYPE0")
	)
	(via
		(at 36.576 -163.9824)
		(size 0.6604)
		(drill 0.3302)
		(layers "F.Cu" "B.Cu")
		(net "IOM_TYPE0")
	)
	(via
		(at 46.100238 -150.599902)
		(size 0.4572)
		(drill 0.2032)
		(layers "F.Cu" "B.Cu")
		(net "IOM_TYPE0")
	)
	(via
		(at 35.179 -162.0266)
		(size 0.508)
		(drill 0.254)
		(layers "F.Cu" "B.Cu")
		(net "IOM_TYPE0")
	)
	(segment
		(start 35.3822 -161.8234)
		(end 39.856664 -161.8234)
		(width 0.127)
		(layer "In2.Cu")
		(net "IOM_TYPE0")
	)
	(segment
		(start 44.906438 -152.03678)
		(end 44.906184 -152.036526)
		(width 0.127)
		(layer "In2.Cu")
		(net "IOM_TYPE0")
	)
	(segment
		(start 45.85716 -150.599902)
		(end 46.100238 -150.599902)
		(width 0.127)
		(layer "In2.Cu")
		(net "IOM_TYPE0")
	)
	(segment
		(start 45.450506 -151.006556)
		(end 45.85716 -150.599902)
		(width 0.127)
		(layer "In2.Cu")
		(net "IOM_TYPE0")
	)
	(segment
		(start 40.3987 -160.9217)
		(end 42.369994 -158.950406)
		(width 0.127)
		(layer "In2.Cu")
		(net "IOM_TYPE0")
	)
	(segment
		(start 45.136562 -151.006556)
		(end 45.450506 -151.006556)
		(width 0.127)
		(layer "In2.Cu")
		(net "IOM_TYPE0")
	)
	(segment
		(start 40.3987 -161.281618)
		(end 40.3987 -160.9217)
		(width 0.127)
		(layer "In2.Cu")
		(net "IOM_TYPE0")
	)
	(segment
		(start 39.856664 -161.8234)
		(end 40.3987 -161.281618)
		(width 0.127)
		(layer "In2.Cu")
		(net "IOM_TYPE0")
	)
	(segment
		(start 42.369994 -158.950406)
		(end 43.264582 -158.950406)
		(width 0.127)
		(layer "In2.Cu")
		(net "IOM_TYPE0")
	)
	(segment
		(start 43.264582 -158.950406)
		(end 44.906438 -157.30855)
		(width 0.127)
		(layer "In2.Cu")
		(net "IOM_TYPE0")
	)
	(segment
		(start 44.906438 -157.30855)
		(end 44.906438 -152.03678)
		(width 0.127)
		(layer "In2.Cu")
		(net "IOM_TYPE0")
	)
	(segment
		(start 44.906184 -152.036526)
		(end 44.906184 -151.236934)
		(width 0.127)
		(layer "In2.Cu")
		(net "IOM_TYPE0")
	)
	(segment
		(start 44.906184 -151.236934)
		(end 45.136562 -151.006556)
		(width 0.127)
		(layer "In2.Cu")
		(net "IOM_TYPE0")
	)
	(segment
		(start 35.179 -162.0266)
		(end 35.3822 -161.8234)
		(width 0.127)
		(layer "In2.Cu")
		(net "IOM_TYPE0")
	)
	(segment
		(start 66.9925 -166.8907)
		(end 66.421 -167.4622)
		(width 0.127)
		(layer "F.Cu")
		(net "BMC_SELF_HW_RST_D")
	)
	(segment
		(start 66.421 -167.4622)
		(end 62.2935 -167.4622)
		(width 0.127)
		(layer "F.Cu")
		(net "BMC_SELF_HW_RST_D")
	)
	(segment
		(start 68.7705 -168.5544)
		(end 67.7672 -169.5577)
		(width 0.127)
		(layer "F.Cu")
		(net "BMC_SELF_HW_RST_D")
	)
	(segment
		(start 66.6496 -170.1292)
		(end 67.1957 -170.1292)
		(width 0.127)
		(layer "F.Cu")
		(net "BMC_SELF_HW_RST_D")
	)
	(segment
		(start 67.1957 -170.1292)
		(end 67.7672 -169.5577)
		(width 0.127)
		(layer "F.Cu")
		(net "BMC_SELF_HW_RST_D")
	)
	(segment
		(start 62.2935 -167.4622)
		(end 61.247274 -168.508426)
		(width 0.127)
		(layer "F.Cu")
		(net "BMC_SELF_HW_RST_D")
	)
	(segment
		(start 69.460618 -166.8907)
		(end 66.9925 -166.8907)
		(width 0.127)
		(layer "F.Cu")
		(net "BMC_SELF_HW_RST_D")
	)
	(segment
		(start 69.6468 -167.076882)
		(end 69.460618 -166.8907)
		(width 0.127)
		(layer "F.Cu")
		(net "BMC_SELF_HW_RST_D")
	)
	(segment
		(start 69.6468 -168.5544)
		(end 68.7705 -168.5544)
		(width 0.127)
		(layer "F.Cu")
		(net "BMC_SELF_HW_RST_D")
	)
	(segment
		(start 61.247274 -168.508426)
		(end 60.689744 -168.508426)
		(width 0.127)
		(layer "F.Cu")
		(net "BMC_SELF_HW_RST_D")
	)
	(segment
		(start 69.6468 -168.5544)
		(end 69.6468 -167.076882)
		(width 0.127)
		(layer "F.Cu")
		(net "BMC_SELF_HW_RST_D")
	)
	(via
		(at 69.460618 -166.8907)
		(size 0.6604)
		(drill 0.3302)
		(layers "F.Cu" "B.Cu")
		(net "BMC_SELF_HW_RST_D")
	)
	(segment
		(start 139.768326 -13.62202)
		(end 139.402312 -13.988034)
		(width 0.127)
		(layer "F.Cu")
		(net "IOC_EXT2_LED_Y_XOR")
	)
	(segment
		(start 139.1158 -15.239492)
		(end 139.1158 -16.6497)
		(width 0.127)
		(layer "F.Cu")
		(net "IOC_EXT2_LED_Y_XOR")
	)
	(segment
		(start 140.34516 -13.62202)
		(end 139.768326 -13.62202)
		(width 0.127)
		(layer "F.Cu")
		(net "IOC_EXT2_LED_Y_XOR")
	)
	(segment
		(start 139.402312 -13.988034)
		(end 139.402312 -14.95298)
		(width 0.127)
		(layer "F.Cu")
		(net "IOC_EXT2_LED_Y_XOR")
	)
	(segment
		(start 139.1158 -16.6497)
		(end 139.6111 -17.145)
		(width 0.127)
		(layer "F.Cu")
		(net "IOC_EXT2_LED_Y_XOR")
	)
	(segment
		(start 139.402312 -14.95298)
		(end 139.1158 -15.239492)
		(width 0.127)
		(layer "F.Cu")
		(net "IOC_EXT2_LED_Y_XOR")
	)
	(segment
		(start 141.12875 -17.4625)
		(end 139.9286 -17.4625)
		(width 0.127)
		(layer "F.Cu")
		(net "IOC_EXT2_LED_Y_XOR")
	)
	(segment
		(start 139.9286 -17.4625)
		(end 139.6111 -17.145)
		(width 0.127)
		(layer "F.Cu")
		(net "IOC_EXT2_LED_Y_XOR")
	)
	(via
		(at 139.6111 -17.145)
		(size 0.6604)
		(drill 0.3302)
		(layers "F.Cu" "B.Cu")
		(net "IOC_EXT2_LED_Y_XOR")
	)
	(segment
		(start 198.91375 -16.15694)
		(end 199.6948 -15.37589)
		(width 0.127)
		(layer "F.Cu")
		(net "IOC_EXT1_LED_Y_XOR")
	)
	(segment
		(start 200.40092 -13.604748)
		(end 200.40092 -14.66977)
		(width 0.127)
		(layer "F.Cu")
		(net "IOC_EXT1_LED_Y_XOR")
	)
	(segment
		(start 198.91375 -16.9545)
		(end 198.91375 -16.15694)
		(width 0.127)
		(layer "F.Cu")
		(net "IOC_EXT1_LED_Y_XOR")
	)
	(segment
		(start 200.40092 -14.66977)
		(end 199.6948 -15.37589)
		(width 0.127)
		(layer "F.Cu")
		(net "IOC_EXT1_LED_Y_XOR")
	)
	(via
		(at 199.6948 -15.37589)
		(size 0.6604)
		(drill 0.3302)
		(layers "F.Cu" "B.Cu")
		(net "IOC_EXT1_LED_Y_XOR")
	)
	(segment
		(start 197.358 -125.1077)
		(end 198.3867 -125.1077)
		(width 0.254)
		(layer "F.Cu")
		(net "P0V975_SEN")
	)
	(via
		(at 198.3867 -125.1077)
		(size 0.508)
		(drill 0.254)
		(layers "F.Cu" "B.Cu")
		(net "P0V975_SEN")
	)
	(via
		(at 204.2414 -121.7168)
		(size 0.6096)
		(drill 0.3048)
		(layers "F.Cu" "B.Cu")
		(net "P0V975_SEN")
	)
	(segment
		(start 207.7593 -79.9084)
		(end 209.0166 -79.9084)
		(width 0.254)
		(layer "B.Cu")
		(net "P0V975_SEN")
	)
	(segment
		(start 213.046056 -116.586)
		(end 208.478628 -121.153428)
		(width 0.254)
		(layer "B.Cu")
		(net "P0V975_SEN")
	)
	(segment
		(start 227.297234 -86.860634)
		(end 227.297234 -105.715562)
		(width 0.254)
		(layer "B.Cu")
		(net "P0V975_SEN")
	)
	(segment
		(start 209.2452 -79.6798)
		(end 210.379056 -79.6798)
		(width 0.254)
		(layer "B.Cu")
		(net "P0V975_SEN")
	)
	(segment
		(start 210.379056 -79.6798)
		(end 212.944456 -82.2452)
		(width 0.254)
		(layer "B.Cu")
		(net "P0V975_SEN")
	)
	(segment
		(start 215.5952 -82.2452)
		(end 216.8906 -80.9498)
		(width 0.254)
		(layer "B.Cu")
		(net "P0V975_SEN")
	)
	(segment
		(start 204.2414 -121.7168)
		(end 200.7108 -125.2474)
		(width 0.254)
		(layer "B.Cu")
		(net "P0V975_SEN")
	)
	(segment
		(start 212.944456 -82.2452)
		(end 215.5952 -82.2452)
		(width 0.254)
		(layer "B.Cu")
		(net "P0V975_SEN")
	)
	(segment
		(start 216.8906 -80.9498)
		(end 221.3864 -80.9498)
		(width 0.254)
		(layer "B.Cu")
		(net "P0V975_SEN")
	)
	(segment
		(start 227.935536 -114.893598)
		(end 226.243134 -116.586)
		(width 0.254)
		(layer "B.Cu")
		(net "P0V975_SEN")
	)
	(segment
		(start 227.297234 -105.715562)
		(end 227.935536 -106.353864)
		(width 0.254)
		(layer "B.Cu")
		(net "P0V975_SEN")
	)
	(segment
		(start 204.804772 -121.153428)
		(end 204.2414 -121.7168)
		(width 0.254)
		(layer "B.Cu")
		(net "P0V975_SEN")
	)
	(segment
		(start 226.243134 -116.586)
		(end 213.046056 -116.586)
		(width 0.254)
		(layer "B.Cu")
		(net "P0V975_SEN")
	)
	(segment
		(start 198.5264 -125.2474)
		(end 198.3867 -125.1077)
		(width 0.254)
		(layer "B.Cu")
		(net "P0V975_SEN")
	)
	(segment
		(start 209.0166 -79.9084)
		(end 209.2452 -79.6798)
		(width 0.254)
		(layer "B.Cu")
		(net "P0V975_SEN")
	)
	(segment
		(start 227.935536 -106.353864)
		(end 227.935536 -114.893598)
		(width 0.254)
		(layer "B.Cu")
		(net "P0V975_SEN")
	)
	(segment
		(start 208.478628 -121.153428)
		(end 204.804772 -121.153428)
		(width 0.254)
		(layer "B.Cu")
		(net "P0V975_SEN")
	)
	(segment
		(start 221.3864 -80.9498)
		(end 227.297234 -86.860634)
		(width 0.254)
		(layer "B.Cu")
		(net "P0V975_SEN")
	)
	(segment
		(start 200.7108 -125.2474)
		(end 198.5264 -125.2474)
		(width 0.254)
		(layer "B.Cu")
		(net "P0V975_SEN")
	)
	(segment
		(start 197.4088 -126.1745)
		(end 198.3105 -126.1745)
		(width 0.254)
		(layer "F.Cu")
		(net "GND_SEN")
	)
	(via
		(at 207.7212 -121.8184)
		(size 0.6096)
		(drill 0.3048)
		(layers "F.Cu" "B.Cu")
		(net "GND_SEN")
	)
	(via
		(at 198.3105 -126.1745)
		(size 0.508)
		(drill 0.254)
		(layers "F.Cu" "B.Cu")
		(net "GND_SEN")
	)
	(segment
		(start 216.2556 -80.686656)
		(end 215.332056 -81.6102)
		(width 0.254)
		(layer "B.Cu")
		(net "GND_SEN")
	)
	(segment
		(start 213.2076 -81.6102)
		(end 210.6422 -79.0448)
		(width 0.254)
		(layer "B.Cu")
		(net "GND_SEN")
	)
	(segment
		(start 216.627202 -80.3148)
		(end 216.2556 -80.686402)
		(width 0.254)
		(layer "B.Cu")
		(net "GND_SEN")
	)
	(segment
		(start 210.6422 -79.0448)
		(end 209.2198 -79.0448)
		(width 0.254)
		(layer "B.Cu")
		(net "GND_SEN")
	)
	(segment
		(start 209.0166 -78.8416)
		(end 207.7593 -78.8416)
		(width 0.254)
		(layer "B.Cu")
		(net "GND_SEN")
	)
	(segment
		(start 215.332056 -81.6102)
		(end 213.2076 -81.6102)
		(width 0.254)
		(layer "B.Cu")
		(net "GND_SEN")
	)
	(segment
		(start 207.7212 -121.8184)
		(end 205.3844 -121.8184)
		(width 0.254)
		(layer "B.Cu")
		(net "GND_SEN")
	)
	(segment
		(start 205.3844 -121.8184)
		(end 201.3204 -125.8824)
		(width 0.254)
		(layer "B.Cu")
		(net "GND_SEN")
	)
	(segment
		(start 209.2198 -79.0448)
		(end 209.0166 -78.8416)
		(width 0.254)
		(layer "B.Cu")
		(net "GND_SEN")
	)
	(segment
		(start 228.726238 -115.00104)
		(end 228.726238 -106.246422)
		(width 0.254)
		(layer "B.Cu")
		(net "GND_SEN")
	)
	(segment
		(start 213.3092 -117.221)
		(end 226.506278 -117.221)
		(width 0.254)
		(layer "B.Cu")
		(net "GND_SEN")
	)
	(segment
		(start 227.932234 -105.452418)
		(end 227.932234 -86.59749)
		(width 0.254)
		(layer "B.Cu")
		(net "GND_SEN")
	)
	(segment
		(start 201.3204 -125.8824)
		(end 198.6026 -125.8824)
		(width 0.254)
		(layer "B.Cu")
		(net "GND_SEN")
	)
	(segment
		(start 228.726238 -106.246422)
		(end 227.932234 -105.452418)
		(width 0.254)
		(layer "B.Cu")
		(net "GND_SEN")
	)
	(segment
		(start 227.932234 -86.59749)
		(end 221.649544 -80.3148)
		(width 0.254)
		(layer "B.Cu")
		(net "GND_SEN")
	)
	(segment
		(start 226.506278 -117.221)
		(end 228.726238 -115.00104)
		(width 0.254)
		(layer "B.Cu")
		(net "GND_SEN")
	)
	(segment
		(start 216.2556 -80.686402)
		(end 216.2556 -80.686656)
		(width 0.254)
		(layer "B.Cu")
		(net "GND_SEN")
	)
	(segment
		(start 208.7118 -121.8184)
		(end 213.3092 -117.221)
		(width 0.254)
		(layer "B.Cu")
		(net "GND_SEN")
	)
	(segment
		(start 198.6026 -125.8824)
		(end 198.3105 -126.1745)
		(width 0.254)
		(layer "B.Cu")
		(net "GND_SEN")
	)
	(segment
		(start 221.649544 -80.3148)
		(end 216.627202 -80.3148)
		(width 0.254)
		(layer "B.Cu")
		(net "GND_SEN")
	)
	(segment
		(start 207.7212 -121.8184)
		(end 208.7118 -121.8184)
		(width 0.254)
		(layer "B.Cu")
		(net "GND_SEN")
	)
	(via
		(at 162.3822 -135.3058)
		(size 0.6604)
		(drill 0.3302)
		(layers "F.Cu" "B.Cu")
		(net "P12V_STBY_VIN_PU4")
	)
	(segment
		(start 30.744668 -180.570632)
		(end 31.845504 -180.570632)
		(width 0.254)
		(layer "F.Cu")
		(net "P12V_STBY_VDD_PU2")
	)
	(segment
		(start 30.441646 -180.26761)
		(end 30.744668 -180.570632)
		(width 0.254)
		(layer "F.Cu")
		(net "P12V_STBY_VDD_PU2")
	)
	(via
		(at 27.807412 -181.16423)
		(size 0.6096)
		(drill 0.3048)
		(layers "F.Cu" "B.Cu")
		(net "P12V_STBY_VDD_PU2")
	)
	(via
		(at 30.441646 -180.26761)
		(size 0.508)
		(drill 0.254)
		(layers "F.Cu" "B.Cu")
		(net "P12V_STBY_VDD_PU2")
	)
	(segment
		(start 25.4254 -179.2478)
		(end 25.4254 -180.2384)
		(width 0.254)
		(layer "B.Cu")
		(net "P12V_STBY_VDD_PU2")
	)
	(segment
		(start 25.4254 -180.2384)
		(end 26.0858 -180.8988)
		(width 0.254)
		(layer "B.Cu")
		(net "P12V_STBY_VDD_PU2")
	)
	(segment
		(start 26.0858 -180.8988)
		(end 26.35123 -181.16423)
		(width 0.254)
		(layer "B.Cu")
		(net "P12V_STBY_VDD_PU2")
	)
	(segment
		(start 30.441646 -180.26761)
		(end 29.545026 -181.16423)
		(width 0.254)
		(layer "B.Cu")
		(net "P12V_STBY_VDD_PU2")
	)
	(segment
		(start 29.545026 -181.16423)
		(end 27.807412 -181.16423)
		(width 0.254)
		(layer "B.Cu")
		(net "P12V_STBY_VDD_PU2")
	)
	(segment
		(start 26.35123 -181.16423)
		(end 27.807412 -181.16423)
		(width 0.254)
		(layer "B.Cu")
		(net "P12V_STBY_VDD_PU2")
	)
	(segment
		(start 179.07381 -143.02486)
		(end 179.07381 -143.036798)
		(width 0.254)
		(layer "F.Cu")
		(net "P12V_STBY_VDD_PU1")
	)
	(segment
		(start 178.938682 -143.171926)
		(end 178.938682 -144.260824)
		(width 0.254)
		(layer "F.Cu")
		(net "P12V_STBY_VDD_PU1")
	)
	(segment
		(start 179.241704 -142.856966)
		(end 179.07381 -143.02486)
		(width 0.254)
		(layer "F.Cu")
		(net "P12V_STBY_VDD_PU1")
	)
	(segment
		(start 179.07381 -143.036798)
		(end 178.938682 -143.171926)
		(width 0.254)
		(layer "F.Cu")
		(net "P12V_STBY_VDD_PU1")
	)
	(via
		(at 179.241704 -142.856966)
		(size 0.508)
		(drill 0.254)
		(layers "F.Cu" "B.Cu")
		(net "P12V_STBY_VDD_PU1")
	)
	(via
		(at 177.665888 -142.3162)
		(size 0.6096)
		(drill 0.3048)
		(layers "F.Cu" "B.Cu")
		(net "P12V_STBY_VDD_PU1")
	)
	(segment
		(start 177.133504 -141.783816)
		(end 177.665888 -142.3162)
		(width 0.254)
		(layer "B.Cu")
		(net "P12V_STBY_VDD_PU1")
	)
	(segment
		(start 178.206654 -142.856966)
		(end 177.665888 -142.3162)
		(width 0.254)
		(layer "B.Cu")
		(net "P12V_STBY_VDD_PU1")
	)
	(segment
		(start 177.133504 -139.262104)
		(end 177.133504 -140.824966)
		(width 0.254)
		(layer "B.Cu")
		(net "P12V_STBY_VDD_PU1")
	)
	(segment
		(start 179.241704 -142.856966)
		(end 178.206654 -142.856966)
		(width 0.254)
		(layer "B.Cu")
		(net "P12V_STBY_VDD_PU1")
	)
	(segment
		(start 177.133504 -140.824966)
		(end 177.133504 -141.783816)
		(width 0.254)
		(layer "B.Cu")
		(net "P12V_STBY_VDD_PU1")
	)
	(segment
		(start 177.0888 -139.2174)
		(end 177.133504 -139.262104)
		(width 0.254)
		(layer "B.Cu")
		(net "P12V_STBY_VDD_PU1")
	)
	(segment
		(start 75.022202 -134.2898)
		(end 75.385676 -134.653274)
		(width 0.127)
		(layer "F.Cu")
		(net "I2C_DEBUG_SDA_L")
	)
	(segment
		(start 77.48778 -134.653274)
		(end 75.770232 -134.653274)
		(width 0.127)
		(layer "F.Cu")
		(net "I2C_DEBUG_SDA_L")
	)
	(segment
		(start 99.74961 -146.431)
		(end 100.05314 -146.12747)
		(width 0.127)
		(layer "F.Cu")
		(net "I2C_DEBUG_SDA_L")
	)
	(segment
		(start 71.318374 -134.068566)
		(end 73.961244 -134.068566)
		(width 0.127)
		(layer "F.Cu")
		(net "I2C_DEBUG_SDA_L")
	)
	(segment
		(start 73.961244 -134.068566)
		(end 74.182478 -134.2898)
		(width 0.127)
		(layer "F.Cu")
		(net "I2C_DEBUG_SDA_L")
	)
	(segment
		(start 75.385676 -134.653274)
		(end 75.770232 -134.653274)
		(width 0.127)
		(layer "F.Cu")
		(net "I2C_DEBUG_SDA_L")
	)
	(segment
		(start 68.924678 -136.462262)
		(end 71.318374 -134.068566)
		(width 0.127)
		(layer "F.Cu")
		(net "I2C_DEBUG_SDA_L")
	)
	(segment
		(start 74.182478 -134.2898)
		(end 75.022202 -134.2898)
		(width 0.127)
		(layer "F.Cu")
		(net "I2C_DEBUG_SDA_L")
	)
	(segment
		(start 98.9965 -146.431)
		(end 99.74961 -146.431)
		(width 0.127)
		(layer "F.Cu")
		(net "I2C_DEBUG_SDA_L")
	)
	(via
		(at 68.924678 -136.462262)
		(size 0.508)
		(drill 0.254)
		(layers "F.Cu" "B.Cu")
		(net "I2C_DEBUG_SDA_L")
	)
	(via
		(at 100.05314 -146.12747)
		(size 0.508)
		(drill 0.254)
		(layers "F.Cu" "B.Cu")
		(net "I2C_DEBUG_SDA_L")
	)
	(via
		(at 70.317106 -147.906486)
		(size 0.508)
		(drill 0.254)
		(layers "F.Cu" "B.Cu")
		(net "I2C_DEBUG_SDA_L")
	)
	(via
		(at 75.770232 -134.653274)
		(size 0.6604)
		(drill 0.3302)
		(layers "F.Cu" "B.Cu")
		(net "I2C_DEBUG_SDA_L")
	)
	(segment
		(start 70.187566 -145.888202)
		(end 70.187566 -143.520414)
		(width 0.127)
		(layer "B.Cu")
		(net "I2C_DEBUG_SDA_L")
	)
	(segment
		(start 70.317106 -147.906486)
		(end 70.41388 -147.809712)
		(width 0.127)
		(layer "B.Cu")
		(net "I2C_DEBUG_SDA_L")
	)
	(segment
		(start 68.788534 -142.515336)
		(end 68.792344 -142.511526)
		(width 0.127)
		(layer "B.Cu")
		(net "I2C_DEBUG_SDA_L")
	)
	(segment
		(start 70.41388 -147.809712)
		(end 70.41388 -146.114516)
		(width 0.127)
		(layer "B.Cu")
		(net "I2C_DEBUG_SDA_L")
	)
	(segment
		(start 70.187566 -143.520414)
		(end 69.178678 -142.511526)
		(width 0.127)
		(layer "B.Cu")
		(net "I2C_DEBUG_SDA_L")
	)
	(segment
		(start 70.41388 -146.114516)
		(end 70.187566 -145.888202)
		(width 0.127)
		(layer "B.Cu")
		(net "I2C_DEBUG_SDA_L")
	)
	(segment
		(start 67.772026 -142.515336)
		(end 68.788534 -142.515336)
		(width 0.127)
		(layer "B.Cu")
		(net "I2C_DEBUG_SDA_L")
	)
	(segment
		(start 69.178678 -142.511526)
		(end 68.792344 -142.511526)
		(width 0.127)
		(layer "B.Cu")
		(net "I2C_DEBUG_SDA_L")
	)
	(segment
		(start 67.771264 -142.516098)
		(end 67.772026 -142.515336)
		(width 0.127)
		(layer "B.Cu")
		(net "I2C_DEBUG_SDA_L")
	)
	(segment
		(start 69.663564 -142.761208)
		(end 70.4469 -143.544544)
		(width 0.127)
		(layer "In2.Cu")
		(net "I2C_DEBUG_SDA_L")
	)
	(segment
		(start 70.4469 -146.993864)
		(end 70.317106 -147.123658)
		(width 0.127)
		(layer "In2.Cu")
		(net "I2C_DEBUG_SDA_L")
	)
	(segment
		(start 70.4469 -143.544544)
		(end 70.4469 -146.993864)
		(width 0.127)
		(layer "In2.Cu")
		(net "I2C_DEBUG_SDA_L")
	)
	(segment
		(start 69.663564 -138.881866)
		(end 69.663564 -142.761208)
		(width 0.127)
		(layer "In2.Cu")
		(net "I2C_DEBUG_SDA_L")
	)
	(segment
		(start 68.924678 -136.462262)
		(end 68.924678 -138.14298)
		(width 0.127)
		(layer "In2.Cu")
		(net "I2C_DEBUG_SDA_L")
	)
	(segment
		(start 68.924678 -138.14298)
		(end 69.663564 -138.881866)
		(width 0.127)
		(layer "In2.Cu")
		(net "I2C_DEBUG_SDA_L")
	)
	(segment
		(start 70.317106 -147.123658)
		(end 70.317106 -147.906486)
		(width 0.127)
		(layer "In2.Cu")
		(net "I2C_DEBUG_SDA_L")
	)
	(segment
		(start 93.424502 -146.471132)
		(end 94.016068 -145.879566)
		(width 0.127)
		(layer "In5.Cu")
		(net "I2C_DEBUG_SDA_L")
	)
	(segment
		(start 73.092818 -148.398484)
		(end 78.176628 -148.398484)
		(width 0.127)
		(layer "In5.Cu")
		(net "I2C_DEBUG_SDA_L")
	)
	(segment
		(start 78.176628 -148.398484)
		(end 79.001366 -147.573746)
		(width 0.127)
		(layer "In5.Cu")
		(net "I2C_DEBUG_SDA_L")
	)
	(segment
		(start 94.016068 -145.879566)
		(end 98.886264 -145.879566)
		(width 0.127)
		(layer "In5.Cu")
		(net "I2C_DEBUG_SDA_L")
	)
	(segment
		(start 88.779604 -146.471132)
		(end 93.424502 -146.471132)
		(width 0.127)
		(layer "In5.Cu")
		(net "I2C_DEBUG_SDA_L")
	)
	(segment
		(start 98.886264 -145.879566)
		(end 99.134168 -146.12747)
		(width 0.127)
		(layer "In5.Cu")
		(net "I2C_DEBUG_SDA_L")
	)
	(segment
		(start 87.67699 -147.573746)
		(end 88.779604 -146.471132)
		(width 0.127)
		(layer "In5.Cu")
		(net "I2C_DEBUG_SDA_L")
	)
	(segment
		(start 72.32904 -147.634706)
		(end 73.092818 -148.398484)
		(width 0.127)
		(layer "In5.Cu")
		(net "I2C_DEBUG_SDA_L")
	)
	(segment
		(start 70.317106 -147.906486)
		(end 70.588886 -147.634706)
		(width 0.127)
		(layer "In5.Cu")
		(net "I2C_DEBUG_SDA_L")
	)
	(segment
		(start 79.001366 -147.573746)
		(end 87.67699 -147.573746)
		(width 0.127)
		(layer "In5.Cu")
		(net "I2C_DEBUG_SDA_L")
	)
	(segment
		(start 70.588886 -147.634706)
		(end 72.32904 -147.634706)
		(width 0.127)
		(layer "In5.Cu")
		(net "I2C_DEBUG_SDA_L")
	)
	(segment
		(start 99.134168 -146.12747)
		(end 100.05314 -146.12747)
		(width 0.127)
		(layer "In5.Cu")
		(net "I2C_DEBUG_SDA_L")
	)
	(segment
		(start 99.900994 -145.415)
		(end 100.053648 -145.262346)
		(width 0.127)
		(layer "F.Cu")
		(net "I2C_DEBUG_SCL_L")
	)
	(segment
		(start 73.960482 -133.349238)
		(end 73.05421 -133.349238)
		(width 0.127)
		(layer "F.Cu")
		(net "I2C_DEBUG_SCL_L")
	)
	(segment
		(start 77.48778 -134.003034)
		(end 75.454002 -134.003034)
		(width 0.127)
		(layer "F.Cu")
		(net "I2C_DEBUG_SCL_L")
	)
	(segment
		(start 98.9965 -145.415)
		(end 99.900994 -145.415)
		(width 0.127)
		(layer "F.Cu")
		(net "I2C_DEBUG_SCL_L")
	)
	(segment
		(start 68.061078 -136.475216)
		(end 71.187056 -133.349238)
		(width 0.127)
		(layer "F.Cu")
		(net "I2C_DEBUG_SCL_L")
	)
	(segment
		(start 75.454002 -134.003034)
		(end 75.232768 -133.7818)
		(width 0.127)
		(layer "F.Cu")
		(net "I2C_DEBUG_SCL_L")
	)
	(segment
		(start 74.393044 -133.7818)
		(end 73.960482 -133.349238)
		(width 0.127)
		(layer "F.Cu")
		(net "I2C_DEBUG_SCL_L")
	)
	(segment
		(start 71.187056 -133.349238)
		(end 73.05421 -133.349238)
		(width 0.127)
		(layer "F.Cu")
		(net "I2C_DEBUG_SCL_L")
	)
	(segment
		(start 75.232768 -133.7818)
		(end 74.393044 -133.7818)
		(width 0.127)
		(layer "F.Cu")
		(net "I2C_DEBUG_SCL_L")
	)
	(via
		(at 100.053648 -145.262346)
		(size 0.508)
		(drill 0.254)
		(layers "F.Cu" "B.Cu")
		(net "I2C_DEBUG_SCL_L")
	)
	(via
		(at 68.061078 -136.475216)
		(size 0.508)
		(drill 0.254)
		(layers "F.Cu" "B.Cu")
		(net "I2C_DEBUG_SCL_L")
	)
	(via
		(at 73.05421 -133.349238)
		(size 0.6604)
		(drill 0.3302)
		(layers "F.Cu" "B.Cu")
		(net "I2C_DEBUG_SCL_L")
	)
	(via
		(at 69.754242 -147.039584)
		(size 0.508)
		(drill 0.254)
		(layers "F.Cu" "B.Cu")
		(net "I2C_DEBUG_SCL_L")
	)
	(segment
		(start 68.098416 -146.419316)
		(end 67.7672 -146.0881)
		(width 0.127)
		(layer "B.Cu")
		(net "I2C_DEBUG_SCL_L")
	)
	(segment
		(start 68.820538 -146.419316)
		(end 68.098416 -146.419316)
		(width 0.127)
		(layer "B.Cu")
		(net "I2C_DEBUG_SCL_L")
	)
	(segment
		(start 68.820538 -146.419316)
		(end 69.133974 -146.419316)
		(width 0.127)
		(layer "B.Cu")
		(net "I2C_DEBUG_SCL_L")
	)
	(segment
		(start 69.133974 -146.419316)
		(end 69.754242 -147.039584)
		(width 0.127)
		(layer "B.Cu")
		(net "I2C_DEBUG_SCL_L")
	)
	(segment
		(start 69.155564 -139.22756)
		(end 69.155564 -143.115792)
		(width 0.127)
		(layer "In2.Cu")
		(net "I2C_DEBUG_SCL_L")
	)
	(segment
		(start 69.809106 -146.913092)
		(end 69.809106 -146.98472)
		(width 0.127)
		(layer "In2.Cu")
		(net "I2C_DEBUG_SCL_L")
	)
	(segment
		(start 68.285614 -138.35761)
		(end 69.155564 -139.22756)
		(width 0.127)
		(layer "In2.Cu")
		(net "I2C_DEBUG_SCL_L")
	)
	(segment
		(start 69.9389 -146.783298)
		(end 69.809106 -146.913092)
		(width 0.127)
		(layer "In2.Cu")
		(net "I2C_DEBUG_SCL_L")
	)
	(segment
		(start 68.285614 -136.699752)
		(end 68.285614 -138.35761)
		(width 0.127)
		(layer "In2.Cu")
		(net "I2C_DEBUG_SCL_L")
	)
	(segment
		(start 69.883528 -143.843756)
		(end 69.883528 -143.86941)
		(width 0.127)
		(layer "In2.Cu")
		(net "I2C_DEBUG_SCL_L")
	)
	(segment
		(start 69.155564 -143.115792)
		(end 69.883528 -143.843756)
		(width 0.127)
		(layer "In2.Cu")
		(net "I2C_DEBUG_SCL_L")
	)
	(segment
		(start 69.809106 -146.98472)
		(end 69.754242 -147.039584)
		(width 0.127)
		(layer "In2.Cu")
		(net "I2C_DEBUG_SCL_L")
	)
	(segment
		(start 69.883528 -143.86941)
		(end 69.9389 -143.924782)
		(width 0.127)
		(layer "In2.Cu")
		(net "I2C_DEBUG_SCL_L")
	)
	(segment
		(start 68.061078 -136.475216)
		(end 68.285614 -136.699752)
		(width 0.127)
		(layer "In2.Cu")
		(net "I2C_DEBUG_SCL_L")
	)
	(segment
		(start 69.9389 -143.924782)
		(end 69.9389 -146.783298)
		(width 0.127)
		(layer "In2.Cu")
		(net "I2C_DEBUG_SCL_L")
	)
	(segment
		(start 89.16543 -145.835624)
		(end 89.503504 -145.49755)
		(width 0.127)
		(layer "In5.Cu")
		(net "I2C_DEBUG_SCL_L")
	)
	(segment
		(start 76.019406 -147.890484)
		(end 76.844398 -147.065492)
		(width 0.127)
		(layer "In5.Cu")
		(net "I2C_DEBUG_SCL_L")
	)
	(segment
		(start 76.844398 -147.065492)
		(end 87.466678 -147.065492)
		(width 0.127)
		(layer "In5.Cu")
		(net "I2C_DEBUG_SCL_L")
	)
	(segment
		(start 73.46442 -147.890484)
		(end 76.019406 -147.890484)
		(width 0.127)
		(layer "In5.Cu")
		(net "I2C_DEBUG_SCL_L")
	)
	(segment
		(start 99.966018 -145.262346)
		(end 100.053648 -145.262346)
		(width 0.127)
		(layer "In5.Cu")
		(net "I2C_DEBUG_SCL_L")
	)
	(segment
		(start 69.754242 -147.039584)
		(end 69.906388 -146.887438)
		(width 0.127)
		(layer "In5.Cu")
		(net "I2C_DEBUG_SCL_L")
	)
	(segment
		(start 69.906388 -146.887438)
		(end 72.461374 -146.887438)
		(width 0.127)
		(layer "In5.Cu")
		(net "I2C_DEBUG_SCL_L")
	)
	(segment
		(start 93.896942 -145.280126)
		(end 99.948238 -145.280126)
		(width 0.127)
		(layer "In5.Cu")
		(net "I2C_DEBUG_SCL_L")
	)
	(segment
		(start 89.503504 -145.49755)
		(end 93.679518 -145.49755)
		(width 0.127)
		(layer "In5.Cu")
		(net "I2C_DEBUG_SCL_L")
	)
	(segment
		(start 87.466678 -147.065492)
		(end 88.696546 -145.835624)
		(width 0.127)
		(layer "In5.Cu")
		(net "I2C_DEBUG_SCL_L")
	)
	(segment
		(start 88.696546 -145.835624)
		(end 89.16543 -145.835624)
		(width 0.127)
		(layer "In5.Cu")
		(net "I2C_DEBUG_SCL_L")
	)
	(segment
		(start 99.948238 -145.280126)
		(end 99.966018 -145.262346)
		(width 0.127)
		(layer "In5.Cu")
		(net "I2C_DEBUG_SCL_L")
	)
	(segment
		(start 93.679518 -145.49755)
		(end 93.896942 -145.280126)
		(width 0.127)
		(layer "In5.Cu")
		(net "I2C_DEBUG_SCL_L")
	)
	(segment
		(start 72.461374 -146.887438)
		(end 73.46442 -147.890484)
		(width 0.127)
		(layer "In5.Cu")
		(net "I2C_DEBUG_SCL_L")
	)
	(via
		(at 32.2453 -125.864112)
		(size 0.6096)
		(drill 0.3048)
		(layers "F.Cu" "B.Cu")
		(net "U104_EN")
	)
	(segment
		(start 31.93288 -126.8349)
		(end 30.88132 -126.8349)
		(width 0.127)
		(layer "B.Cu")
		(net "U104_EN")
	)
	(segment
		(start 32.2453 -124.53874)
		(end 32.2199 -124.51334)
		(width 0.127)
		(layer "B.Cu")
		(net "U104_EN")
	)
	(segment
		(start 31.93288 -126.8349)
		(end 32.2453 -126.52248)
		(width 0.127)
		(layer "B.Cu")
		(net "U104_EN")
	)
	(segment
		(start 30.88132 -126.8349)
		(end 30.83052 -126.8857)
		(width 0.127)
		(layer "B.Cu")
		(net "U104_EN")
	)
	(segment
		(start 32.2453 -125.864112)
		(end 32.2453 -124.53874)
		(width 0.127)
		(layer "B.Cu")
		(net "U104_EN")
	)
	(segment
		(start 32.2453 -126.52248)
		(end 32.2453 -125.864112)
		(width 0.127)
		(layer "B.Cu")
		(net "U104_EN")
	)
	(segment
		(start 52.900072 -140.599922)
		(end 53.299868 -140.200126)
		(width 0.127)
		(layer "F.Cu")
		(net "SYS_RST_EN")
	)
	(segment
		(start 52.899818 -140.599922)
		(end 52.900072 -140.599922)
		(width 0.127)
		(layer "F.Cu")
		(net "SYS_RST_EN")
	)
	(via
		(at 68.185792 -132.283454)
		(size 0.6096)
		(drill 0.3048)
		(layers "F.Cu" "B.Cu")
		(net "SYS_RST_EN")
	)
	(via
		(at 71.358506 -128.19507)
		(size 0.508)
		(drill 0.254)
		(layers "F.Cu" "B.Cu")
		(net "SYS_RST_EN")
	)
	(via
		(at 53.299868 -140.200126)
		(size 0.4572)
		(drill 0.2032)
		(layers "F.Cu" "B.Cu")
		(net "SYS_RST_EN")
	)
	(via
		(at 33.724596 -126.238)
		(size 0.508)
		(drill 0.254)
		(layers "F.Cu" "B.Cu")
		(net "SYS_RST_EN")
	)
	(segment
		(start 32.82188 -126.8349)
		(end 33.127696 -126.8349)
		(width 0.127)
		(layer "B.Cu")
		(net "SYS_RST_EN")
	)
	(segment
		(start 55.536592 -139.00658)
		(end 56.467756 -139.00658)
		(width 0.127)
		(layer "B.Cu")
		(net "SYS_RST_EN")
	)
	(segment
		(start 60.983876 -135.8011)
		(end 66.4718 -135.8011)
		(width 0.127)
		(layer "B.Cu")
		(net "SYS_RST_EN")
	)
	(segment
		(start 53.6702 -139.8016)
		(end 55.05577 -139.8016)
		(width 0.127)
		(layer "B.Cu")
		(net "SYS_RST_EN")
	)
	(segment
		(start 53.299868 -140.200126)
		(end 53.299868 -140.171932)
		(width 0.127)
		(layer "B.Cu")
		(net "SYS_RST_EN")
	)
	(segment
		(start 55.05577 -139.8016)
		(end 55.306214 -139.551156)
		(width 0.127)
		(layer "B.Cu")
		(net "SYS_RST_EN")
	)
	(segment
		(start 55.306214 -139.551156)
		(end 55.306214 -139.236958)
		(width 0.127)
		(layer "B.Cu")
		(net "SYS_RST_EN")
	)
	(segment
		(start 53.299868 -140.171932)
		(end 53.6702 -139.8016)
		(width 0.127)
		(layer "B.Cu")
		(net "SYS_RST_EN")
	)
	(segment
		(start 66.4718 -135.8011)
		(end 68.185792 -134.087108)
		(width 0.127)
		(layer "B.Cu")
		(net "SYS_RST_EN")
	)
	(segment
		(start 68.185792 -132.283454)
		(end 68.185792 -131.367784)
		(width 0.127)
		(layer "B.Cu")
		(net "SYS_RST_EN")
	)
	(segment
		(start 57.361836 -138.1125)
		(end 58.672476 -138.1125)
		(width 0.127)
		(layer "B.Cu")
		(net "SYS_RST_EN")
	)
	(segment
		(start 55.306214 -139.236958)
		(end 55.536592 -139.00658)
		(width 0.127)
		(layer "B.Cu")
		(net "SYS_RST_EN")
	)
	(segment
		(start 33.127696 -126.8349)
		(end 33.724596 -126.238)
		(width 0.127)
		(layer "B.Cu")
		(net "SYS_RST_EN")
	)
	(segment
		(start 56.467756 -139.00658)
		(end 57.361836 -138.1125)
		(width 0.127)
		(layer "B.Cu")
		(net "SYS_RST_EN")
	)
	(segment
		(start 68.185792 -134.087108)
		(end 68.185792 -132.283454)
		(width 0.127)
		(layer "B.Cu")
		(net "SYS_RST_EN")
	)
	(segment
		(start 68.185792 -131.367784)
		(end 71.358506 -128.19507)
		(width 0.127)
		(layer "B.Cu")
		(net "SYS_RST_EN")
	)
	(segment
		(start 58.672476 -138.1125)
		(end 60.983876 -135.8011)
		(width 0.127)
		(layer "B.Cu")
		(net "SYS_RST_EN")
	)
	(segment
		(start 71.3359 -126.401068)
		(end 71.3359 -128.172464)
		(width 0.127)
		(layer "In5.Cu")
		(net "SYS_RST_EN")
	)
	(segment
		(start 33.724596 -126.238)
		(end 34.257996 -126.7714)
		(width 0.127)
		(layer "In5.Cu")
		(net "SYS_RST_EN")
	)
	(segment
		(start 67.56908 -125.168152)
		(end 68.384928 -125.984)
		(width 0.127)
		(layer "In5.Cu")
		(net "SYS_RST_EN")
	)
	(segment
		(start 71.3359 -128.172464)
		(end 71.358506 -128.19507)
		(width 0.127)
		(layer "In5.Cu")
		(net "SYS_RST_EN")
	)
	(segment
		(start 68.384928 -125.984)
		(end 70.918832 -125.984)
		(width 0.127)
		(layer "In5.Cu")
		(net "SYS_RST_EN")
	)
	(segment
		(start 55.324248 -125.168152)
		(end 67.56908 -125.168152)
		(width 0.127)
		(layer "In5.Cu")
		(net "SYS_RST_EN")
	)
	(segment
		(start 41.955466 -126.065534)
		(end 54.426866 -126.065534)
		(width 0.127)
		(layer "In5.Cu")
		(net "SYS_RST_EN")
	)
	(segment
		(start 70.918832 -125.984)
		(end 71.3359 -126.401068)
		(width 0.127)
		(layer "In5.Cu")
		(net "SYS_RST_EN")
	)
	(segment
		(start 34.257996 -126.7714)
		(end 41.2496 -126.7714)
		(width 0.127)
		(layer "In5.Cu")
		(net "SYS_RST_EN")
	)
	(segment
		(start 54.426866 -126.065534)
		(end 55.324248 -125.168152)
		(width 0.127)
		(layer "In5.Cu")
		(net "SYS_RST_EN")
	)
	(segment
		(start 41.2496 -126.7714)
		(end 41.955466 -126.065534)
		(width 0.127)
		(layer "In5.Cu")
		(net "SYS_RST_EN")
	)
	(segment
		(start 140.9954 -16.1036)
		(end 140.9954 -15.27302)
		(width 0.127)
		(layer "F.Cu")
		(net "IOC_EXT2_LED_Y")
	)
	(segment
		(start 181.99989 -72.69988)
		(end 181.99989 -72.701912)
		(width 0.127)
		(layer "F.Cu")
		(net "IOC_EXT2_LED_Y")
	)
	(segment
		(start 142.631414 -16.461486)
		(end 141.353286 -16.461486)
		(width 0.127)
		(layer "F.Cu")
		(net "IOC_EXT2_LED_Y")
	)
	(segment
		(start 141.353286 -16.461486)
		(end 140.9954 -16.1036)
		(width 0.127)
		(layer "F.Cu")
		(net "IOC_EXT2_LED_Y")
	)
	(segment
		(start 143.383 -16.2814)
		(end 142.8115 -16.2814)
		(width 0.127)
		(layer "F.Cu")
		(net "IOC_EXT2_LED_Y")
	)
	(segment
		(start 142.8115 -16.2814)
		(end 142.631414 -16.461486)
		(width 0.127)
		(layer "F.Cu")
		(net "IOC_EXT2_LED_Y")
	)
	(segment
		(start 181.99989 -72.701912)
		(end 181.597046 -73.104756)
		(width 0.127)
		(layer "F.Cu")
		(net "IOC_EXT2_LED_Y")
	)
	(via
		(at 152.319228 -26.34361)
		(size 0.508)
		(drill 0.254)
		(layers "F.Cu" "B.Cu")
		(net "IOC_EXT2_LED_Y")
	)
	(via
		(at 160.291526 -74.298048)
		(size 0.508)
		(drill 0.254)
		(layers "F.Cu" "B.Cu")
		(net "IOC_EXT2_LED_Y")
	)
	(via
		(at 143.383 -16.2814)
		(size 0.508)
		(drill 0.254)
		(layers "F.Cu" "B.Cu")
		(net "IOC_EXT2_LED_Y")
	)
	(via
		(at 181.597046 -73.104756)
		(size 0.508)
		(drill 0.254)
		(layers "F.Cu" "B.Cu")
		(net "IOC_EXT2_LED_Y")
	)
	(segment
		(start 156.0195 -56.042052)
		(end 158.115 -53.946552)
		(width 0.127)
		(layer "In2.Cu")
		(net "IOC_EXT2_LED_Y")
	)
	(segment
		(start 158.80969 -73.39457)
		(end 158.494222 -73.39457)
		(width 0.127)
		(layer "In2.Cu")
		(net "IOC_EXT2_LED_Y")
	)
	(segment
		(start 158.115 -53.946552)
		(end 158.115 -49.676558)
		(width 0.127)
		(layer "In2.Cu")
		(net "IOC_EXT2_LED_Y")
	)
	(segment
		(start 152.320244 -43.881802)
		(end 152.320244 -26.344626)
		(width 0.127)
		(layer "In2.Cu")
		(net "IOC_EXT2_LED_Y")
	)
	(segment
		(start 152.320244 -26.344626)
		(end 152.319228 -26.34361)
		(width 0.127)
		(layer "In2.Cu")
		(net "IOC_EXT2_LED_Y")
	)
	(segment
		(start 158.809944 -73.394316)
		(end 158.80969 -73.39457)
		(width 0.127)
		(layer "In2.Cu")
		(net "IOC_EXT2_LED_Y")
	)
	(segment
		(start 159.387794 -73.394316)
		(end 158.809944 -73.394316)
		(width 0.127)
		(layer "In2.Cu")
		(net "IOC_EXT2_LED_Y")
	)
	(segment
		(start 158.115 -49.676558)
		(end 152.320244 -43.881802)
		(width 0.127)
		(layer "In2.Cu")
		(net "IOC_EXT2_LED_Y")
	)
	(segment
		(start 158.494222 -73.39457)
		(end 158.493968 -73.394824)
		(width 0.127)
		(layer "In2.Cu")
		(net "IOC_EXT2_LED_Y")
	)
	(segment
		(start 160.291526 -74.298048)
		(end 159.387794 -73.394316)
		(width 0.127)
		(layer "In2.Cu")
		(net "IOC_EXT2_LED_Y")
	)
	(segment
		(start 157.862524 -73.394824)
		(end 156.0195 -71.5518)
		(width 0.127)
		(layer "In2.Cu")
		(net "IOC_EXT2_LED_Y")
	)
	(segment
		(start 156.0195 -71.5518)
		(end 156.0195 -56.042052)
		(width 0.127)
		(layer "In2.Cu")
		(net "IOC_EXT2_LED_Y")
	)
	(segment
		(start 158.493968 -73.394824)
		(end 157.862524 -73.394824)
		(width 0.127)
		(layer "In2.Cu")
		(net "IOC_EXT2_LED_Y")
	)
	(segment
		(start 143.8529 -16.2814)
		(end 144.0053 -16.129)
		(width 0.127)
		(layer "In5.Cu")
		(net "IOC_EXT2_LED_Y")
	)
	(segment
		(start 174.6123 -77.978)
		(end 169.244518 -77.978)
		(width 0.127)
		(layer "In5.Cu")
		(net "IOC_EXT2_LED_Y")
	)
	(segment
		(start 175.3743 -78.74)
		(end 174.6123 -77.978)
		(width 0.127)
		(layer "In5.Cu")
		(net "IOC_EXT2_LED_Y")
	)
	(segment
		(start 168.9227 -78.2193)
		(end 168.402 -78.74)
		(width 0.127)
		(layer "In5.Cu")
		(net "IOC_EXT2_LED_Y")
	)
	(segment
		(start 180.5559 -75.9587)
		(end 177.7746 -78.74)
		(width 0.127)
		(layer "In5.Cu")
		(net "IOC_EXT2_LED_Y")
	)
	(segment
		(start 144.784318 -16.129)
		(end 148.9456 -20.290282)
		(width 0.127)
		(layer "In5.Cu")
		(net "IOC_EXT2_LED_Y")
	)
	(segment
		(start 164.771324 -78.74)
		(end 161.10331 -75.071986)
		(width 0.127)
		(layer "In5.Cu")
		(net "IOC_EXT2_LED_Y")
	)
	(segment
		(start 144.0053 -16.129)
		(end 144.784318 -16.129)
		(width 0.127)
		(layer "In5.Cu")
		(net "IOC_EXT2_LED_Y")
	)
	(segment
		(start 161.10331 -75.071986)
		(end 161.065464 -75.071986)
		(width 0.127)
		(layer "In5.Cu")
		(net "IOC_EXT2_LED_Y")
	)
	(segment
		(start 161.065464 -75.071986)
		(end 160.291526 -74.298048)
		(width 0.127)
		(layer "In5.Cu")
		(net "IOC_EXT2_LED_Y")
	)
	(segment
		(start 177.7746 -78.74)
		(end 175.3743 -78.74)
		(width 0.127)
		(layer "In5.Cu")
		(net "IOC_EXT2_LED_Y")
	)
	(segment
		(start 169.003218 -78.2193)
		(end 168.9227 -78.2193)
		(width 0.127)
		(layer "In5.Cu")
		(net "IOC_EXT2_LED_Y")
	)
	(segment
		(start 148.9456 -20.290282)
		(end 148.9456 -22.969982)
		(width 0.127)
		(layer "In5.Cu")
		(net "IOC_EXT2_LED_Y")
	)
	(segment
		(start 169.244518 -77.978)
		(end 169.003218 -78.2193)
		(width 0.127)
		(layer "In5.Cu")
		(net "IOC_EXT2_LED_Y")
	)
	(segment
		(start 143.383 -16.2814)
		(end 143.8529 -16.2814)
		(width 0.127)
		(layer "In5.Cu")
		(net "IOC_EXT2_LED_Y")
	)
	(segment
		(start 168.402 -78.74)
		(end 164.771324 -78.74)
		(width 0.127)
		(layer "In5.Cu")
		(net "IOC_EXT2_LED_Y")
	)
	(segment
		(start 148.9456 -22.969982)
		(end 152.319228 -26.34361)
		(width 0.127)
		(layer "In5.Cu")
		(net "IOC_EXT2_LED_Y")
	)
	(segment
		(start 180.5559 -74.145902)
		(end 180.5559 -75.9587)
		(width 0.127)
		(layer "In5.Cu")
		(net "IOC_EXT2_LED_Y")
	)
	(segment
		(start 181.597046 -73.104756)
		(end 180.5559 -74.145902)
		(width 0.127)
		(layer "In5.Cu")
		(net "IOC_EXT2_LED_Y")
	)
	(segment
		(start 139.5857 -15.7226)
		(end 139.783312 -15.524988)
		(width 0.127)
		(layer "F.Cu")
		(net "IOC_EXT2_LED_B")
	)
	(segment
		(start 182.399686 -68.300346)
		(end 182.79999 -67.900042)
		(width 0.127)
		(layer "F.Cu")
		(net "IOC_EXT2_LED_B")
	)
	(segment
		(start 182.399686 -68.309236)
		(end 182.399686 -68.300346)
		(width 0.127)
		(layer "F.Cu")
		(net "IOC_EXT2_LED_B")
	)
	(segment
		(start 139.783312 -14.752574)
		(end 140.062966 -14.47292)
		(width 0.127)
		(layer "F.Cu")
		(net "IOC_EXT2_LED_B")
	)
	(segment
		(start 141.64564 -14.58214)
		(end 141.64564 -15.27302)
		(width 0.127)
		(layer "F.Cu")
		(net "IOC_EXT2_LED_B")
	)
	(segment
		(start 140.062966 -14.47292)
		(end 141.53642 -14.47292)
		(width 0.127)
		(layer "F.Cu")
		(net "IOC_EXT2_LED_B")
	)
	(segment
		(start 139.783312 -15.524988)
		(end 139.783312 -14.752574)
		(width 0.127)
		(layer "F.Cu")
		(net "IOC_EXT2_LED_B")
	)
	(segment
		(start 141.53642 -14.47292)
		(end 141.64564 -14.58214)
		(width 0.127)
		(layer "F.Cu")
		(net "IOC_EXT2_LED_B")
	)
	(via
		(at 138.382756 -15.922244)
		(size 0.6096)
		(drill 0.3048)
		(layers "F.Cu" "B.Cu")
		(net "IOC_EXT2_LED_B")
	)
	(via
		(at 163.932362 -75.242166)
		(size 0.508)
		(drill 0.254)
		(layers "F.Cu" "B.Cu")
		(net "IOC_EXT2_LED_B")
	)
	(via
		(at 182.399686 -68.309236)
		(size 0.508)
		(drill 0.254)
		(layers "F.Cu" "B.Cu")
		(net "IOC_EXT2_LED_B")
	)
	(via
		(at 139.5857 -15.7226)
		(size 0.508)
		(drill 0.254)
		(layers "F.Cu" "B.Cu")
		(net "IOC_EXT2_LED_B")
	)
	(via
		(at 151.8793 -14.9733)
		(size 0.508)
		(drill 0.254)
		(layers "F.Cu" "B.Cu")
		(net "IOC_EXT2_LED_B")
	)
	(segment
		(start 137.795 -17.907)
		(end 138.303 -18.415)
		(width 0.127)
		(layer "B.Cu")
		(net "IOC_EXT2_LED_B")
	)
	(segment
		(start 138.303 -18.415)
		(end 140.0175 -18.415)
		(width 0.127)
		(layer "B.Cu")
		(net "IOC_EXT2_LED_B")
	)
	(segment
		(start 138.382756 -15.922244)
		(end 138.5824 -15.7226)
		(width 0.127)
		(layer "B.Cu")
		(net "IOC_EXT2_LED_B")
	)
	(segment
		(start 138.5824 -15.7226)
		(end 139.5857 -15.7226)
		(width 0.127)
		(layer "B.Cu")
		(net "IOC_EXT2_LED_B")
	)
	(segment
		(start 137.795 -16.51)
		(end 137.795 -17.907)
		(width 0.127)
		(layer "B.Cu")
		(net "IOC_EXT2_LED_B")
	)
	(segment
		(start 138.382756 -15.922244)
		(end 137.795 -16.51)
		(width 0.127)
		(layer "B.Cu")
		(net "IOC_EXT2_LED_B")
	)
	(segment
		(start 154.242008 -44.009818)
		(end 154.242008 -21.717762)
		(width 0.127)
		(layer "In2.Cu")
		(net "IOC_EXT2_LED_B")
	)
	(segment
		(start 154.242008 -21.717762)
		(end 152.93975 -20.415504)
		(width 0.127)
		(layer "In2.Cu")
		(net "IOC_EXT2_LED_B")
	)
	(segment
		(start 162.675316 -72.251316)
		(end 158.33598 -72.251316)
		(width 0.127)
		(layer "In2.Cu")
		(net "IOC_EXT2_LED_B")
	)
	(segment
		(start 157.1625 -71.077836)
		(end 157.1625 -56.516016)
		(width 0.127)
		(layer "In2.Cu")
		(net "IOC_EXT2_LED_B")
	)
	(segment
		(start 157.1625 -56.516016)
		(end 159.330898 -54.347618)
		(width 0.127)
		(layer "In2.Cu")
		(net "IOC_EXT2_LED_B")
	)
	(segment
		(start 152.93975 -20.415504)
		(end 152.93975 -16.03375)
		(width 0.127)
		(layer "In2.Cu")
		(net "IOC_EXT2_LED_B")
	)
	(segment
		(start 163.932362 -73.508362)
		(end 162.675316 -72.251316)
		(width 0.127)
		(layer "In2.Cu")
		(net "IOC_EXT2_LED_B")
	)
	(segment
		(start 152.93975 -16.03375)
		(end 151.8793 -14.9733)
		(width 0.127)
		(layer "In2.Cu")
		(net "IOC_EXT2_LED_B")
	)
	(segment
		(start 163.932362 -75.242166)
		(end 163.932362 -73.508362)
		(width 0.127)
		(layer "In2.Cu")
		(net "IOC_EXT2_LED_B")
	)
	(segment
		(start 159.330898 -54.347618)
		(end 159.330898 -49.098708)
		(width 0.127)
		(layer "In2.Cu")
		(net "IOC_EXT2_LED_B")
	)
	(segment
		(start 158.33598 -72.251316)
		(end 157.1625 -71.077836)
		(width 0.127)
		(layer "In2.Cu")
		(net "IOC_EXT2_LED_B")
	)
	(segment
		(start 159.330898 -49.098708)
		(end 154.242008 -44.009818)
		(width 0.127)
		(layer "In2.Cu")
		(net "IOC_EXT2_LED_B")
	)
	(segment
		(start 139.5857 -15.7226)
		(end 140.335 -14.9733)
		(width 0.127)
		(layer "In5.Cu")
		(net "IOC_EXT2_LED_B")
	)
	(segment
		(start 165.350952 -76.660756)
		(end 169.043604 -76.660756)
		(width 0.127)
		(layer "In5.Cu")
		(net "IOC_EXT2_LED_B")
	)
	(segment
		(start 172.687488 -76.670662)
		(end 173.002956 -76.670662)
		(width 0.127)
		(layer "In5.Cu")
		(net "IOC_EXT2_LED_B")
	)
	(segment
		(start 180.354986 -70.539356)
		(end 180.354986 -70.353936)
		(width 0.127)
		(layer "In5.Cu")
		(net "IOC_EXT2_LED_B")
	)
	(segment
		(start 170.58259 -76.670408)
		(end 172.687234 -76.670408)
		(width 0.127)
		(layer "In5.Cu")
		(net "IOC_EXT2_LED_B")
	)
	(segment
		(start 174.438564 -76.670154)
		(end 174.447962 -76.660756)
		(width 0.127)
		(layer "In5.Cu")
		(net "IOC_EXT2_LED_B")
	)
	(segment
		(start 173.003464 -76.670154)
		(end 174.438564 -76.670154)
		(width 0.127)
		(layer "In5.Cu")
		(net "IOC_EXT2_LED_B")
	)
	(segment
		(start 180.354986 -70.353936)
		(end 182.399686 -68.309236)
		(width 0.127)
		(layer "In5.Cu")
		(net "IOC_EXT2_LED_B")
	)
	(segment
		(start 163.932362 -75.242166)
		(end 165.350952 -76.660756)
		(width 0.127)
		(layer "In5.Cu")
		(net "IOC_EXT2_LED_B")
	)
	(segment
		(start 173.002956 -76.670662)
		(end 173.003464 -76.670154)
		(width 0.127)
		(layer "In5.Cu")
		(net "IOC_EXT2_LED_B")
	)
	(segment
		(start 169.043604 -76.660756)
		(end 169.052748 -76.6699)
		(width 0.127)
		(layer "In5.Cu")
		(net "IOC_EXT2_LED_B")
	)
	(segment
		(start 170.582082 -76.6699)
		(end 170.58259 -76.670408)
		(width 0.127)
		(layer "In5.Cu")
		(net "IOC_EXT2_LED_B")
	)
	(segment
		(start 172.687234 -76.670408)
		(end 172.687488 -76.670662)
		(width 0.127)
		(layer "In5.Cu")
		(net "IOC_EXT2_LED_B")
	)
	(segment
		(start 179.142136 -71.752206)
		(end 180.354986 -70.539356)
		(width 0.127)
		(layer "In5.Cu")
		(net "IOC_EXT2_LED_B")
	)
	(segment
		(start 169.052748 -76.6699)
		(end 170.582082 -76.6699)
		(width 0.127)
		(layer "In5.Cu")
		(net "IOC_EXT2_LED_B")
	)
	(segment
		(start 174.447962 -76.660756)
		(end 176.426368 -76.660756)
		(width 0.127)
		(layer "In5.Cu")
		(net "IOC_EXT2_LED_B")
	)
	(segment
		(start 140.335 -14.9733)
		(end 151.8793 -14.9733)
		(width 0.127)
		(layer "In5.Cu")
		(net "IOC_EXT2_LED_B")
	)
	(segment
		(start 176.426368 -76.660756)
		(end 179.142136 -73.944988)
		(width 0.127)
		(layer "In5.Cu")
		(net "IOC_EXT2_LED_B")
	)
	(segment
		(start 179.142136 -73.944988)
		(end 179.142136 -71.752206)
		(width 0.127)
		(layer "In5.Cu")
		(net "IOC_EXT2_LED_B")
	)
	(segment
		(start 197.527164 -11.107166)
		(end 197.2564 -10.836402)
		(width 0.127)
		(layer "F.Cu")
		(net "IOC_EXT1_LED_Y")
	)
	(segment
		(start 199.355456 -11.107166)
		(end 197.527164 -11.107166)
		(width 0.127)
		(layer "F.Cu")
		(net "IOC_EXT1_LED_Y")
	)
	(segment
		(start 197.2564 -10.836402)
		(end 197.2564 -8.9535)
		(width 0.127)
		(layer "F.Cu")
		(net "IOC_EXT1_LED_Y")
	)
	(segment
		(start 199.75068 -11.953748)
		(end 199.75068 -11.50239)
		(width 0.127)
		(layer "F.Cu")
		(net "IOC_EXT1_LED_Y")
	)
	(segment
		(start 199.75068 -11.50239)
		(end 199.355456 -11.107166)
		(width 0.127)
		(layer "F.Cu")
		(net "IOC_EXT1_LED_Y")
	)
	(segment
		(start 178.910488 -70.302882)
		(end 179.713382 -69.499988)
		(width 0.127)
		(layer "F.Cu")
		(net "IOC_EXT1_LED_Y")
	)
	(segment
		(start 178.910488 -71.132954)
		(end 178.910488 -70.302882)
		(width 0.127)
		(layer "F.Cu")
		(net "IOC_EXT1_LED_Y")
	)
	(segment
		(start 178.546506 -71.496936)
		(end 178.910488 -71.132954)
		(width 0.127)
		(layer "F.Cu")
		(net "IOC_EXT1_LED_Y")
	)
	(segment
		(start 179.713382 -69.499988)
		(end 181.200044 -69.499988)
		(width 0.127)
		(layer "F.Cu")
		(net "IOC_EXT1_LED_Y")
	)
	(via
		(at 197.527164 -11.107166)
		(size 0.6604)
		(drill 0.3302)
		(layers "F.Cu" "B.Cu")
		(net "IOC_EXT1_LED_Y")
	)
	(via
		(at 197.2564 -8.9535)
		(size 0.508)
		(drill 0.254)
		(layers "F.Cu" "B.Cu")
		(net "IOC_EXT1_LED_Y")
	)
	(via
		(at 163.068762 -75.247246)
		(size 0.508)
		(drill 0.254)
		(layers "F.Cu" "B.Cu")
		(net "IOC_EXT1_LED_Y")
	)
	(via
		(at 169.2656 -5.6388)
		(size 0.508)
		(drill 0.254)
		(layers "F.Cu" "B.Cu")
		(net "IOC_EXT1_LED_Y")
	)
	(via
		(at 178.546506 -71.496936)
		(size 0.508)
		(drill 0.254)
		(layers "F.Cu" "B.Cu")
		(net "IOC_EXT1_LED_Y")
	)
	(segment
		(start 163.068762 -73.299828)
		(end 162.40125 -72.632316)
		(width 0.127)
		(layer "In2.Cu")
		(net "IOC_EXT1_LED_Y")
	)
	(segment
		(start 162.40125 -72.632316)
		(end 158.493968 -72.632316)
		(width 0.127)
		(layer "In2.Cu")
		(net "IOC_EXT1_LED_Y")
	)
	(segment
		(start 158.178246 -72.63257)
		(end 156.7815 -71.235824)
		(width 0.127)
		(layer "In2.Cu")
		(net "IOC_EXT1_LED_Y")
	)
	(segment
		(start 167.9448 -4.318)
		(end 169.2656 -5.6388)
		(width 0.127)
		(layer "In2.Cu")
		(net "IOC_EXT1_LED_Y")
	)
	(segment
		(start 153.5176 -10.94486)
		(end 153.5176 -4.8895)
		(width 0.127)
		(layer "In2.Cu")
		(net "IOC_EXT1_LED_Y")
	)
	(segment
		(start 158.493714 -72.63257)
		(end 158.178246 -72.63257)
		(width 0.127)
		(layer "In2.Cu")
		(net "IOC_EXT1_LED_Y")
	)
	(segment
		(start 156.7815 -71.235824)
		(end 156.7815 -56.358028)
		(width 0.127)
		(layer "In2.Cu")
		(net "IOC_EXT1_LED_Y")
	)
	(segment
		(start 158.877 -54.262528)
		(end 158.877 -49.360582)
		(width 0.127)
		(layer "In2.Cu")
		(net "IOC_EXT1_LED_Y")
	)
	(segment
		(start 153.360374 -43.843956)
		(end 153.360374 -21.775674)
		(width 0.127)
		(layer "In2.Cu")
		(net "IOC_EXT1_LED_Y")
	)
	(segment
		(start 151.3586 -13.10386)
		(end 153.5176 -10.94486)
		(width 0.127)
		(layer "In2.Cu")
		(net "IOC_EXT1_LED_Y")
	)
	(segment
		(start 163.068762 -75.247246)
		(end 163.068762 -73.299828)
		(width 0.127)
		(layer "In2.Cu")
		(net "IOC_EXT1_LED_Y")
	)
	(segment
		(start 152.2476 -20.6629)
		(end 152.2476 -16.891254)
		(width 0.127)
		(layer "In2.Cu")
		(net "IOC_EXT1_LED_Y")
	)
	(segment
		(start 152.2476 -16.891254)
		(end 151.3586 -16.002254)
		(width 0.127)
		(layer "In2.Cu")
		(net "IOC_EXT1_LED_Y")
	)
	(segment
		(start 156.7815 -56.358028)
		(end 158.877 -54.262528)
		(width 0.127)
		(layer "In2.Cu")
		(net "IOC_EXT1_LED_Y")
	)
	(segment
		(start 158.877 -49.360582)
		(end 153.360374 -43.843956)
		(width 0.127)
		(layer "In2.Cu")
		(net "IOC_EXT1_LED_Y")
	)
	(segment
		(start 153.360374 -21.775674)
		(end 152.2476 -20.6629)
		(width 0.127)
		(layer "In2.Cu")
		(net "IOC_EXT1_LED_Y")
	)
	(segment
		(start 153.5176 -4.8895)
		(end 154.0891 -4.318)
		(width 0.127)
		(layer "In2.Cu")
		(net "IOC_EXT1_LED_Y")
	)
	(segment
		(start 158.493968 -72.632316)
		(end 158.493714 -72.63257)
		(width 0.127)
		(layer "In2.Cu")
		(net "IOC_EXT1_LED_Y")
	)
	(segment
		(start 151.3586 -16.002254)
		(end 151.3586 -13.10386)
		(width 0.127)
		(layer "In2.Cu")
		(net "IOC_EXT1_LED_Y")
	)
	(segment
		(start 154.0891 -4.318)
		(end 167.9448 -4.318)
		(width 0.127)
		(layer "In2.Cu")
		(net "IOC_EXT1_LED_Y")
	)
	(segment
		(start 174.973996 -75.959208)
		(end 175.212248 -75.720956)
		(width 0.127)
		(layer "In5.Cu")
		(net "IOC_EXT1_LED_Y")
	)
	(segment
		(start 164.345366 -74.772266)
		(end 165.532308 -75.959208)
		(width 0.127)
		(layer "In5.Cu")
		(net "IOC_EXT1_LED_Y")
	)
	(segment
		(start 185.193178 -6.046978)
		(end 173.35881 -6.046978)
		(width 0.127)
		(layer "In5.Cu")
		(net "IOC_EXT1_LED_Y")
	)
	(segment
		(start 168.848278 -75.959208)
		(end 169.17797 -76.2889)
		(width 0.127)
		(layer "In5.Cu")
		(net "IOC_EXT1_LED_Y")
	)
	(segment
		(start 170.740578 -76.289408)
		(end 172.845222 -76.289408)
		(width 0.127)
		(layer "In5.Cu")
		(net "IOC_EXT1_LED_Y")
	)
	(segment
		(start 172.845222 -76.289408)
		(end 172.845476 -76.289154)
		(width 0.127)
		(layer "In5.Cu")
		(net "IOC_EXT1_LED_Y")
	)
	(segment
		(start 175.212248 -75.720956)
		(end 175.42891 -75.720956)
		(width 0.127)
		(layer "In5.Cu")
		(net "IOC_EXT1_LED_Y")
	)
	(segment
		(start 165.532308 -75.959208)
		(end 168.848278 -75.959208)
		(width 0.127)
		(layer "In5.Cu")
		(net "IOC_EXT1_LED_Y")
	)
	(segment
		(start 178.546506 -72.60336)
		(end 178.546506 -71.496936)
		(width 0.127)
		(layer "In5.Cu")
		(net "IOC_EXT1_LED_Y")
	)
	(segment
		(start 174.610522 -75.959208)
		(end 174.973996 -75.959208)
		(width 0.127)
		(layer "In5.Cu")
		(net "IOC_EXT1_LED_Y")
	)
	(segment
		(start 170.74007 -76.2889)
		(end 170.740578 -76.289408)
		(width 0.127)
		(layer "In5.Cu")
		(net "IOC_EXT1_LED_Y")
	)
	(segment
		(start 197.2564 -8.9535)
		(end 188.0997 -8.9535)
		(width 0.127)
		(layer "In5.Cu")
		(net "IOC_EXT1_LED_Y")
	)
	(segment
		(start 172.845476 -76.289154)
		(end 174.280576 -76.289154)
		(width 0.127)
		(layer "In5.Cu")
		(net "IOC_EXT1_LED_Y")
	)
	(segment
		(start 163.068762 -75.247246)
		(end 163.543742 -74.772266)
		(width 0.127)
		(layer "In5.Cu")
		(net "IOC_EXT1_LED_Y")
	)
	(segment
		(start 169.17797 -76.2889)
		(end 170.74007 -76.2889)
		(width 0.127)
		(layer "In5.Cu")
		(net "IOC_EXT1_LED_Y")
	)
	(segment
		(start 163.543742 -74.772266)
		(end 164.345366 -74.772266)
		(width 0.127)
		(layer "In5.Cu")
		(net "IOC_EXT1_LED_Y")
	)
	(segment
		(start 174.280576 -76.289154)
		(end 174.610522 -75.959208)
		(width 0.127)
		(layer "In5.Cu")
		(net "IOC_EXT1_LED_Y")
	)
	(segment
		(start 188.0997 -8.9535)
		(end 185.193178 -6.046978)
		(width 0.127)
		(layer "In5.Cu")
		(net "IOC_EXT1_LED_Y")
	)
	(segment
		(start 175.42891 -75.720956)
		(end 178.546506 -72.60336)
		(width 0.127)
		(layer "In5.Cu")
		(net "IOC_EXT1_LED_Y")
	)
	(segment
		(start 173.35881 -6.046978)
		(end 172.950632 -5.6388)
		(width 0.127)
		(layer "In5.Cu")
		(net "IOC_EXT1_LED_Y")
	)
	(segment
		(start 172.950632 -5.6388)
		(end 169.2656 -5.6388)
		(width 0.127)
		(layer "In5.Cu")
		(net "IOC_EXT1_LED_Y")
	)
	(segment
		(start 199.10044 -11.953748)
		(end 198.32701 -11.953748)
		(width 0.127)
		(layer "F.Cu")
		(net "IOC_EXT1_LED_B")
	)
	(segment
		(start 182.79999 -69.499988)
		(end 182.79999 -69.504052)
		(width 0.127)
		(layer "F.Cu")
		(net "IOC_EXT1_LED_B")
	)
	(segment
		(start 194.3862 -25.3365)
		(end 194.3862 -23.811992)
		(width 0.127)
		(layer "F.Cu")
		(net "IOC_EXT1_LED_B")
	)
	(segment
		(start 182.79999 -69.504052)
		(end 182.406798 -69.897244)
		(width 0.127)
		(layer "F.Cu")
		(net "IOC_EXT1_LED_B")
	)
	(segment
		(start 195.453 -23.114)
		(end 195.084192 -23.114)
		(width 0.127)
		(layer "F.Cu")
		(net "IOC_EXT1_LED_B")
	)
	(segment
		(start 195.084192 -23.114)
		(end 194.63004 -23.568152)
		(width 0.127)
		(layer "F.Cu")
		(net "IOC_EXT1_LED_B")
	)
	(segment
		(start 194.3862 -23.811992)
		(end 194.63004 -23.568152)
		(width 0.127)
		(layer "F.Cu")
		(net "IOC_EXT1_LED_B")
	)
	(via
		(at 194.63004 -23.568152)
		(size 0.6604)
		(drill 0.3302)
		(layers "F.Cu" "B.Cu")
		(net "IOC_EXT1_LED_B")
	)
	(via
		(at 162.205162 -75.26528)
		(size 0.508)
		(drill 0.254)
		(layers "F.Cu" "B.Cu")
		(net "IOC_EXT1_LED_B")
	)
	(via
		(at 198.32701 -11.953748)
		(size 0.508)
		(drill 0.254)
		(layers "F.Cu" "B.Cu")
		(net "IOC_EXT1_LED_B")
	)
	(via
		(at 182.406798 -69.897244)
		(size 0.508)
		(drill 0.254)
		(layers "F.Cu" "B.Cu")
		(net "IOC_EXT1_LED_B")
	)
	(via
		(at 151.4602 -17.0053)
		(size 0.508)
		(drill 0.254)
		(layers "F.Cu" "B.Cu")
		(net "IOC_EXT1_LED_B")
	)
	(via
		(at 195.453 -23.114)
		(size 0.508)
		(drill 0.254)
		(layers "F.Cu" "B.Cu")
		(net "IOC_EXT1_LED_B")
	)
	(segment
		(start 156.4005 -71.393812)
		(end 156.4005 -56.20004)
		(width 0.127)
		(layer "In2.Cu")
		(net "IOC_EXT1_LED_B")
	)
	(segment
		(start 162.687762 -74.78268)
		(end 162.687762 -73.457816)
		(width 0.127)
		(layer "In2.Cu")
		(net "IOC_EXT1_LED_B")
	)
	(segment
		(start 162.687762 -73.457816)
		(end 162.243262 -73.013316)
		(width 0.127)
		(layer "In2.Cu")
		(net "IOC_EXT1_LED_B")
	)
	(segment
		(start 158.651956 -73.013316)
		(end 158.651702 -73.01357)
		(width 0.127)
		(layer "In2.Cu")
		(net "IOC_EXT1_LED_B")
	)
	(segment
		(start 158.496 -54.10454)
		(end 158.496 -49.51857)
		(width 0.127)
		(layer "In2.Cu")
		(net "IOC_EXT1_LED_B")
	)
	(segment
		(start 197.866 -23.114)
		(end 195.453 -23.114)
		(width 0.127)
		(layer "In2.Cu")
		(net "IOC_EXT1_LED_B")
	)
	(segment
		(start 162.205162 -75.26528)
		(end 162.687762 -74.78268)
		(width 0.127)
		(layer "In2.Cu")
		(net "IOC_EXT1_LED_B")
	)
	(segment
		(start 198.6661 -22.3139)
		(end 197.866 -23.114)
		(width 0.127)
		(layer "In2.Cu")
		(net "IOC_EXT1_LED_B")
	)
	(segment
		(start 156.4005 -56.20004)
		(end 158.496 -54.10454)
		(width 0.127)
		(layer "In2.Cu")
		(net "IOC_EXT1_LED_B")
	)
	(segment
		(start 151.4602 -20.6121)
		(end 151.4602 -17.0053)
		(width 0.127)
		(layer "In2.Cu")
		(net "IOC_EXT1_LED_B")
	)
	(segment
		(start 158.020512 -73.013824)
		(end 156.4005 -71.393812)
		(width 0.127)
		(layer "In2.Cu")
		(net "IOC_EXT1_LED_B")
	)
	(segment
		(start 198.32701 -11.953748)
		(end 198.6661 -12.292838)
		(width 0.127)
		(layer "In2.Cu")
		(net "IOC_EXT1_LED_B")
	)
	(segment
		(start 158.336234 -73.01357)
		(end 158.33598 -73.013824)
		(width 0.127)
		(layer "In2.Cu")
		(net "IOC_EXT1_LED_B")
	)
	(segment
		(start 152.979374 -44.001944)
		(end 152.979374 -22.131274)
		(width 0.127)
		(layer "In2.Cu")
		(net "IOC_EXT1_LED_B")
	)
	(segment
		(start 152.979374 -22.131274)
		(end 151.4602 -20.6121)
		(width 0.127)
		(layer "In2.Cu")
		(net "IOC_EXT1_LED_B")
	)
	(segment
		(start 158.496 -49.51857)
		(end 152.979374 -44.001944)
		(width 0.127)
		(layer "In2.Cu")
		(net "IOC_EXT1_LED_B")
	)
	(segment
		(start 198.6661 -12.292838)
		(end 198.6661 -22.3139)
		(width 0.127)
		(layer "In2.Cu")
		(net "IOC_EXT1_LED_B")
	)
	(segment
		(start 158.33598 -73.013824)
		(end 158.020512 -73.013824)
		(width 0.127)
		(layer "In2.Cu")
		(net "IOC_EXT1_LED_B")
	)
	(segment
		(start 162.243262 -73.013316)
		(end 158.651956 -73.013316)
		(width 0.127)
		(layer "In2.Cu")
		(net "IOC_EXT1_LED_B")
	)
	(segment
		(start 158.651702 -73.01357)
		(end 158.336234 -73.01357)
		(width 0.127)
		(layer "In2.Cu")
		(net "IOC_EXT1_LED_B")
	)
	(segment
		(start 166.971218 -78.119478)
		(end 165.05936 -78.119478)
		(width 0.127)
		(layer "In5.Cu")
		(net "IOC_EXT1_LED_B")
	)
	(segment
		(start 165.05936 -78.119478)
		(end 162.205162 -75.26528)
		(width 0.127)
		(layer "In5.Cu")
		(net "IOC_EXT1_LED_B")
	)
	(segment
		(start 182.406798 -69.897244)
		(end 181.7751 -70.528942)
		(width 0.127)
		(layer "In5.Cu")
		(net "IOC_EXT1_LED_B")
	)
	(segment
		(start 167.811196 -77.2795)
		(end 166.971218 -78.119478)
		(width 0.127)
		(layer "In5.Cu")
		(net "IOC_EXT1_LED_B")
	)
	(segment
		(start 192.861946 -18.7579)
		(end 195.436236 -21.33219)
		(width 0.127)
		(layer "In5.Cu")
		(net "IOC_EXT1_LED_B")
	)
	(segment
		(start 181.7751 -71.851012)
		(end 176.346612 -77.2795)
		(width 0.127)
		(layer "In5.Cu")
		(net "IOC_EXT1_LED_B")
	)
	(segment
		(start 189.184026 -18.7579)
		(end 192.861946 -18.7579)
		(width 0.127)
		(layer "In5.Cu")
		(net "IOC_EXT1_LED_B")
	)
	(segment
		(start 151.4602 -17.0053)
		(end 156.353256 -12.112244)
		(width 0.127)
		(layer "In5.Cu")
		(net "IOC_EXT1_LED_B")
	)
	(segment
		(start 195.436236 -23.097236)
		(end 195.453 -23.114)
		(width 0.127)
		(layer "In5.Cu")
		(net "IOC_EXT1_LED_B")
	)
	(segment
		(start 195.436236 -21.33219)
		(end 195.436236 -23.097236)
		(width 0.127)
		(layer "In5.Cu")
		(net "IOC_EXT1_LED_B")
	)
	(segment
		(start 176.346612 -77.2795)
		(end 167.811196 -77.2795)
		(width 0.127)
		(layer "In5.Cu")
		(net "IOC_EXT1_LED_B")
	)
	(segment
		(start 181.7751 -70.528942)
		(end 181.7751 -71.851012)
		(width 0.127)
		(layer "In5.Cu")
		(net "IOC_EXT1_LED_B")
	)
	(segment
		(start 182.53837 -12.112244)
		(end 189.184026 -18.7579)
		(width 0.127)
		(layer "In5.Cu")
		(net "IOC_EXT1_LED_B")
	)
	(segment
		(start 156.353256 -12.112244)
		(end 182.53837 -12.112244)
		(width 0.127)
		(layer "In5.Cu")
		(net "IOC_EXT1_LED_B")
	)
	(via
		(at 55.8292 -124.5997)
		(size 0.6096)
		(drill 0.3048)
		(layers "F.Cu" "B.Cu")
		(net "DEBUG_RST_BTN_N_R")
	)
	(segment
		(start 55.0164 -128.07442)
		(end 55.0164 -125.485398)
		(width 0.127)
		(layer "B.Cu")
		(net "DEBUG_RST_BTN_N_R")
	)
	(segment
		(start 55.6895 -124.7394)
		(end 54.67858 -124.7394)
		(width 0.127)
		(layer "B.Cu")
		(net "DEBUG_RST_BTN_N_R")
	)
	(segment
		(start 55.278782 -123.693682)
		(end 55.8292 -124.2441)
		(width 0.127)
		(layer "B.Cu")
		(net "DEBUG_RST_BTN_N_R")
	)
	(segment
		(start 55.8292 -124.2441)
		(end 55.8292 -124.5997)
		(width 0.127)
		(layer "B.Cu")
		(net "DEBUG_RST_BTN_N_R")
	)
	(segment
		(start 55.8292 -124.5997)
		(end 55.6895 -124.7394)
		(width 0.127)
		(layer "B.Cu")
		(net "DEBUG_RST_BTN_N_R")
	)
	(segment
		(start 55.0164 -125.485398)
		(end 54.67858 -125.147578)
		(width 0.127)
		(layer "B.Cu")
		(net "DEBUG_RST_BTN_N_R")
	)
	(segment
		(start 54.67858 -125.147578)
		(end 54.67858 -124.7394)
		(width 0.127)
		(layer "B.Cu")
		(net "DEBUG_RST_BTN_N_R")
	)
	(segment
		(start 54.777132 -123.693682)
		(end 55.278782 -123.693682)
		(width 0.127)
		(layer "B.Cu")
		(net "DEBUG_RST_BTN_N_R")
	)
	(segment
		(start 15.500096 -8.750046)
		(end 16.567404 -8.750046)
		(width 0.508)
		(layer "F.Cu")
		(net "RST_BTN_GND")
	)
	(segment
		(start 14.432788 -8.750046)
		(end 15.500096 -8.750046)
		(width 0.508)
		(layer "F.Cu")
		(net "RST_BTN_GND")
	)
	(segment
		(start 8.499856 -8.750046)
		(end 9.567164 -8.750046)
		(width 0.508)
		(layer "F.Cu")
		(net "RST_BTN_GND")
	)
	(segment
		(start 7.432548 -8.750046)
		(end 8.499856 -8.750046)
		(width 0.508)
		(layer "F.Cu")
		(net "RST_BTN_GND")
	)
	(segment
		(start 27.500072 -10.18286)
		(end 27.500072 -11.250168)
		(width 0.508)
		(layer "F.Cu")
		(net "PWR_BTN_GND")
	)
	(segment
		(start 27.500072 -11.250168)
		(end 27.500072 -12.317476)
		(width 0.508)
		(layer "F.Cu")
		(net "PWR_BTN_GND")
	)
	(segment
		(start 20.499832 -11.250168)
		(end 20.499832 -12.317476)
		(width 0.508)
		(layer "F.Cu")
		(net "PWR_BTN_GND")
	)
	(segment
		(start 20.499832 -10.18286)
		(end 20.499832 -11.250168)
		(width 0.508)
		(layer "F.Cu")
		(net "PWR_BTN_GND")
	)
	(segment
		(start 27.500072 -11.250168)
		(end 28.56738 -11.250168)
		(width 0.508)
		(layer "F.Cu")
		(net "PWR_BTN_GND")
	)
	(segment
		(start 19.432524 -11.250168)
		(end 20.499832 -11.250168)
		(width 0.508)
		(layer "F.Cu")
		(net "PWR_BTN_GND")
	)
	(via
		(at 27.0256 -183.6166)
		(size 0.6604)
		(drill 0.3302)
		(layers "F.Cu" "B.Cu")
		(net "P12V_STBY_VIN_PU2")
	)
	(via
		(at 176.149 -140.7922)
		(size 0.6604)
		(drill 0.3302)
		(layers "F.Cu" "B.Cu")
		(net "P12V_STBY_VIN_PU1")
	)
	(segment
		(start 163.9316 -138.0998)
		(end 163.9316 -138.4554)
		(width 0.508)
		(layer "F.Cu")
		(net "P12V_STBY_VCC_PU4")
	)
	(segment
		(start 161.576258 -136.912858)
		(end 161.9504 -137.287)
		(width 0.3048)
		(layer "F.Cu")
		(net "P12V_STBY_VCC_PU4")
	)
	(segment
		(start 163.6014 -137.2362)
		(end 163.576 -137.2108)
		(width 0.508)
		(layer "F.Cu")
		(net "P12V_STBY_VCC_PU4")
	)
	(segment
		(start 160.836864 -136.912858)
		(end 161.576258 -136.912858)
		(width 0.3048)
		(layer "F.Cu")
		(net "P12V_STBY_VCC_PU4")
	)
	(segment
		(start 162.5092 -137.2108)
		(end 162.433 -137.287)
		(width 0.508)
		(layer "F.Cu")
		(net "P12V_STBY_VCC_PU4")
	)
	(segment
		(start 163.576 -137.2108)
		(end 162.5092 -137.2108)
		(width 0.508)
		(layer "F.Cu")
		(net "P12V_STBY_VCC_PU4")
	)
	(segment
		(start 163.6014 -137.2362)
		(end 163.6014 -137.7696)
		(width 0.508)
		(layer "F.Cu")
		(net "P12V_STBY_VCC_PU4")
	)
	(segment
		(start 161.9504 -137.287)
		(end 162.433 -137.287)
		(width 0.3048)
		(layer "F.Cu")
		(net "P12V_STBY_VCC_PU4")
	)
	(segment
		(start 163.6014 -137.7696)
		(end 163.9316 -138.0998)
		(width 0.508)
		(layer "F.Cu")
		(net "P12V_STBY_VCC_PU4")
	)
	(via
		(at 162.433 -137.287)
		(size 0.6604)
		(drill 0.3302)
		(layers "F.Cu" "B.Cu")
		(net "P12V_STBY_VCC_PU4")
	)
	(via
		(at 162.7124 -38.5064)
		(size 0.6604)
		(drill 0.3302)
		(layers "F.Cu" "B.Cu")
		(net "EXT2_CONN_GND")
	)
	(via
		(at 161.2392 -37.5158)
		(size 0.508)
		(drill 0.254)
		(layers "F.Cu" "B.Cu")
		(net "EXT2_CONN_GND")
	)
	(via
		(at 160.2232 -37.4904)
		(size 0.508)
		(drill 0.254)
		(layers "F.Cu" "B.Cu")
		(net "EXT2_CONN_GND")
	)
	(via
		(at 190.6524 -29.0068)
		(size 0.508)
		(drill 0.254)
		(layers "F.Cu" "B.Cu")
		(net "EXT1_CONN_GND")
	)
	(via
		(at 192.3034 -28.702)
		(size 0.6604)
		(drill 0.3302)
		(layers "F.Cu" "B.Cu")
		(net "EXT1_CONN_GND")
	)
	(via
		(at 190.627 -30.099)
		(size 0.508)
		(drill 0.254)
		(layers "F.Cu" "B.Cu")
		(net "EXT1_CONN_GND")
	)
	(segment
		(start 64.15786 -137.67054)
		(end 63.2206 -138.6078)
		(width 0.127)
		(layer "F.Cu")
		(net "COMP_SPARE_1_R")
	)
	(segment
		(start 64.15786 -136.65454)
		(end 64.15786 -136.2583)
		(width 0.127)
		(layer "F.Cu")
		(net "COMP_SPARE_1_R")
	)
	(segment
		(start 64.15786 -136.65454)
		(end 64.15786 -137.67054)
		(width 0.127)
		(layer "F.Cu")
		(net "COMP_SPARE_1_R")
	)
	(segment
		(start 64.15786 -136.2583)
		(end 65.06718 -135.34898)
		(width 0.127)
		(layer "F.Cu")
		(net "COMP_SPARE_1_R")
	)
	(segment
		(start 52.899818 -141.400022)
		(end 52.900072 -141.400022)
		(width 0.127)
		(layer "F.Cu")
		(net "COMP_SPARE_1_R")
	)
	(segment
		(start 52.900072 -141.400022)
		(end 53.299868 -141.000226)
		(width 0.127)
		(layer "F.Cu")
		(net "COMP_SPARE_1_R")
	)
	(via
		(at 64.15786 -136.65454)
		(size 0.6604)
		(drill 0.3302)
		(layers "F.Cu" "B.Cu")
		(net "COMP_SPARE_1_R")
	)
	(via
		(at 63.2206 -138.6078)
		(size 0.508)
		(drill 0.254)
		(layers "F.Cu" "B.Cu")
		(net "COMP_SPARE_1_R")
	)
	(via
		(at 53.299868 -141.000226)
		(size 0.4572)
		(drill 0.2032)
		(layers "F.Cu" "B.Cu")
		(net "COMP_SPARE_1_R")
	)
	(segment
		(start 53.70576 -140.594334)
		(end 53.299868 -141.000226)
		(width 0.127)
		(layer "In5.Cu")
		(net "COMP_SPARE_1_R")
	)
	(segment
		(start 63.2206 -138.6078)
		(end 63.071502 -138.458702)
		(width 0.127)
		(layer "In5.Cu")
		(net "COMP_SPARE_1_R")
	)
	(segment
		(start 59.592972 -138.864594)
		(end 58.668666 -139.7889)
		(width 0.127)
		(layer "In5.Cu")
		(net "COMP_SPARE_1_R")
	)
	(segment
		(start 62.099698 -138.458702)
		(end 61.693806 -138.864594)
		(width 0.127)
		(layer "In5.Cu")
		(net "COMP_SPARE_1_R")
	)
	(segment
		(start 58.668666 -139.7889)
		(end 56.969406 -139.7889)
		(width 0.127)
		(layer "In5.Cu")
		(net "COMP_SPARE_1_R")
	)
	(segment
		(start 63.071502 -138.458702)
		(end 62.099698 -138.458702)
		(width 0.127)
		(layer "In5.Cu")
		(net "COMP_SPARE_1_R")
	)
	(segment
		(start 56.969406 -139.7889)
		(end 56.163972 -140.594334)
		(width 0.127)
		(layer "In5.Cu")
		(net "COMP_SPARE_1_R")
	)
	(segment
		(start 56.163972 -140.594334)
		(end 53.70576 -140.594334)
		(width 0.127)
		(layer "In5.Cu")
		(net "COMP_SPARE_1_R")
	)
	(segment
		(start 61.693806 -138.864594)
		(end 59.592972 -138.864594)
		(width 0.127)
		(layer "In5.Cu")
		(net "COMP_SPARE_1_R")
	)
	(segment
		(start 54.900068 -138.599926)
		(end 54.500018 -138.999976)
		(width 0.127)
		(layer "F.Cu")
		(net "COMP_SPARE_0_R")
	)
	(via
		(at 60.452 -135.255)
		(size 0.6096)
		(drill 0.3048)
		(layers "F.Cu" "B.Cu")
		(net "COMP_SPARE_0_R")
	)
	(via
		(at 54.900068 -138.599926)
		(size 0.4572)
		(drill 0.2032)
		(layers "F.Cu" "B.Cu")
		(net "COMP_SPARE_0_R")
	)
	(segment
		(start 55.974742 -137.778998)
		(end 57.436766 -137.778998)
		(width 0.127)
		(layer "B.Cu")
		(net "COMP_SPARE_0_R")
	)
	(segment
		(start 58.971688 -137.2743)
		(end 60.071 -136.174988)
		(width 0.127)
		(layer "B.Cu")
		(net "COMP_SPARE_0_R")
	)
	(segment
		(start 55.153814 -138.599926)
		(end 55.974742 -137.778998)
		(width 0.127)
		(layer "B.Cu")
		(net "COMP_SPARE_0_R")
	)
	(segment
		(start 60.071 -135.636)
		(end 60.452 -135.255)
		(width 0.127)
		(layer "B.Cu")
		(net "COMP_SPARE_0_R")
	)
	(segment
		(start 57.436766 -137.778998)
		(end 57.941464 -137.2743)
		(width 0.127)
		(layer "B.Cu")
		(net "COMP_SPARE_0_R")
	)
	(segment
		(start 57.941464 -137.2743)
		(end 58.971688 -137.2743)
		(width 0.127)
		(layer "B.Cu")
		(net "COMP_SPARE_0_R")
	)
	(segment
		(start 60.071 -136.174988)
		(end 60.071 -135.636)
		(width 0.127)
		(layer "B.Cu")
		(net "COMP_SPARE_0_R")
	)
	(segment
		(start 54.900068 -138.599926)
		(end 55.153814 -138.599926)
		(width 0.127)
		(layer "B.Cu")
		(net "COMP_SPARE_0_R")
	)
	(segment
		(start 61.8109 -134.93496)
		(end 60.77204 -134.93496)
		(width 0.127)
		(layer "B.Cu")
		(net "COMP_SPARE_0_R")
	)
	(segment
		(start 60.77204 -134.93496)
		(end 60.452 -135.255)
		(width 0.127)
		(layer "B.Cu")
		(net "COMP_SPARE_0_R")
	)
	(segment
		(start 64.701674 -133.151372)
		(end 62.250828 -133.151372)
		(width 0.127)
		(layer "F.Cu")
		(net "BMC_EXT2_LED_Y")
	)
	(segment
		(start 58.575956 -136.244838)
		(end 56.22417 -138.596624)
		(width 0.127)
		(layer "F.Cu")
		(net "BMC_EXT2_LED_Y")
	)
	(segment
		(start 61.1632 -134.239)
		(end 59.157362 -136.244838)
		(width 0.127)
		(layer "F.Cu")
		(net "BMC_EXT2_LED_Y")
	)
	(segment
		(start 86.04377 -73.572624)
		(end 85.803232 -73.332086)
		(width 0.127)
		(layer "F.Cu")
		(net "BMC_EXT2_LED_Y")
	)
	(segment
		(start 86.04377 -93.76283)
		(end 86.04377 -73.572624)
		(width 0.127)
		(layer "F.Cu")
		(net "BMC_EXT2_LED_Y")
	)
	(segment
		(start 55.703216 -138.596624)
		(end 55.299864 -138.999976)
		(width 0.127)
		(layer "F.Cu")
		(net "BMC_EXT2_LED_Y")
	)
	(segment
		(start 85.3186 -96.4565)
		(end 85.3186 -94.488)
		(width 0.127)
		(layer "F.Cu")
		(net "BMC_EXT2_LED_Y")
	)
	(segment
		(start 85.2932 -96.4692)
		(end 85.3059 -96.4692)
		(width 0.127)
		(layer "F.Cu")
		(net "BMC_EXT2_LED_Y")
	)
	(segment
		(start 62.250828 -133.151372)
		(end 61.1632 -134.239)
		(width 0.127)
		(layer "F.Cu")
		(net "BMC_EXT2_LED_Y")
	)
	(segment
		(start 85.3059 -96.4692)
		(end 85.3186 -96.4565)
		(width 0.127)
		(layer "F.Cu")
		(net "BMC_EXT2_LED_Y")
	)
	(segment
		(start 67.379596 -130.47345)
		(end 64.701674 -133.151372)
		(width 0.127)
		(layer "F.Cu")
		(net "BMC_EXT2_LED_Y")
	)
	(segment
		(start 67.379596 -129.416048)
		(end 67.379596 -130.47345)
		(width 0.127)
		(layer "F.Cu")
		(net "BMC_EXT2_LED_Y")
	)
	(segment
		(start 59.157362 -136.244838)
		(end 58.575956 -136.244838)
		(width 0.127)
		(layer "F.Cu")
		(net "BMC_EXT2_LED_Y")
	)
	(segment
		(start 85.3186 -94.488)
		(end 86.04377 -93.76283)
		(width 0.127)
		(layer "F.Cu")
		(net "BMC_EXT2_LED_Y")
	)
	(segment
		(start 56.22417 -138.596624)
		(end 55.703216 -138.596624)
		(width 0.127)
		(layer "F.Cu")
		(net "BMC_EXT2_LED_Y")
	)
	(via
		(at 133.3373 -4.09448)
		(size 0.508)
		(drill 0.254)
		(layers "F.Cu" "B.Cu")
		(net "BMC_EXT2_LED_Y")
	)
	(via
		(at 138.4808 -17.526)
		(size 0.508)
		(drill 0.254)
		(layers "F.Cu" "B.Cu")
		(net "BMC_EXT2_LED_Y")
	)
	(via
		(at 68.0212 -121.8946)
		(size 0.508)
		(drill 0.254)
		(layers "F.Cu" "B.Cu")
		(net "BMC_EXT2_LED_Y")
	)
	(via
		(at 85.803232 -73.332086)
		(size 0.508)
		(drill 0.254)
		(layers "F.Cu" "B.Cu")
		(net "BMC_EXT2_LED_Y")
	)
	(via
		(at 67.379596 -129.416048)
		(size 0.508)
		(drill 0.254)
		(layers "F.Cu" "B.Cu")
		(net "BMC_EXT2_LED_Y")
	)
	(via
		(at 90.118692 -5.702808)
		(size 0.508)
		(drill 0.254)
		(layers "F.Cu" "B.Cu")
		(net "BMC_EXT2_LED_Y")
	)
	(via
		(at 85.2932 -96.4692)
		(size 0.508)
		(drill 0.254)
		(layers "F.Cu" "B.Cu")
		(net "BMC_EXT2_LED_Y")
	)
	(via
		(at 94.2086 -118.0338)
		(size 0.508)
		(drill 0.254)
		(layers "F.Cu" "B.Cu")
		(net "BMC_EXT2_LED_Y")
	)
	(via
		(at 61.1632 -134.239)
		(size 0.6604)
		(drill 0.3302)
		(layers "F.Cu" "B.Cu")
		(net "BMC_EXT2_LED_Y")
	)
	(segment
		(start 68.1482 -121.7676)
		(end 69.9008 -121.7676)
		(width 0.127)
		(layer "B.Cu")
		(net "BMC_EXT2_LED_Y")
	)
	(segment
		(start 82.225642 -114.627914)
		(end 87.104728 -119.507)
		(width 0.127)
		(layer "B.Cu")
		(net "BMC_EXT2_LED_Y")
	)
	(segment
		(start 77.774546 -114.627914)
		(end 82.225642 -114.627914)
		(width 0.127)
		(layer "B.Cu")
		(net "BMC_EXT2_LED_Y")
	)
	(segment
		(start 142.348458 -18.33626)
		(end 141.157706 -18.33626)
		(width 0.127)
		(layer "B.Cu")
		(net "BMC_EXT2_LED_Y")
	)
	(segment
		(start 87.104728 -119.507)
		(end 92.7354 -119.507)
		(width 0.127)
		(layer "B.Cu")
		(net "BMC_EXT2_LED_Y")
	)
	(segment
		(start 140.59916 -17.76476)
		(end 140.0175 -17.76476)
		(width 0.127)
		(layer "B.Cu")
		(net "BMC_EXT2_LED_Y")
	)
	(segment
		(start 92.7354 -119.507)
		(end 94.2086 -118.0338)
		(width 0.127)
		(layer "B.Cu")
		(net "BMC_EXT2_LED_Y")
	)
	(segment
		(start 145.601436 -16.363696)
		(end 144.321022 -16.363696)
		(width 0.127)
		(layer "B.Cu")
		(net "BMC_EXT2_LED_Y")
	)
	(segment
		(start 68.0212 -121.8946)
		(end 68.1482 -121.7676)
		(width 0.127)
		(layer "B.Cu")
		(net "BMC_EXT2_LED_Y")
	)
	(segment
		(start 69.9008 -121.7676)
		(end 70.2818 -121.3866)
		(width 0.127)
		(layer "B.Cu")
		(net "BMC_EXT2_LED_Y")
	)
	(segment
		(start 140.0175 -17.76476)
		(end 138.71956 -17.76476)
		(width 0.127)
		(layer "B.Cu")
		(net "BMC_EXT2_LED_Y")
	)
	(segment
		(start 71.97344 -121.031)
		(end 73.7616 -119.24284)
		(width 0.127)
		(layer "B.Cu")
		(net "BMC_EXT2_LED_Y")
	)
	(segment
		(start 73.7616 -118.64086)
		(end 77.774546 -114.627914)
		(width 0.127)
		(layer "B.Cu")
		(net "BMC_EXT2_LED_Y")
	)
	(segment
		(start 140.59916 -17.777714)
		(end 140.59916 -17.76476)
		(width 0.127)
		(layer "B.Cu")
		(net "BMC_EXT2_LED_Y")
	)
	(segment
		(start 145.7325 -16.49476)
		(end 145.601436 -16.363696)
		(width 0.127)
		(layer "B.Cu")
		(net "BMC_EXT2_LED_Y")
	)
	(segment
		(start 138.71956 -17.76476)
		(end 138.4808 -17.526)
		(width 0.127)
		(layer "B.Cu")
		(net "BMC_EXT2_LED_Y")
	)
	(segment
		(start 141.157706 -18.33626)
		(end 140.59916 -17.777714)
		(width 0.127)
		(layer "B.Cu")
		(net "BMC_EXT2_LED_Y")
	)
	(segment
		(start 71.6026 -121.3866)
		(end 71.9582 -121.031)
		(width 0.127)
		(layer "B.Cu")
		(net "BMC_EXT2_LED_Y")
	)
	(segment
		(start 73.7616 -119.24284)
		(end 73.7616 -118.64086)
		(width 0.127)
		(layer "B.Cu")
		(net "BMC_EXT2_LED_Y")
	)
	(segment
		(start 144.321022 -16.363696)
		(end 142.348458 -18.33626)
		(width 0.127)
		(layer "B.Cu")
		(net "BMC_EXT2_LED_Y")
	)
	(segment
		(start 70.2818 -121.3866)
		(end 71.6026 -121.3866)
		(width 0.127)
		(layer "B.Cu")
		(net "BMC_EXT2_LED_Y")
	)
	(segment
		(start 71.9582 -121.031)
		(end 71.97344 -121.031)
		(width 0.127)
		(layer "B.Cu")
		(net "BMC_EXT2_LED_Y")
	)
	(segment
		(start 84.1248 -45.9232)
		(end 83.345528 -46.702472)
		(width 0.127)
		(layer "In2.Cu")
		(net "BMC_EXT2_LED_Y")
	)
	(segment
		(start 67.056508 -128.86309)
		(end 67.379596 -129.186178)
		(width 0.127)
		(layer "In2.Cu")
		(net "BMC_EXT2_LED_Y")
	)
	(segment
		(start 67.379596 -129.186178)
		(end 67.379596 -129.416048)
		(width 0.127)
		(layer "In2.Cu")
		(net "BMC_EXT2_LED_Y")
	)
	(segment
		(start 141.097254 -5.038598)
		(end 140.153136 -4.09448)
		(width 0.127)
		(layer "In2.Cu")
		(net "BMC_EXT2_LED_Y")
	)
	(segment
		(start 68.0212 -122.173746)
		(end 67.056508 -123.138438)
		(width 0.127)
		(layer "In2.Cu")
		(net "BMC_EXT2_LED_Y")
	)
	(segment
		(start 82.215736 -6.361938)
		(end 79.87538 -8.702294)
		(width 0.127)
		(layer "In2.Cu")
		(net "BMC_EXT2_LED_Y")
	)
	(segment
		(start 85.487002 -36.809934)
		(end 85.487002 -42.52722)
		(width 0.127)
		(layer "In2.Cu")
		(net "BMC_EXT2_LED_Y")
	)
	(segment
		(start 85.787484 -69.252084)
		(end 85.787484 -73.316338)
		(width 0.127)
		(layer "In2.Cu")
		(net "BMC_EXT2_LED_Y")
	)
	(segment
		(start 90.118692 -5.702808)
		(end 89.459562 -6.361938)
		(width 0.127)
		(layer "In2.Cu")
		(net "BMC_EXT2_LED_Y")
	)
	(segment
		(start 85.787484 -73.316338)
		(end 85.803232 -73.332086)
		(width 0.127)
		(layer "In2.Cu")
		(net "BMC_EXT2_LED_Y")
	)
	(segment
		(start 89.459562 -6.361938)
		(end 82.215736 -6.361938)
		(width 0.127)
		(layer "In2.Cu")
		(net "BMC_EXT2_LED_Y")
	)
	(segment
		(start 138.4808 -17.526)
		(end 141.097254 -14.909546)
		(width 0.127)
		(layer "In2.Cu")
		(net "BMC_EXT2_LED_Y")
	)
	(segment
		(start 85.487002 -42.52722)
		(end 84.1248 -43.889422)
		(width 0.127)
		(layer "In2.Cu")
		(net "BMC_EXT2_LED_Y")
	)
	(segment
		(start 68.0212 -121.8946)
		(end 68.0212 -122.173746)
		(width 0.127)
		(layer "In2.Cu")
		(net "BMC_EXT2_LED_Y")
	)
	(segment
		(start 141.097254 -14.909546)
		(end 141.097254 -5.038598)
		(width 0.127)
		(layer "In2.Cu")
		(net "BMC_EXT2_LED_Y")
	)
	(segment
		(start 79.87538 -8.702294)
		(end 79.87538 -31.198312)
		(width 0.127)
		(layer "In2.Cu")
		(net "BMC_EXT2_LED_Y")
	)
	(segment
		(start 67.056508 -123.138438)
		(end 67.056508 -128.86309)
		(width 0.127)
		(layer "In2.Cu")
		(net "BMC_EXT2_LED_Y")
	)
	(segment
		(start 83.345528 -66.810128)
		(end 85.787484 -69.252084)
		(width 0.127)
		(layer "In2.Cu")
		(net "BMC_EXT2_LED_Y")
	)
	(segment
		(start 84.1248 -43.889422)
		(end 84.1248 -45.9232)
		(width 0.127)
		(layer "In2.Cu")
		(net "BMC_EXT2_LED_Y")
	)
	(segment
		(start 140.153136 -4.09448)
		(end 133.3373 -4.09448)
		(width 0.127)
		(layer "In2.Cu")
		(net "BMC_EXT2_LED_Y")
	)
	(segment
		(start 83.345528 -46.702472)
		(end 83.345528 -66.810128)
		(width 0.127)
		(layer "In2.Cu")
		(net "BMC_EXT2_LED_Y")
	)
	(segment
		(start 79.87538 -31.198312)
		(end 85.487002 -36.809934)
		(width 0.127)
		(layer "In2.Cu")
		(net "BMC_EXT2_LED_Y")
	)
	(segment
		(start 85.2932 -96.4692)
		(end 85.2932 -96.7232)
		(width 0.127)
		(layer "In5.Cu")
		(net "BMC_EXT2_LED_Y")
	)
	(segment
		(start 95.325692 -115.062508)
		(end 94.6912 -115.697)
		(width 0.127)
		(layer "In5.Cu")
		(net "BMC_EXT2_LED_Y")
	)
	(segment
		(start 92.432378 -3.389122)
		(end 132.631942 -3.389122)
		(width 0.127)
		(layer "In5.Cu")
		(net "BMC_EXT2_LED_Y")
	)
	(segment
		(start 90.118692 -5.702808)
		(end 92.432378 -3.389122)
		(width 0.127)
		(layer "In5.Cu")
		(net "BMC_EXT2_LED_Y")
	)
	(segment
		(start 95.0976 -108.246418)
		(end 95.0976 -108.2548)
		(width 0.127)
		(layer "In5.Cu")
		(net "BMC_EXT2_LED_Y")
	)
	(segment
		(start 94.6912 -115.697)
		(end 94.6912 -117.5512)
		(width 0.127)
		(layer "In5.Cu")
		(net "BMC_EXT2_LED_Y")
	)
	(segment
		(start 132.631942 -3.389122)
		(end 133.3373 -4.09448)
		(width 0.127)
		(layer "In5.Cu")
		(net "BMC_EXT2_LED_Y")
	)
	(segment
		(start 86.795102 -99.94392)
		(end 95.0976 -108.246418)
		(width 0.127)
		(layer "In5.Cu")
		(net "BMC_EXT2_LED_Y")
	)
	(segment
		(start 85.2932 -96.7232)
		(end 86.795102 -98.225102)
		(width 0.127)
		(layer "In5.Cu")
		(net "BMC_EXT2_LED_Y")
	)
	(segment
		(start 86.795102 -98.225102)
		(end 86.795102 -99.94392)
		(width 0.127)
		(layer "In5.Cu")
		(net "BMC_EXT2_LED_Y")
	)
	(segment
		(start 95.0976 -108.2548)
		(end 95.325692 -108.482892)
		(width 0.127)
		(layer "In5.Cu")
		(net "BMC_EXT2_LED_Y")
	)
	(segment
		(start 94.6912 -117.5512)
		(end 94.2086 -118.0338)
		(width 0.127)
		(layer "In5.Cu")
		(net "BMC_EXT2_LED_Y")
	)
	(segment
		(start 95.325692 -108.482892)
		(end 95.325692 -115.062508)
		(width 0.127)
		(layer "In5.Cu")
		(net "BMC_EXT2_LED_Y")
	)
	(segment
		(start 193.73596 -23.12924)
		(end 193.73596 -25.3365)
		(width 0.127)
		(layer "F.Cu")
		(net "BMC_EXT1_LED_Y")
	)
	(segment
		(start 53.699918 -138.999976)
		(end 54.099968 -138.599926)
		(width 0.127)
		(layer "F.Cu")
		(net "BMC_EXT1_LED_Y")
	)
	(segment
		(start 197.231 -21.0058)
		(end 197.140068 -21.096732)
		(width 0.127)
		(layer "F.Cu")
		(net "BMC_EXT1_LED_Y")
	)
	(segment
		(start 196.407532 -21.096732)
		(end 196.10324 -20.79244)
		(width 0.127)
		(layer "F.Cu")
		(net "BMC_EXT1_LED_Y")
	)
	(segment
		(start 196.10324 -20.79244)
		(end 196.10324 -20.0025)
		(width 0.127)
		(layer "F.Cu")
		(net "BMC_EXT1_LED_Y")
	)
	(segment
		(start 197.140068 -21.096732)
		(end 196.407532 -21.096732)
		(width 0.127)
		(layer "F.Cu")
		(net "BMC_EXT1_LED_Y")
	)
	(segment
		(start 194.01155 -22.85365)
		(end 193.73596 -23.12924)
		(width 0.127)
		(layer "F.Cu")
		(net "BMC_EXT1_LED_Y")
	)
	(via
		(at 197.231 -21.0058)
		(size 0.508)
		(drill 0.254)
		(layers "F.Cu" "B.Cu")
		(net "BMC_EXT1_LED_Y")
	)
	(via
		(at 58.674 -136.292336)
		(size 0.6096)
		(drill 0.3048)
		(layers "F.Cu" "B.Cu")
		(net "BMC_EXT1_LED_Y")
	)
	(via
		(at 75.047348 -44.047156)
		(size 0.508)
		(drill 0.254)
		(layers "F.Cu" "B.Cu")
		(net "BMC_EXT1_LED_Y")
	)
	(via
		(at 194.01155 -22.85365)
		(size 0.508)
		(drill 0.254)
		(layers "F.Cu" "B.Cu")
		(net "BMC_EXT1_LED_Y")
	)
	(via
		(at 169.1132 -1.9177)
		(size 0.508)
		(drill 0.254)
		(layers "F.Cu" "B.Cu")
		(net "BMC_EXT1_LED_Y")
	)
	(via
		(at 59.0296 -135.4328)
		(size 0.508)
		(drill 0.254)
		(layers "F.Cu" "B.Cu")
		(net "BMC_EXT1_LED_Y")
	)
	(via
		(at 58.9788 -113.1824)
		(size 0.508)
		(drill 0.254)
		(layers "F.Cu" "B.Cu")
		(net "BMC_EXT1_LED_Y")
	)
	(via
		(at 54.099968 -138.599926)
		(size 0.4572)
		(drill 0.2032)
		(layers "F.Cu" "B.Cu")
		(net "BMC_EXT1_LED_Y")
	)
	(via
		(at 60.579 -113.8555)
		(size 0.6096)
		(drill 0.3048)
		(layers "F.Cu" "B.Cu")
		(net "BMC_EXT1_LED_Y")
	)
	(segment
		(start 74.10958 -44.984924)
		(end 75.047348 -44.047156)
		(width 0.127)
		(layer "B.Cu")
		(net "BMC_EXT1_LED_Y")
	)
	(segment
		(start 54.099968 -138.470132)
		(end 54.099968 -138.599926)
		(width 0.127)
		(layer "B.Cu")
		(net "BMC_EXT1_LED_Y")
	)
	(segment
		(start 67.0052 -112.903)
		(end 67.9196 -111.9886)
		(width 0.127)
		(layer "B.Cu")
		(net "BMC_EXT1_LED_Y")
	)
	(segment
		(start 83.601814 -103.068374)
		(end 81.146142 -100.612702)
		(width 0.127)
		(layer "B.Cu")
		(net "BMC_EXT1_LED_Y")
	)
	(segment
		(start 58.234834 -136.731502)
		(end 57.725818 -136.731502)
		(width 0.127)
		(layer "B.Cu")
		(net "BMC_EXT1_LED_Y")
	)
	(segment
		(start 57.725818 -136.731502)
		(end 57.29732 -137.16)
		(width 0.127)
		(layer "B.Cu")
		(net "BMC_EXT1_LED_Y")
	)
	(segment
		(start 60.579 -113.8555)
		(end 64.6049 -113.8555)
		(width 0.127)
		(layer "B.Cu")
		(net "BMC_EXT1_LED_Y")
	)
	(segment
		(start 75.3872 -110.363)
		(end 80.1878 -110.363)
		(width 0.127)
		(layer "B.Cu")
		(net "BMC_EXT1_LED_Y")
	)
	(segment
		(start 67.9196 -111.9886)
		(end 73.7616 -111.9886)
		(width 0.127)
		(layer "B.Cu")
		(net "BMC_EXT1_LED_Y")
	)
	(segment
		(start 76.537312 -100.14966)
		(end 74.10958 -97.721928)
		(width 0.127)
		(layer "B.Cu")
		(net "BMC_EXT1_LED_Y")
	)
	(segment
		(start 79.977996 -100.14966)
		(end 76.537312 -100.14966)
		(width 0.127)
		(layer "B.Cu")
		(net "BMC_EXT1_LED_Y")
	)
	(segment
		(start 60.579 -113.8555)
		(end 59.9059 -113.8555)
		(width 0.127)
		(layer "B.Cu")
		(net "BMC_EXT1_LED_Y")
	)
	(segment
		(start 59.9059 -113.8555)
		(end 59.2328 -113.1824)
		(width 0.127)
		(layer "B.Cu")
		(net "BMC_EXT1_LED_Y")
	)
	(segment
		(start 81.146142 -100.612702)
		(end 80.441038 -100.612702)
		(width 0.127)
		(layer "B.Cu")
		(net "BMC_EXT1_LED_Y")
	)
	(segment
		(start 58.674 -136.292336)
		(end 58.234834 -136.731502)
		(width 0.127)
		(layer "B.Cu")
		(net "BMC_EXT1_LED_Y")
	)
	(segment
		(start 57.29732 -137.16)
		(end 54.971696 -137.16)
		(width 0.127)
		(layer "B.Cu")
		(net "BMC_EXT1_LED_Y")
	)
	(segment
		(start 80.1878 -110.363)
		(end 83.601814 -106.948986)
		(width 0.127)
		(layer "B.Cu")
		(net "BMC_EXT1_LED_Y")
	)
	(segment
		(start 80.441038 -100.612702)
		(end 79.977996 -100.14966)
		(width 0.127)
		(layer "B.Cu")
		(net "BMC_EXT1_LED_Y")
	)
	(segment
		(start 54.971696 -137.16)
		(end 54.493414 -137.638282)
		(width 0.127)
		(layer "B.Cu")
		(net "BMC_EXT1_LED_Y")
	)
	(segment
		(start 59.0296 -135.936736)
		(end 58.674 -136.292336)
		(width 0.127)
		(layer "B.Cu")
		(net "BMC_EXT1_LED_Y")
	)
	(segment
		(start 65.5574 -112.903)
		(end 67.0052 -112.903)
		(width 0.127)
		(layer "B.Cu")
		(net "BMC_EXT1_LED_Y")
	)
	(segment
		(start 64.6049 -113.8555)
		(end 65.5574 -112.903)
		(width 0.127)
		(layer "B.Cu")
		(net "BMC_EXT1_LED_Y")
	)
	(segment
		(start 74.10958 -97.721928)
		(end 74.10958 -44.984924)
		(width 0.127)
		(layer "B.Cu")
		(net "BMC_EXT1_LED_Y")
	)
	(segment
		(start 59.2328 -113.1824)
		(end 58.9788 -113.1824)
		(width 0.127)
		(layer "B.Cu")
		(net "BMC_EXT1_LED_Y")
	)
	(segment
		(start 54.493414 -137.638282)
		(end 54.493414 -138.076686)
		(width 0.127)
		(layer "B.Cu")
		(net "BMC_EXT1_LED_Y")
	)
	(segment
		(start 83.601814 -106.948986)
		(end 83.601814 -103.068374)
		(width 0.127)
		(layer "B.Cu")
		(net "BMC_EXT1_LED_Y")
	)
	(segment
		(start 59.0296 -135.4328)
		(end 59.0296 -135.936736)
		(width 0.127)
		(layer "B.Cu")
		(net "BMC_EXT1_LED_Y")
	)
	(segment
		(start 54.493414 -138.076686)
		(end 54.099968 -138.470132)
		(width 0.127)
		(layer "B.Cu")
		(net "BMC_EXT1_LED_Y")
	)
	(segment
		(start 73.7616 -111.9886)
		(end 75.3872 -110.363)
		(width 0.127)
		(layer "B.Cu")
		(net "BMC_EXT1_LED_Y")
	)
	(segment
		(start 186.795664 -1.8923)
		(end 169.1386 -1.8923)
		(width 0.127)
		(layer "In2.Cu")
		(net "BMC_EXT1_LED_Y")
	)
	(segment
		(start 189.400688 -4.497324)
		(end 186.795664 -1.8923)
		(width 0.127)
		(layer "In2.Cu")
		(net "BMC_EXT1_LED_Y")
	)
	(segment
		(start 196.2912 -21.9456)
		(end 197.231 -21.0058)
		(width 0.127)
		(layer "In2.Cu")
		(net "BMC_EXT1_LED_Y")
	)
	(segment
		(start 195.9356 -21.9456)
		(end 196.2912 -21.9456)
		(width 0.127)
		(layer "In2.Cu")
		(net "BMC_EXT1_LED_Y")
	)
	(segment
		(start 59.7281 -129.095754)
		(end 59.7281 -133.502146)
		(width 0.127)
		(layer "In2.Cu")
		(net "BMC_EXT1_LED_Y")
	)
	(segment
		(start 194.7418 -13.4112)
		(end 189.400688 -8.070088)
		(width 0.127)
		(layer "In2.Cu")
		(net "BMC_EXT1_LED_Y")
	)
	(segment
		(start 60.0837 -128.740154)
		(end 59.7281 -129.095754)
		(width 0.127)
		(layer "In2.Cu")
		(net "BMC_EXT1_LED_Y")
	)
	(segment
		(start 59.8297 -121.628154)
		(end 60.0837 -121.882154)
		(width 0.127)
		(layer "In2.Cu")
		(net "BMC_EXT1_LED_Y")
	)
	(segment
		(start 194.7418 -18.5166)
		(end 194.7418 -13.4112)
		(width 0.127)
		(layer "In2.Cu")
		(net "BMC_EXT1_LED_Y")
	)
	(segment
		(start 194.02425 -22.86635)
		(end 195.01485 -22.86635)
		(width 0.127)
		(layer "In2.Cu")
		(net "BMC_EXT1_LED_Y")
	)
	(segment
		(start 59.0296 -134.200646)
		(end 59.0296 -135.4328)
		(width 0.127)
		(layer "In2.Cu")
		(net "BMC_EXT1_LED_Y")
	)
	(segment
		(start 59.8297 -116.6622)
		(end 59.8297 -121.628154)
		(width 0.127)
		(layer "In2.Cu")
		(net "BMC_EXT1_LED_Y")
	)
	(segment
		(start 169.1386 -1.8923)
		(end 169.1132 -1.9177)
		(width 0.127)
		(layer "In2.Cu")
		(net "BMC_EXT1_LED_Y")
	)
	(segment
		(start 58.9788 -113.1824)
		(end 58.9788 -115.8113)
		(width 0.127)
		(layer "In2.Cu")
		(net "BMC_EXT1_LED_Y")
	)
	(segment
		(start 59.7281 -133.502146)
		(end 59.0296 -134.200646)
		(width 0.127)
		(layer "In2.Cu")
		(net "BMC_EXT1_LED_Y")
	)
	(segment
		(start 60.0837 -121.882154)
		(end 60.0837 -128.740154)
		(width 0.127)
		(layer "In2.Cu")
		(net "BMC_EXT1_LED_Y")
	)
	(segment
		(start 195.01485 -22.86635)
		(end 195.9356 -21.9456)
		(width 0.127)
		(layer "In2.Cu")
		(net "BMC_EXT1_LED_Y")
	)
	(segment
		(start 194.01155 -22.85365)
		(end 194.02425 -22.86635)
		(width 0.127)
		(layer "In2.Cu")
		(net "BMC_EXT1_LED_Y")
	)
	(segment
		(start 58.9788 -115.8113)
		(end 59.8297 -116.6622)
		(width 0.127)
		(layer "In2.Cu")
		(net "BMC_EXT1_LED_Y")
	)
	(segment
		(start 197.231 -21.0058)
		(end 194.7418 -18.5166)
		(width 0.127)
		(layer "In2.Cu")
		(net "BMC_EXT1_LED_Y")
	)
	(segment
		(start 189.400688 -8.070088)
		(end 189.400688 -4.497324)
		(width 0.127)
		(layer "In2.Cu")
		(net "BMC_EXT1_LED_Y")
	)
	(segment
		(start 75.047348 -30.384496)
		(end 75.047348 -44.047156)
		(width 0.127)
		(layer "In5.Cu")
		(net "BMC_EXT1_LED_Y")
	)
	(segment
		(start 169.1132 -1.9177)
		(end 169.038778 -1.992122)
		(width 0.127)
		(layer "In5.Cu")
		(net "BMC_EXT1_LED_Y")
	)
	(segment
		(start 76.9874 -28.444444)
		(end 75.047348 -30.384496)
		(width 0.127)
		(layer "In5.Cu")
		(net "BMC_EXT1_LED_Y")
	)
	(segment
		(start 169.038778 -1.992122)
		(end 81.808066 -1.992122)
		(width 0.127)
		(layer "In5.Cu")
		(net "BMC_EXT1_LED_Y")
	)
	(segment
		(start 76.9874 -6.2992)
		(end 76.9874 -28.444444)
		(width 0.127)
		(layer "In5.Cu")
		(net "BMC_EXT1_LED_Y")
	)
	(segment
		(start 80.1243 -3.1623)
		(end 76.9874 -6.2992)
		(width 0.127)
		(layer "In5.Cu")
		(net "BMC_EXT1_LED_Y")
	)
	(segment
		(start 80.637888 -3.1623)
		(end 80.1243 -3.1623)
		(width 0.127)
		(layer "In5.Cu")
		(net "BMC_EXT1_LED_Y")
	)
	(segment
		(start 81.808066 -1.992122)
		(end 80.637888 -3.1623)
		(width 0.127)
		(layer "In5.Cu")
		(net "BMC_EXT1_LED_Y")
	)
	(segment
		(start 141.053058 -20.8026)
		(end 142.0241 -20.8026)
		(width 0.127)
		(layer "F.Cu")
		(net "EXT2_LED_YELLOW_D")
	)
	(segment
		(start 142.113 -20.7645)
		(end 142.0495 -20.828)
		(width 0.127)
		(layer "F.Cu")
		(net "EXT2_LED_YELLOW_D")
	)
	(segment
		(start 140.1318 -20.8026)
		(end 141.053058 -20.8026)
		(width 0.127)
		(layer "F.Cu")
		(net "EXT2_LED_YELLOW_D")
	)
	(segment
		(start 140.081 -20.8534)
		(end 140.1318 -20.8026)
		(width 0.127)
		(layer "F.Cu")
		(net "EXT2_LED_YELLOW_D")
	)
	(segment
		(start 142.0241 -20.8026)
		(end 142.0495 -20.828)
		(width 0.127)
		(layer "F.Cu")
		(net "EXT2_LED_YELLOW_D")
	)
	(segment
		(start 142.113 -19.3675)
		(end 142.113 -20.7645)
		(width 0.127)
		(layer "F.Cu")
		(net "EXT2_LED_YELLOW_D")
	)
	(segment
		(start 140.081 -20.9296)
		(end 140.081 -20.8534)
		(width 0.127)
		(layer "F.Cu")
		(net "EXT2_LED_YELLOW_D")
	)
	(via
		(at 141.053058 -20.8026)
		(size 0.6604)
		(drill 0.3302)
		(layers "F.Cu" "B.Cu")
		(net "EXT2_LED_YELLOW_D")
	)
	(via
		(at 144.6022 -16.833596)
		(size 0.508)
		(drill 0.254)
		(layers "F.Cu" "B.Cu")
		(net "EXT2_LED_YELLOW_D")
	)
	(via
		(at 140.081 -20.9296)
		(size 0.508)
		(drill 0.254)
		(layers "F.Cu" "B.Cu")
		(net "EXT2_LED_YELLOW_D")
	)
	(segment
		(start 145.158968 -17.1323)
		(end 144.900904 -17.1323)
		(width 0.127)
		(layer "B.Cu")
		(net "EXT2_LED_YELLOW_D")
	)
	(segment
		(start 144.900904 -17.1323)
		(end 144.6022 -16.833596)
		(width 0.127)
		(layer "B.Cu")
		(net "EXT2_LED_YELLOW_D")
	)
	(segment
		(start 145.7325 -17.145)
		(end 145.171668 -17.145)
		(width 0.127)
		(layer "B.Cu")
		(net "EXT2_LED_YELLOW_D")
	)
	(segment
		(start 145.171668 -17.145)
		(end 145.158968 -17.1323)
		(width 0.127)
		(layer "B.Cu")
		(net "EXT2_LED_YELLOW_D")
	)
	(segment
		(start 140.081 -20.8534)
		(end 141.1986 -19.7358)
		(width 0.127)
		(layer "In5.Cu")
		(net "EXT2_LED_YELLOW_D")
	)
	(segment
		(start 144.290796 -17.145)
		(end 144.6022 -16.833596)
		(width 0.127)
		(layer "In5.Cu")
		(net "EXT2_LED_YELLOW_D")
	)
	(segment
		(start 140.081 -20.9296)
		(end 140.081 -20.8534)
		(width 0.127)
		(layer "In5.Cu")
		(net "EXT2_LED_YELLOW_D")
	)
	(segment
		(start 142.2654 -17.145)
		(end 144.290796 -17.145)
		(width 0.127)
		(layer "In5.Cu")
		(net "EXT2_LED_YELLOW_D")
	)
	(segment
		(start 141.1986 -18.2118)
		(end 142.2654 -17.145)
		(width 0.127)
		(layer "In5.Cu")
		(net "EXT2_LED_YELLOW_D")
	)
	(segment
		(start 141.1986 -19.7358)
		(end 141.1986 -18.2118)
		(width 0.127)
		(layer "In5.Cu")
		(net "EXT2_LED_YELLOW_D")
	)
	(segment
		(start 147.694904 -7.044944)
		(end 148.539962 -6.199886)
		(width 0.254)
		(layer "F.Cu")
		(net "EXT2_LED_YELLOW")
	)
	(segment
		(start 147.694904 -10.933684)
		(end 147.694904 -7.044944)
		(width 0.254)
		(layer "F.Cu")
		(net "EXT2_LED_YELLOW")
	)
	(segment
		(start 147.85086 -11.08964)
		(end 147.694904 -10.933684)
		(width 0.254)
		(layer "F.Cu")
		(net "EXT2_LED_YELLOW")
	)
	(segment
		(start 147.85086 -12.36472)
		(end 147.85086 -11.08964)
		(width 0.254)
		(layer "F.Cu")
		(net "EXT2_LED_YELLOW")
	)
	(via
		(at 147.694904 -10.933684)
		(size 0.6604)
		(drill 0.3302)
		(layers "F.Cu" "B.Cu")
		(net "EXT2_LED_YELLOW")
	)
	(segment
		(start 143.22298 -11.285982)
		(end 143.2814 -11.227562)
		(width 0.254)
		(layer "F.Cu")
		(net "EXT2_LED_BLUE")
	)
	(segment
		(start 143.2814 -11.227562)
		(end 143.2814 -6.378448)
		(width 0.254)
		(layer "F.Cu")
		(net "EXT2_LED_BLUE")
	)
	(segment
		(start 143.22298 -12.548362)
		(end 143.22298 -11.285982)
		(width 0.254)
		(layer "F.Cu")
		(net "EXT2_LED_BLUE")
	)
	(segment
		(start 143.2814 -6.378448)
		(end 143.459962 -6.199886)
		(width 0.254)
		(layer "F.Cu")
		(net "EXT2_LED_BLUE")
	)
	(via
		(at 143.2814 -11.227562)
		(size 0.6604)
		(drill 0.3302)
		(layers "F.Cu" "B.Cu")
		(net "EXT2_LED_BLUE")
	)
	(segment
		(start 197.5358 -19.7231)
		(end 197.12559 -19.7231)
		(width 0.127)
		(layer "F.Cu")
		(net "EXT1_LED_YELLOW_D")
	)
	(segment
		(start 198.1454 -20.3327)
		(end 197.5358 -19.7231)
		(width 0.127)
		(layer "F.Cu")
		(net "EXT1_LED_YELLOW_D")
	)
	(segment
		(start 199.898 -18.8595)
		(end 199.898 -20.2057)
		(width 0.127)
		(layer "F.Cu")
		(net "EXT1_LED_YELLOW_D")
	)
	(segment
		(start 199.771 -20.3327)
		(end 198.9709 -20.3327)
		(width 0.127)
		(layer "F.Cu")
		(net "EXT1_LED_YELLOW_D")
	)
	(segment
		(start 199.898 -20.2057)
		(end 199.771 -20.3327)
		(width 0.127)
		(layer "F.Cu")
		(net "EXT1_LED_YELLOW_D")
	)
	(segment
		(start 195.580254 -19.1516)
		(end 195.453 -19.278854)
		(width 0.127)
		(layer "F.Cu")
		(net "EXT1_LED_YELLOW_D")
	)
	(segment
		(start 196.55409 -19.1516)
		(end 195.580254 -19.1516)
		(width 0.127)
		(layer "F.Cu")
		(net "EXT1_LED_YELLOW_D")
	)
	(segment
		(start 195.453 -19.278854)
		(end 195.453 -20.0025)
		(width 0.127)
		(layer "F.Cu")
		(net "EXT1_LED_YELLOW_D")
	)
	(segment
		(start 197.12559 -19.7231)
		(end 196.55409 -19.1516)
		(width 0.127)
		(layer "F.Cu")
		(net "EXT1_LED_YELLOW_D")
	)
	(segment
		(start 198.9709 -20.3327)
		(end 198.1454 -20.3327)
		(width 0.127)
		(layer "F.Cu")
		(net "EXT1_LED_YELLOW_D")
	)
	(via
		(at 198.9709 -20.3327)
		(size 0.6604)
		(drill 0.3302)
		(layers "F.Cu" "B.Cu")
		(net "EXT1_LED_YELLOW_D")
	)
	(segment
		(start 196.27977 -6.460236)
		(end 196.27977 -10.09269)
		(width 0.254)
		(layer "F.Cu")
		(net "EXT1_LED_YELLOW")
	)
	(segment
		(start 196.54012 -6.199886)
		(end 196.27977 -6.460236)
		(width 0.254)
		(layer "F.Cu")
		(net "EXT1_LED_YELLOW")
	)
	(segment
		(start 190.9699 -6.690106)
		(end 191.46012 -6.199886)
		(width 0.254)
		(layer "F.Cu")
		(net "EXT1_LED_BLUE")
	)
	(segment
		(start 190.881 -12.25042)
		(end 190.9699 -12.16152)
		(width 0.254)
		(layer "F.Cu")
		(net "EXT1_LED_BLUE")
	)
	(segment
		(start 190.9699 -12.16152)
		(end 190.9699 -6.690106)
		(width 0.254)
		(layer "F.Cu")
		(net "EXT1_LED_BLUE")
	)
	(via
		(at 92.9386 -17.0434)
		(size 0.6096)
		(drill 0.3048)
		(layers "F.Cu" "B.Cu")
		(net "USB_CONN_GND")
	)
	(via
		(at 91.5924 -5.6642)
		(size 0.6096)
		(drill 0.3048)
		(layers "F.Cu" "B.Cu")
		(net "USB_CONN_GND")
	)
	(segment
		(start 91.609926 -21.584158)
		(end 91.609926 -23.349966)
		(width 0.508)
		(layer "B.Cu")
		(net "USB_CONN_GND")
	)
	(segment
		(start 91.609926 -11.227054)
		(end 91.609926 -12.649962)
		(width 0.508)
		(layer "B.Cu")
		(net "USB_CONN_GND")
	)
	(segment
		(start 86.190074 -12.649962)
		(end 87.308182 -12.649962)
		(width 0.508)
		(layer "B.Cu")
		(net "USB_CONN_GND")
	)
	(segment
		(start 91.609926 -12.649962)
		(end 91.609926 -14.07287)
		(width 0.508)
		(layer "B.Cu")
		(net "USB_CONN_GND")
	)
	(segment
		(start 86.190074 -23.349966)
		(end 87.308182 -23.349966)
		(width 0.508)
		(layer "B.Cu")
		(net "USB_CONN_GND")
	)
	(segment
		(start 85.071966 -12.649962)
		(end 86.190074 -12.649962)
		(width 0.508)
		(layer "B.Cu")
		(net "USB_CONN_GND")
	)
	(segment
		(start 91.609926 -12.649962)
		(end 92.728034 -12.649962)
		(width 0.508)
		(layer "B.Cu")
		(net "USB_CONN_GND")
	)
	(segment
		(start 90.491818 -12.649962)
		(end 91.609926 -12.649962)
		(width 0.508)
		(layer "B.Cu")
		(net "USB_CONN_GND")
	)
	(segment
		(start 86.190074 -12.649962)
		(end 86.190074 -14.41577)
		(width 0.508)
		(layer "B.Cu")
		(net "USB_CONN_GND")
	)
	(segment
		(start 90.491818 -23.349966)
		(end 91.609926 -23.349966)
		(width 0.508)
		(layer "B.Cu")
		(net "USB_CONN_GND")
	)
	(segment
		(start 85.071966 -23.349966)
		(end 86.190074 -23.349966)
		(width 0.508)
		(layer "B.Cu")
		(net "USB_CONN_GND")
	)
	(segment
		(start 91.609926 -23.349966)
		(end 91.609926 -25.115774)
		(width 0.508)
		(layer "B.Cu")
		(net "USB_CONN_GND")
	)
	(segment
		(start 86.190074 -10.884154)
		(end 86.190074 -12.649962)
		(width 0.508)
		(layer "B.Cu")
		(net "USB_CONN_GND")
	)
	(segment
		(start 91.609926 -23.349966)
		(end 92.728034 -23.349966)
		(width 0.508)
		(layer "B.Cu")
		(net "USB_CONN_GND")
	)
	(segment
		(start 86.190074 -23.349966)
		(end 86.190074 -24.772874)
		(width 0.508)
		(layer "B.Cu")
		(net "USB_CONN_GND")
	)
	(segment
		(start 86.190074 -21.927058)
		(end 86.190074 -23.349966)
		(width 0.508)
		(layer "B.Cu")
		(net "USB_CONN_GND")
	)
	(segment
		(start 92.132658 -48.960024)
		(end 92.132658 -48.001936)
		(width 0.127)
		(layer "F.Cu")
		(net "P3V3_EN_R")
	)
	(segment
		(start 92.613988 -49.64176)
		(end 92.132658 -49.16043)
		(width 0.127)
		(layer "F.Cu")
		(net "P3V3_EN_R")
	)
	(segment
		(start 92.583508 -58.217816)
		(end 93.165168 -57.636156)
		(width 0.127)
		(layer "F.Cu")
		(net "P3V3_EN_R")
	)
	(segment
		(start 92.1766 -51.758596)
		(end 92.613988 -51.321208)
		(width 0.127)
		(layer "F.Cu")
		(net "P3V3_EN_R")
	)
	(segment
		(start 92.613988 -51.321208)
		(end 92.613988 -49.64176)
		(width 0.127)
		(layer "F.Cu")
		(net "P3V3_EN_R")
	)
	(segment
		(start 91.147138 -56.758078)
		(end 91.147138 -53.241956)
		(width 0.127)
		(layer "F.Cu")
		(net "P3V3_EN_R")
	)
	(segment
		(start 93.165168 -57.133236)
		(end 92.799662 -57.133236)
		(width 0.127)
		(layer "F.Cu")
		(net "P3V3_EN_R")
	)
	(segment
		(start 90.198448 -59.111896)
		(end 91.092528 -58.217816)
		(width 0.127)
		(layer "F.Cu")
		(net "P3V3_EN_R")
	)
	(segment
		(start 92.1766 -52.212494)
		(end 92.1766 -51.758596)
		(width 0.127)
		(layer "F.Cu")
		(net "P3V3_EN_R")
	)
	(segment
		(start 91.72067 -57.33161)
		(end 91.147138 -56.758078)
		(width 0.127)
		(layer "F.Cu")
		(net "P3V3_EN_R")
	)
	(segment
		(start 91.092528 -58.217816)
		(end 92.583508 -58.217816)
		(width 0.127)
		(layer "F.Cu")
		(net "P3V3_EN_R")
	)
	(segment
		(start 92.132658 -49.16043)
		(end 92.132658 -48.960024)
		(width 0.127)
		(layer "F.Cu")
		(net "P3V3_EN_R")
	)
	(segment
		(start 93.338904 -47.639224)
		(end 93.338904 -48.77054)
		(width 0.127)
		(layer "F.Cu")
		(net "P3V3_EN_R")
	)
	(segment
		(start 92.49537 -47.639224)
		(end 93.338904 -47.639224)
		(width 0.127)
		(layer "F.Cu")
		(net "P3V3_EN_R")
	)
	(segment
		(start 92.601288 -57.33161)
		(end 91.72067 -57.33161)
		(width 0.127)
		(layer "F.Cu")
		(net "P3V3_EN_R")
	)
	(segment
		(start 93.338904 -48.77054)
		(end 93.124528 -48.984916)
		(width 0.127)
		(layer "F.Cu")
		(net "P3V3_EN_R")
	)
	(segment
		(start 93.165168 -57.636156)
		(end 93.165168 -57.133236)
		(width 0.127)
		(layer "F.Cu")
		(net "P3V3_EN_R")
	)
	(segment
		(start 92.132658 -48.001936)
		(end 92.49537 -47.639224)
		(width 0.127)
		(layer "F.Cu")
		(net "P3V3_EN_R")
	)
	(segment
		(start 90.061288 -59.111896)
		(end 90.198448 -59.111896)
		(width 0.127)
		(layer "F.Cu")
		(net "P3V3_EN_R")
	)
	(segment
		(start 91.147138 -53.241956)
		(end 92.1766 -52.212494)
		(width 0.127)
		(layer "F.Cu")
		(net "P3V3_EN_R")
	)
	(segment
		(start 92.799662 -57.133236)
		(end 92.601288 -57.33161)
		(width 0.127)
		(layer "F.Cu")
		(net "P3V3_EN_R")
	)
	(via
		(at 92.132658 -48.960024)
		(size 0.6604)
		(drill 0.3302)
		(layers "F.Cu" "B.Cu")
		(net "P3V3_EN_R")
	)
	(via
		(at 126.5301 -6.8199)
		(size 0.6604)
		(drill 0.3302)
		(layers "F.Cu" "B.Cu")
		(net "MB0_CM_GATE_2")
	)
	(segment
		(start 35.478466 -152.769316)
		(end 35.960558 -152.769316)
		(width 0.127)
		(layer "F.Cu")
		(net "ENCL_FAULT_LED_R")
	)
	(segment
		(start 34.688526 -152.769316)
		(end 35.478466 -152.769316)
		(width 0.127)
		(layer "F.Cu")
		(net "ENCL_FAULT_LED_R")
	)
	(segment
		(start 35.960558 -152.769316)
		(end 36.177474 -152.5524)
		(width 0.127)
		(layer "F.Cu")
		(net "ENCL_FAULT_LED_R")
	)
	(segment
		(start 36.177474 -152.5524)
		(end 36.9951 -152.5524)
		(width 0.127)
		(layer "F.Cu")
		(net "ENCL_FAULT_LED_R")
	)
	(segment
		(start 39.100252 -151.1554)
		(end 39.144448 -151.1554)
		(width 0.127)
		(layer "F.Cu")
		(net "ENCL_FAULT_LED_R")
	)
	(segment
		(start 36.9951 -152.5524)
		(end 37.710618 -151.836882)
		(width 0.127)
		(layer "F.Cu")
		(net "ENCL_FAULT_LED_R")
	)
	(segment
		(start 39.144448 -151.1554)
		(end 39.299896 -150.999952)
		(width 0.127)
		(layer "F.Cu")
		(net "ENCL_FAULT_LED_R")
	)
	(segment
		(start 34.216848 -153.240994)
		(end 34.688526 -152.769316)
		(width 0.127)
		(layer "F.Cu")
		(net "ENCL_FAULT_LED_R")
	)
	(segment
		(start 37.710618 -151.836882)
		(end 38.41877 -151.836882)
		(width 0.127)
		(layer "F.Cu")
		(net "ENCL_FAULT_LED_R")
	)
	(segment
		(start 38.41877 -151.836882)
		(end 39.100252 -151.1554)
		(width 0.127)
		(layer "F.Cu")
		(net "ENCL_FAULT_LED_R")
	)
	(via
		(at 35.478466 -152.769316)
		(size 0.6604)
		(drill 0.3302)
		(layers "F.Cu" "B.Cu")
		(net "ENCL_FAULT_LED_R")
	)
	(segment
		(start 33.327848 -153.240994)
		(end 33.327848 -153.997152)
		(width 0.127)
		(layer "F.Cu")
		(net "ENCL_FAULT_LED")
	)
	(segment
		(start 33.327848 -153.997152)
		(end 33.2232 -154.1018)
		(width 0.127)
		(layer "F.Cu")
		(net "ENCL_FAULT_LED")
	)
	(via
		(at 34.2138 -153.416)
		(size 0.6096)
		(drill 0.3048)
		(layers "F.Cu" "B.Cu")
		(net "ENCL_FAULT_LED")
	)
	(via
		(at 33.2232 -154.1018)
		(size 0.508)
		(drill 0.254)
		(layers "F.Cu" "B.Cu")
		(net "ENCL_FAULT_LED")
	)
	(via
		(at 100.690426 -173.529244)
		(size 0.508)
		(drill 0.254)
		(layers "F.Cu" "B.Cu")
		(net "ENCL_FAULT_LED")
	)
	(segment
		(start 33.157668 -153.124916)
		(end 33.922716 -153.124916)
		(width 0.127)
		(layer "B.Cu")
		(net "ENCL_FAULT_LED")
	)
	(segment
		(start 33.8074 -154.1018)
		(end 33.2232 -154.1018)
		(width 0.127)
		(layer "B.Cu")
		(net "ENCL_FAULT_LED")
	)
	(segment
		(start 33.922716 -153.124916)
		(end 34.2138 -153.416)
		(width 0.127)
		(layer "B.Cu")
		(net "ENCL_FAULT_LED")
	)
	(segment
		(start 34.2138 -153.6954)
		(end 33.8074 -154.1018)
		(width 0.127)
		(layer "B.Cu")
		(net "ENCL_FAULT_LED")
	)
	(segment
		(start 34.2138 -153.416)
		(end 34.2138 -153.6954)
		(width 0.127)
		(layer "B.Cu")
		(net "ENCL_FAULT_LED")
	)
	(segment
		(start 106.705146 -31.147512)
		(end 105.7148 -32.137858)
		(width 0.127)
		(layer "In2.Cu")
		(net "ENCL_FAULT_LED")
	)
	(segment
		(start 100.182172 -172.43552)
		(end 100.182172 -173.02099)
		(width 0.127)
		(layer "In2.Cu")
		(net "ENCL_FAULT_LED")
	)
	(segment
		(start 100.583746 -172.033946)
		(end 100.182172 -172.43552)
		(width 0.127)
		(layer "In2.Cu")
		(net "ENCL_FAULT_LED")
	)
	(segment
		(start 100.588318 -164.334952)
		(end 100.083366 -164.839904)
		(width 0.127)
		(layer "In2.Cu")
		(net "ENCL_FAULT_LED")
	)
	(segment
		(start 100.947474 -112.894618)
		(end 100.947474 -123.638818)
		(width 0.127)
		(layer "In2.Cu")
		(net "ENCL_FAULT_LED")
	)
	(segment
		(start 100.588318 -143.326104)
		(end 100.588318 -164.334952)
		(width 0.127)
		(layer "In2.Cu")
		(net "ENCL_FAULT_LED")
	)
	(segment
		(start 100.388166 -124.198126)
		(end 100.388166 -127.76708)
		(width 0.127)
		(layer "In2.Cu")
		(net "ENCL_FAULT_LED")
	)
	(segment
		(start 100.501958 -46.53661)
		(end 100.501958 -84.336128)
		(width 0.127)
		(layer "In2.Cu")
		(net "ENCL_FAULT_LED")
	)
	(segment
		(start 100.583746 -167.328088)
		(end 100.583746 -172.033946)
		(width 0.127)
		(layer "In2.Cu")
		(net "ENCL_FAULT_LED")
	)
	(segment
		(start 100.083366 -164.839904)
		(end 100.083366 -166.827708)
		(width 0.127)
		(layer "In2.Cu")
		(net "ENCL_FAULT_LED")
	)
	(segment
		(start 100.155502 -112.102646)
		(end 100.947474 -112.894618)
		(width 0.127)
		(layer "In2.Cu")
		(net "ENCL_FAULT_LED")
	)
	(segment
		(start 108.232702 -38.532816)
		(end 108.232702 -31.885636)
		(width 0.127)
		(layer "In2.Cu")
		(net "ENCL_FAULT_LED")
	)
	(segment
		(start 100.523548 -143.261334)
		(end 100.588318 -143.326104)
		(width 0.127)
		(layer "In2.Cu")
		(net "ENCL_FAULT_LED")
	)
	(segment
		(start 100.523548 -140.8811)
		(end 100.523548 -143.261334)
		(width 0.127)
		(layer "In2.Cu")
		(net "ENCL_FAULT_LED")
	)
	(segment
		(start 108.89996 -39.200074)
		(end 108.232702 -38.532816)
		(width 0.127)
		(layer "In2.Cu")
		(net "ENCL_FAULT_LED")
	)
	(segment
		(start 100.501958 -84.336128)
		(end 100.155502 -84.682584)
		(width 0.127)
		(layer "In2.Cu")
		(net "ENCL_FAULT_LED")
	)
	(segment
		(start 100.083366 -166.827708)
		(end 100.583746 -167.328088)
		(width 0.127)
		(layer "In2.Cu")
		(net "ENCL_FAULT_LED")
	)
	(segment
		(start 108.232702 -31.885636)
		(end 107.494578 -31.147512)
		(width 0.127)
		(layer "In2.Cu")
		(net "ENCL_FAULT_LED")
	)
	(segment
		(start 100.182172 -173.02099)
		(end 100.690426 -173.529244)
		(width 0.127)
		(layer "In2.Cu")
		(net "ENCL_FAULT_LED")
	)
	(segment
		(start 100.947474 -123.638818)
		(end 100.388166 -124.198126)
		(width 0.127)
		(layer "In2.Cu")
		(net "ENCL_FAULT_LED")
	)
	(segment
		(start 105.7148 -32.137858)
		(end 105.7148 -41.323768)
		(width 0.127)
		(layer "In2.Cu")
		(net "ENCL_FAULT_LED")
	)
	(segment
		(start 100.769166 -128.14808)
		(end 100.769166 -140.635482)
		(width 0.127)
		(layer "In2.Cu")
		(net "ENCL_FAULT_LED")
	)
	(segment
		(start 100.388166 -127.76708)
		(end 100.769166 -128.14808)
		(width 0.127)
		(layer "In2.Cu")
		(net "ENCL_FAULT_LED")
	)
	(segment
		(start 100.155502 -84.682584)
		(end 100.155502 -112.102646)
		(width 0.127)
		(layer "In2.Cu")
		(net "ENCL_FAULT_LED")
	)
	(segment
		(start 107.494578 -31.147512)
		(end 106.705146 -31.147512)
		(width 0.127)
		(layer "In2.Cu")
		(net "ENCL_FAULT_LED")
	)
	(segment
		(start 105.7148 -41.323768)
		(end 100.501958 -46.53661)
		(width 0.127)
		(layer "In2.Cu")
		(net "ENCL_FAULT_LED")
	)
	(segment
		(start 100.769166 -140.635482)
		(end 100.523548 -140.8811)
		(width 0.127)
		(layer "In2.Cu")
		(net "ENCL_FAULT_LED")
	)
	(segment
		(start 96.042988 -172.4152)
		(end 91.015312 -172.4152)
		(width 0.127)
		(layer "In5.Cu")
		(net "ENCL_FAULT_LED")
	)
	(segment
		(start 100.034344 -173.529244)
		(end 99.5426 -173.0375)
		(width 0.127)
		(layer "In5.Cu")
		(net "ENCL_FAULT_LED")
	)
	(segment
		(start 41.37914 -160.604454)
		(end 38.464236 -160.604454)
		(width 0.127)
		(layer "In5.Cu")
		(net "ENCL_FAULT_LED")
	)
	(segment
		(start 100.690426 -173.529244)
		(end 100.034344 -173.529244)
		(width 0.127)
		(layer "In5.Cu")
		(net "ENCL_FAULT_LED")
	)
	(segment
		(start 43.620944 -161.565844)
		(end 42.34053 -161.565844)
		(width 0.127)
		(layer "In5.Cu")
		(net "ENCL_FAULT_LED")
	)
	(segment
		(start 89.789 -173.0375)
		(end 89.5223 -172.7708)
		(width 0.127)
		(layer "In5.Cu")
		(net "ENCL_FAULT_LED")
	)
	(segment
		(start 34.625026 -156.5656)
		(end 34.199322 -156.5656)
		(width 0.127)
		(layer "In5.Cu")
		(net "ENCL_FAULT_LED")
	)
	(segment
		(start 73.190862 -172.6946)
		(end 69.5452 -172.6946)
		(width 0.127)
		(layer "In5.Cu")
		(net "ENCL_FAULT_LED")
	)
	(segment
		(start 49.457864 -166.2557)
		(end 48.615346 -165.413182)
		(width 0.127)
		(layer "In5.Cu")
		(net "ENCL_FAULT_LED")
	)
	(segment
		(start 48.615346 -165.413182)
		(end 47.468282 -165.413182)
		(width 0.127)
		(layer "In5.Cu")
		(net "ENCL_FAULT_LED")
	)
	(segment
		(start 83.000342 -173.4947)
		(end 73.990962 -173.4947)
		(width 0.127)
		(layer "In5.Cu")
		(net "ENCL_FAULT_LED")
	)
	(segment
		(start 83.990942 -172.5041)
		(end 83.000342 -173.4947)
		(width 0.127)
		(layer "In5.Cu")
		(net "ENCL_FAULT_LED")
	)
	(segment
		(start 91.015312 -172.4152)
		(end 90.393012 -173.0375)
		(width 0.127)
		(layer "In5.Cu")
		(net "ENCL_FAULT_LED")
	)
	(segment
		(start 69.5452 -172.6946)
		(end 67.817746 -170.967146)
		(width 0.127)
		(layer "In5.Cu")
		(net "ENCL_FAULT_LED")
	)
	(segment
		(start 62.514734 -170.967146)
		(end 61.575188 -170.0276)
		(width 0.127)
		(layer "In5.Cu")
		(net "ENCL_FAULT_LED")
	)
	(segment
		(start 47.468282 -165.413182)
		(end 43.620944 -161.565844)
		(width 0.127)
		(layer "In5.Cu")
		(net "ENCL_FAULT_LED")
	)
	(segment
		(start 89.5223 -172.7708)
		(end 87.627714 -172.7708)
		(width 0.127)
		(layer "In5.Cu")
		(net "ENCL_FAULT_LED")
	)
	(segment
		(start 87.627714 -172.7708)
		(end 87.40267 -172.995844)
		(width 0.127)
		(layer "In5.Cu")
		(net "ENCL_FAULT_LED")
	)
	(segment
		(start 86.115398 -172.94352)
		(end 85.675978 -172.5041)
		(width 0.127)
		(layer "In5.Cu")
		(net "ENCL_FAULT_LED")
	)
	(segment
		(start 37.858446 -159.79902)
		(end 34.625026 -156.5656)
		(width 0.127)
		(layer "In5.Cu")
		(net "ENCL_FAULT_LED")
	)
	(segment
		(start 34.199322 -156.5656)
		(end 33.2232 -155.589478)
		(width 0.127)
		(layer "In5.Cu")
		(net "ENCL_FAULT_LED")
	)
	(segment
		(start 73.990962 -173.4947)
		(end 73.190862 -172.6946)
		(width 0.127)
		(layer "In5.Cu")
		(net "ENCL_FAULT_LED")
	)
	(segment
		(start 38.464236 -160.604454)
		(end 37.858446 -159.998664)
		(width 0.127)
		(layer "In5.Cu")
		(net "ENCL_FAULT_LED")
	)
	(segment
		(start 57.094882 -170.0276)
		(end 53.322982 -166.2557)
		(width 0.127)
		(layer "In5.Cu")
		(net "ENCL_FAULT_LED")
	)
	(segment
		(start 37.858446 -159.998664)
		(end 37.858446 -159.79902)
		(width 0.127)
		(layer "In5.Cu")
		(net "ENCL_FAULT_LED")
	)
	(segment
		(start 90.393012 -173.0375)
		(end 89.789 -173.0375)
		(width 0.127)
		(layer "In5.Cu")
		(net "ENCL_FAULT_LED")
	)
	(segment
		(start 67.817746 -170.967146)
		(end 62.514734 -170.967146)
		(width 0.127)
		(layer "In5.Cu")
		(net "ENCL_FAULT_LED")
	)
	(segment
		(start 33.2232 -155.589478)
		(end 33.2232 -154.1018)
		(width 0.127)
		(layer "In5.Cu")
		(net "ENCL_FAULT_LED")
	)
	(segment
		(start 87.40267 -172.995844)
		(end 87.013034 -172.995844)
		(width 0.127)
		(layer "In5.Cu")
		(net "ENCL_FAULT_LED")
	)
	(segment
		(start 99.5426 -173.0375)
		(end 96.665288 -173.0375)
		(width 0.127)
		(layer "In5.Cu")
		(net "ENCL_FAULT_LED")
	)
	(segment
		(start 42.34053 -161.565844)
		(end 41.37914 -160.604454)
		(width 0.127)
		(layer "In5.Cu")
		(net "ENCL_FAULT_LED")
	)
	(segment
		(start 85.675978 -172.5041)
		(end 83.990942 -172.5041)
		(width 0.127)
		(layer "In5.Cu")
		(net "ENCL_FAULT_LED")
	)
	(segment
		(start 87.013034 -172.995844)
		(end 86.96071 -172.94352)
		(width 0.127)
		(layer "In5.Cu")
		(net "ENCL_FAULT_LED")
	)
	(segment
		(start 86.96071 -172.94352)
		(end 86.115398 -172.94352)
		(width 0.127)
		(layer "In5.Cu")
		(net "ENCL_FAULT_LED")
	)
	(segment
		(start 53.322982 -166.2557)
		(end 49.457864 -166.2557)
		(width 0.127)
		(layer "In5.Cu")
		(net "ENCL_FAULT_LED")
	)
	(segment
		(start 96.665288 -173.0375)
		(end 96.042988 -172.4152)
		(width 0.127)
		(layer "In5.Cu")
		(net "ENCL_FAULT_LED")
	)
	(segment
		(start 61.575188 -170.0276)
		(end 57.094882 -170.0276)
		(width 0.127)
		(layer "In5.Cu")
		(net "ENCL_FAULT_LED")
	)
	(segment
		(start 96.7486 -176.00676)
		(end 97.724976 -176.00676)
		(width 0.127)
		(layer "F.Cu")
		(net "PWRGD_P3V3_STBY_N_R2")
	)
	(segment
		(start 97.724976 -176.00676)
		(end 97.83445 -176.116234)
		(width 0.127)
		(layer "F.Cu")
		(net "PWRGD_P3V3_STBY_N_R2")
	)
	(segment
		(start 95.15094 -176.00676)
		(end 96.7486 -176.00676)
		(width 0.127)
		(layer "F.Cu")
		(net "PWRGD_P3V3_STBY_N_R2")
	)
	(via
		(at 96.7486 -176.00676)
		(size 0.6604)
		(drill 0.3302)
		(layers "F.Cu" "B.Cu")
		(net "PWRGD_P3V3_STBY_N_R2")
	)
	(segment
		(start 80.672686 -142.063978)
		(end 81.13522 -141.601444)
		(width 0.127)
		(layer "F.Cu")
		(net "PWRGD_P3V3_STBY_N_R1")
	)
	(segment
		(start 79.710534 -142.063978)
		(end 80.672686 -142.063978)
		(width 0.127)
		(layer "F.Cu")
		(net "PWRGD_P3V3_STBY_N_R1")
	)
	(via
		(at 80.1624 -141.6558)
		(size 0.6096)
		(drill 0.3048)
		(layers "F.Cu" "B.Cu")
		(net "PWRGD_P3V3_STBY_N_R1")
	)
	(via
		(at 81.13522 -141.601444)
		(size 0.508)
		(drill 0.254)
		(layers "F.Cu" "B.Cu")
		(net "PWRGD_P3V3_STBY_N_R1")
	)
	(segment
		(start 80.1624 -141.6558)
		(end 80.0608 -141.5542)
		(width 0.127)
		(layer "B.Cu")
		(net "PWRGD_P3V3_STBY_N_R1")
	)
	(segment
		(start 81.080864 -141.6558)
		(end 80.1624 -141.6558)
		(width 0.127)
		(layer "B.Cu")
		(net "PWRGD_P3V3_STBY_N_R1")
	)
	(segment
		(start 81.13522 -141.601444)
		(end 81.080864 -141.6558)
		(width 0.127)
		(layer "B.Cu")
		(net "PWRGD_P3V3_STBY_N_R1")
	)
	(segment
		(start 80.0608 -141.5542)
		(end 80.0608 -140.9573)
		(width 0.127)
		(layer "B.Cu")
		(net "PWRGD_P3V3_STBY_N_R1")
	)
	(segment
		(start 80.0608 -140.9573)
		(end 80.5815 -140.4366)
		(width 0.127)
		(layer "B.Cu")
		(net "PWRGD_P3V3_STBY_N_R1")
	)
	(segment
		(start 91.567 -180.32476)
		(end 90.705432 -180.32476)
		(width 0.127)
		(layer "F.Cu")
		(net "PWRGD_P3V3_STBY_N")
	)
	(segment
		(start 98.72345 -176.116234)
		(end 99.473766 -176.116234)
		(width 0.127)
		(layer "F.Cu")
		(net "PWRGD_P3V3_STBY_N")
	)
	(segment
		(start 90.705432 -180.32476)
		(end 90.245692 -180.7845)
		(width 0.127)
		(layer "F.Cu")
		(net "PWRGD_P3V3_STBY_N")
	)
	(segment
		(start 99.473766 -176.116234)
		(end 99.695 -175.895)
		(width 0.127)
		(layer "F.Cu")
		(net "PWRGD_P3V3_STBY_N")
	)
	(via
		(at 99.695 -175.895)
		(size 0.508)
		(drill 0.254)
		(layers "F.Cu" "B.Cu")
		(net "PWRGD_P3V3_STBY_N")
	)
	(via
		(at 98.711004 -181.739286)
		(size 0.508)
		(drill 0.254)
		(layers "F.Cu" "B.Cu")
		(net "PWRGD_P3V3_STBY_N")
	)
	(via
		(at 90.245692 -180.7845)
		(size 0.508)
		(drill 0.254)
		(layers "F.Cu" "B.Cu")
		(net "PWRGD_P3V3_STBY_N")
	)
	(via
		(at 81.895442 -139.44854)
		(size 0.6096)
		(drill 0.3048)
		(layers "F.Cu" "B.Cu")
		(net "PWRGD_P3V3_STBY_N")
	)
	(via
		(at 82.724498 -140.047472)
		(size 0.508)
		(drill 0.254)
		(layers "F.Cu" "B.Cu")
		(net "PWRGD_P3V3_STBY_N")
	)
	(via
		(at 101.61524 -140.904722)
		(size 0.508)
		(drill 0.254)
		(layers "F.Cu" "B.Cu")
		(net "PWRGD_P3V3_STBY_N")
	)
	(segment
		(start 101.044502 -143.553942)
		(end 101.044502 -166.38016)
		(width 0.127)
		(layer "B.Cu")
		(net "PWRGD_P3V3_STBY_N")
	)
	(segment
		(start 101.676708 -168.073324)
		(end 101.676454 -168.073578)
		(width 0.127)
		(layer "B.Cu")
		(net "PWRGD_P3V3_STBY_N")
	)
	(segment
		(start 102.23119 -174.026322)
		(end 100.799392 -175.45812)
		(width 0.127)
		(layer "B.Cu")
		(net "PWRGD_P3V3_STBY_N")
	)
	(segment
		(start 100.431346 -175.45812)
		(end 99.994466 -175.895)
		(width 0.127)
		(layer "B.Cu")
		(net "PWRGD_P3V3_STBY_N")
	)
	(segment
		(start 101.676708 -167.012366)
		(end 101.676708 -168.073324)
		(width 0.127)
		(layer "B.Cu")
		(net "PWRGD_P3V3_STBY_N")
	)
	(segment
		(start 101.61524 -140.904722)
		(end 100.8253 -141.694662)
		(width 0.127)
		(layer "B.Cu")
		(net "PWRGD_P3V3_STBY_N")
	)
	(segment
		(start 82.724498 -140.047472)
		(end 82.724498 -139.876784)
		(width 0.127)
		(layer "B.Cu")
		(net "PWRGD_P3V3_STBY_N")
	)
	(segment
		(start 100.799392 -175.45812)
		(end 100.431346 -175.45812)
		(width 0.127)
		(layer "B.Cu")
		(net "PWRGD_P3V3_STBY_N")
	)
	(segment
		(start 99.994466 -175.895)
		(end 99.695 -175.895)
		(width 0.127)
		(layer "B.Cu")
		(net "PWRGD_P3V3_STBY_N")
	)
	(segment
		(start 81.4705 -139.873482)
		(end 81.895442 -139.44854)
		(width 0.127)
		(layer "B.Cu")
		(net "PWRGD_P3V3_STBY_N")
	)
	(segment
		(start 82.296254 -139.44854)
		(end 81.895442 -139.44854)
		(width 0.127)
		(layer "B.Cu")
		(net "PWRGD_P3V3_STBY_N")
	)
	(segment
		(start 101.676454 -169.652696)
		(end 102.23119 -170.207432)
		(width 0.127)
		(layer "B.Cu")
		(net "PWRGD_P3V3_STBY_N")
	)
	(segment
		(start 102.23119 -170.207432)
		(end 102.23119 -174.026322)
		(width 0.127)
		(layer "B.Cu")
		(net "PWRGD_P3V3_STBY_N")
	)
	(segment
		(start 101.676454 -168.073578)
		(end 101.676454 -169.652696)
		(width 0.127)
		(layer "B.Cu")
		(net "PWRGD_P3V3_STBY_N")
	)
	(segment
		(start 82.724498 -139.876784)
		(end 82.296254 -139.44854)
		(width 0.127)
		(layer "B.Cu")
		(net "PWRGD_P3V3_STBY_N")
	)
	(segment
		(start 100.8253 -141.694662)
		(end 100.8253 -143.33474)
		(width 0.127)
		(layer "B.Cu")
		(net "PWRGD_P3V3_STBY_N")
	)
	(segment
		(start 101.044502 -166.38016)
		(end 101.676708 -167.012366)
		(width 0.127)
		(layer "B.Cu")
		(net "PWRGD_P3V3_STBY_N")
	)
	(segment
		(start 81.4705 -140.4366)
		(end 81.4705 -139.873482)
		(width 0.127)
		(layer "B.Cu")
		(net "PWRGD_P3V3_STBY_N")
	)
	(segment
		(start 100.8253 -143.33474)
		(end 101.044502 -143.553942)
		(width 0.127)
		(layer "B.Cu")
		(net "PWRGD_P3V3_STBY_N")
	)
	(segment
		(start 98.711004 -181.739286)
		(end 99.008438 -181.441852)
		(width 0.127)
		(layer "In2.Cu")
		(net "PWRGD_P3V3_STBY_N")
	)
	(segment
		(start 99.008438 -181.441852)
		(end 99.008438 -176.760632)
		(width 0.127)
		(layer "In2.Cu")
		(net "PWRGD_P3V3_STBY_N")
	)
	(segment
		(start 99.008438 -176.760632)
		(end 99.695 -176.07407)
		(width 0.127)
		(layer "In2.Cu")
		(net "PWRGD_P3V3_STBY_N")
	)
	(segment
		(start 99.695 -176.07407)
		(end 99.695 -175.895)
		(width 0.127)
		(layer "In2.Cu")
		(net "PWRGD_P3V3_STBY_N")
	)
	(segment
		(start 84.335112 -141.157452)
		(end 84.215732 -141.038072)
		(width 0.127)
		(layer "In5.Cu")
		(net "PWRGD_P3V3_STBY_N")
	)
	(segment
		(start 84.186522 -141.038072)
		(end 83.195922 -140.047472)
		(width 0.127)
		(layer "In5.Cu")
		(net "PWRGD_P3V3_STBY_N")
	)
	(segment
		(start 98.569018 -181.5973)
		(end 91.058492 -181.5973)
		(width 0.127)
		(layer "In5.Cu")
		(net "PWRGD_P3V3_STBY_N")
	)
	(segment
		(start 101.148642 -140.904722)
		(end 100.47224 -141.581124)
		(width 0.127)
		(layer "In5.Cu")
		(net "PWRGD_P3V3_STBY_N")
	)
	(segment
		(start 83.195922 -140.047472)
		(end 82.724498 -140.047472)
		(width 0.127)
		(layer "In5.Cu")
		(net "PWRGD_P3V3_STBY_N")
	)
	(segment
		(start 98.711004 -181.739286)
		(end 98.569018 -181.5973)
		(width 0.127)
		(layer "In5.Cu")
		(net "PWRGD_P3V3_STBY_N")
	)
	(segment
		(start 90.681048 -141.581124)
		(end 88.132158 -139.032234)
		(width 0.127)
		(layer "In5.Cu")
		(net "PWRGD_P3V3_STBY_N")
	)
	(segment
		(start 88.132158 -139.032234)
		(end 87.091266 -139.032234)
		(width 0.127)
		(layer "In5.Cu")
		(net "PWRGD_P3V3_STBY_N")
	)
	(segment
		(start 87.091266 -139.032234)
		(end 84.966048 -141.157452)
		(width 0.127)
		(layer "In5.Cu")
		(net "PWRGD_P3V3_STBY_N")
	)
	(segment
		(start 101.61524 -140.904722)
		(end 101.148642 -140.904722)
		(width 0.127)
		(layer "In5.Cu")
		(net "PWRGD_P3V3_STBY_N")
	)
	(segment
		(start 84.966048 -141.157452)
		(end 84.335112 -141.157452)
		(width 0.127)
		(layer "In5.Cu")
		(net "PWRGD_P3V3_STBY_N")
	)
	(segment
		(start 91.058492 -181.5973)
		(end 90.245692 -180.7845)
		(width 0.127)
		(layer "In5.Cu")
		(net "PWRGD_P3V3_STBY_N")
	)
	(segment
		(start 100.47224 -141.581124)
		(end 90.681048 -141.581124)
		(width 0.127)
		(layer "In5.Cu")
		(net "PWRGD_P3V3_STBY_N")
	)
	(segment
		(start 84.215732 -141.038072)
		(end 84.186522 -141.038072)
		(width 0.127)
		(layer "In5.Cu")
		(net "PWRGD_P3V3_STBY_N")
	)
	(segment
		(start 86.70417 -168.9354)
		(end 87.2236 -168.9354)
		(width 0.127)
		(layer "F.Cu")
		(net "P1V15_STBY_PG_G")
	)
	(segment
		(start 88.107774 -168.66997)
		(end 88.107774 -169.422826)
		(width 0.127)
		(layer "F.Cu")
		(net "P1V15_STBY_PG_G")
	)
	(segment
		(start 87.145622 -170.384978)
		(end 86.508082 -170.384978)
		(width 0.127)
		(layer "F.Cu")
		(net "P1V15_STBY_PG_G")
	)
	(segment
		(start 85.81136 -171.0817)
		(end 85.471 -171.0817)
		(width 0.127)
		(layer "F.Cu")
		(net "P1V15_STBY_PG_G")
	)
	(segment
		(start 83.95081 -167.7924)
		(end 85.56117 -167.7924)
		(width 0.127)
		(layer "F.Cu")
		(net "P1V15_STBY_PG_G")
	)
	(segment
		(start 87.2236 -168.9354)
		(end 87.48903 -168.66997)
		(width 0.127)
		(layer "F.Cu")
		(net "P1V15_STBY_PG_G")
	)
	(segment
		(start 85.56117 -167.7924)
		(end 86.70417 -168.9354)
		(width 0.127)
		(layer "F.Cu")
		(net "P1V15_STBY_PG_G")
	)
	(segment
		(start 83.200494 -167.042084)
		(end 83.95081 -167.7924)
		(width 0.127)
		(layer "F.Cu")
		(net "P1V15_STBY_PG_G")
	)
	(segment
		(start 86.508082 -170.384978)
		(end 85.81136 -171.0817)
		(width 0.127)
		(layer "F.Cu")
		(net "P1V15_STBY_PG_G")
	)
	(segment
		(start 88.107774 -169.422826)
		(end 87.145622 -170.384978)
		(width 0.127)
		(layer "F.Cu")
		(net "P1V15_STBY_PG_G")
	)
	(segment
		(start 87.48903 -168.66997)
		(end 88.107774 -168.66997)
		(width 0.127)
		(layer "F.Cu")
		(net "P1V15_STBY_PG_G")
	)
	(segment
		(start 83.200494 -166.74592)
		(end 83.200494 -167.042084)
		(width 0.127)
		(layer "F.Cu")
		(net "P1V15_STBY_PG_G")
	)
	(via
		(at 86.508082 -170.384978)
		(size 0.6604)
		(drill 0.3302)
		(layers "F.Cu" "B.Cu")
		(net "P1V15_STBY_PG_G")
	)
	(segment
		(start 96.869758 -170.922442)
		(end 96.5708 -171.2214)
		(width 0.127)
		(layer "F.Cu")
		(net "DPB_MISC_ALERT_OUT_R")
	)
	(segment
		(start 96.266 -172.10532)
		(end 95.15094 -172.10532)
		(width 0.127)
		(layer "F.Cu")
		(net "DPB_MISC_ALERT_OUT_R")
	)
	(segment
		(start 97.155 -170.6372)
		(end 96.869758 -170.922442)
		(width 0.127)
		(layer "F.Cu")
		(net "DPB_MISC_ALERT_OUT_R")
	)
	(segment
		(start 96.5708 -171.2214)
		(end 96.5708 -171.80052)
		(width 0.127)
		(layer "F.Cu")
		(net "DPB_MISC_ALERT_OUT_R")
	)
	(segment
		(start 96.5708 -171.80052)
		(end 96.266 -172.10532)
		(width 0.127)
		(layer "F.Cu")
		(net "DPB_MISC_ALERT_OUT_R")
	)
	(segment
		(start 97.9551 -170.6372)
		(end 97.155 -170.6372)
		(width 0.127)
		(layer "F.Cu")
		(net "DPB_MISC_ALERT_OUT_R")
	)
	(via
		(at 96.869758 -170.922442)
		(size 0.6604)
		(drill 0.3302)
		(layers "F.Cu" "B.Cu")
		(net "DPB_MISC_ALERT_OUT_R")
	)
	(segment
		(start 44.099988 -150.200106)
		(end 43.700192 -150.599902)
		(width 0.127)
		(layer "F.Cu")
		(net "UART_EXP_BMC_TX_R")
	)
	(segment
		(start 39.9288 -163.297616)
		(end 39.9288 -161.0868)
		(width 0.127)
		(layer "F.Cu")
		(net "UART_EXP_BMC_TX_R")
	)
	(segment
		(start 39.684452 -164.538152)
		(end 39.684452 -163.541964)
		(width 0.127)
		(layer "F.Cu")
		(net "UART_EXP_BMC_TX_R")
	)
	(segment
		(start 44.099988 -150.199852)
		(end 44.099988 -150.200106)
		(width 0.127)
		(layer "F.Cu")
		(net "UART_EXP_BMC_TX_R")
	)
	(segment
		(start 39.8399 -164.6936)
		(end 39.684452 -164.538152)
		(width 0.127)
		(layer "F.Cu")
		(net "UART_EXP_BMC_TX_R")
	)
	(segment
		(start 39.684452 -163.541964)
		(end 39.9288 -163.297616)
		(width 0.127)
		(layer "F.Cu")
		(net "UART_EXP_BMC_TX_R")
	)
	(via
		(at 39.684452 -163.541964)
		(size 0.6604)
		(drill 0.3302)
		(layers "F.Cu" "B.Cu")
		(net "UART_EXP_BMC_TX_R")
	)
	(via
		(at 43.700192 -150.599902)
		(size 0.4572)
		(drill 0.2032)
		(layers "F.Cu" "B.Cu")
		(net "UART_EXP_BMC_TX_R")
	)
	(via
		(at 39.9288 -161.0868)
		(size 0.508)
		(drill 0.254)
		(layers "F.Cu" "B.Cu")
		(net "UART_EXP_BMC_TX_R")
	)
	(segment
		(start 43.700192 -150.749508)
		(end 43.700192 -150.599902)
		(width 0.127)
		(layer "B.Cu")
		(net "UART_EXP_BMC_TX_R")
	)
	(segment
		(start 43.293792 -151.155908)
		(end 43.700192 -150.749508)
		(width 0.127)
		(layer "B.Cu")
		(net "UART_EXP_BMC_TX_R")
	)
	(segment
		(start 42.59072 -153.150062)
		(end 43.293792 -152.44699)
		(width 0.127)
		(layer "B.Cu")
		(net "UART_EXP_BMC_TX_R")
	)
	(segment
		(start 43.293792 -152.44699)
		(end 43.293792 -151.155908)
		(width 0.127)
		(layer "B.Cu")
		(net "UART_EXP_BMC_TX_R")
	)
	(segment
		(start 42.59072 -154.736038)
		(end 42.59072 -153.150062)
		(width 0.127)
		(layer "B.Cu")
		(net "UART_EXP_BMC_TX_R")
	)
	(segment
		(start 40.132 -157.194758)
		(end 42.59072 -154.736038)
		(width 0.127)
		(layer "B.Cu")
		(net "UART_EXP_BMC_TX_R")
	)
	(segment
		(start 39.9288 -161.0868)
		(end 40.132 -160.8836)
		(width 0.127)
		(layer "B.Cu")
		(net "UART_EXP_BMC_TX_R")
	)
	(segment
		(start 40.132 -160.8836)
		(end 40.132 -157.194758)
		(width 0.127)
		(layer "B.Cu")
		(net "UART_EXP_BMC_TX_R")
	)
	(segment
		(start 38.9382 -164.7063)
		(end 38.9509 -164.6936)
		(width 0.127)
		(layer "F.Cu")
		(net "UART_EXP_BMC_TX")
	)
	(segment
		(start 37.9222 -165.354)
		(end 38.5318 -165.9636)
		(width 0.127)
		(layer "F.Cu")
		(net "UART_EXP_BMC_TX")
	)
	(segment
		(start 37.9222 -164.7063)
		(end 37.9222 -165.354)
		(width 0.127)
		(layer "F.Cu")
		(net "UART_EXP_BMC_TX")
	)
	(segment
		(start 46.7106 -170.053)
		(end 47.625 -170.9674)
		(width 0.127)
		(layer "F.Cu")
		(net "UART_EXP_BMC_TX")
	)
	(segment
		(start 43.557698 -165.9636)
		(end 46.7106 -169.116502)
		(width 0.127)
		(layer "F.Cu")
		(net "UART_EXP_BMC_TX")
	)
	(segment
		(start 46.7106 -169.116502)
		(end 46.7106 -170.053)
		(width 0.127)
		(layer "F.Cu")
		(net "UART_EXP_BMC_TX")
	)
	(segment
		(start 38.5318 -165.9636)
		(end 43.557698 -165.9636)
		(width 0.127)
		(layer "F.Cu")
		(net "UART_EXP_BMC_TX")
	)
	(segment
		(start 37.9222 -164.7063)
		(end 38.9382 -164.7063)
		(width 0.127)
		(layer "F.Cu")
		(net "UART_EXP_BMC_TX")
	)
	(via
		(at 65.786 -170.74515)
		(size 0.6096)
		(drill 0.3048)
		(layers "F.Cu" "B.Cu")
		(net "UART_EXP_BMC_TX")
	)
	(via
		(at 47.625 -170.9674)
		(size 0.508)
		(drill 0.254)
		(layers "F.Cu" "B.Cu")
		(net "UART_EXP_BMC_TX")
	)
	(segment
		(start 84.866226 -167.74668)
		(end 82.8802 -167.74668)
		(width 0.127)
		(layer "B.Cu")
		(net "UART_EXP_BMC_TX")
	)
	(segment
		(start 85.7504 -168.630854)
		(end 84.866226 -167.74668)
		(width 0.127)
		(layer "B.Cu")
		(net "UART_EXP_BMC_TX")
	)
	(segment
		(start 83.244436 -173.9519)
		(end 83.5025 -173.693836)
		(width 0.127)
		(layer "B.Cu")
		(net "UART_EXP_BMC_TX")
	)
	(segment
		(start 65.786 -170.74515)
		(end 70.571868 -170.74515)
		(width 0.127)
		(layer "B.Cu")
		(net "UART_EXP_BMC_TX")
	)
	(segment
		(start 59.454034 -170.09491)
		(end 62.102492 -170.09491)
		(width 0.127)
		(layer "B.Cu")
		(net "UART_EXP_BMC_TX")
	)
	(segment
		(start 70.571868 -170.74515)
		(end 72.009 -172.182282)
		(width 0.127)
		(layer "B.Cu")
		(net "UART_EXP_BMC_TX")
	)
	(segment
		(start 73.550018 -173.9519)
		(end 83.244436 -173.9519)
		(width 0.127)
		(layer "B.Cu")
		(net "UART_EXP_BMC_TX")
	)
	(segment
		(start 62.102492 -170.09491)
		(end 62.752732 -170.74515)
		(width 0.127)
		(layer "B.Cu")
		(net "UART_EXP_BMC_TX")
	)
	(segment
		(start 85.7504 -170.561)
		(end 85.7504 -168.630854)
		(width 0.127)
		(layer "B.Cu")
		(net "UART_EXP_BMC_TX")
	)
	(segment
		(start 62.752732 -170.74515)
		(end 65.786 -170.74515)
		(width 0.127)
		(layer "B.Cu")
		(net "UART_EXP_BMC_TX")
	)
	(segment
		(start 58.185304 -171.36364)
		(end 59.454034 -170.09491)
		(width 0.127)
		(layer "B.Cu")
		(net "UART_EXP_BMC_TX")
	)
	(segment
		(start 48.02124 -171.36364)
		(end 58.185304 -171.36364)
		(width 0.127)
		(layer "B.Cu")
		(net "UART_EXP_BMC_TX")
	)
	(segment
		(start 72.009 -172.182282)
		(end 72.009 -172.410882)
		(width 0.127)
		(layer "B.Cu")
		(net "UART_EXP_BMC_TX")
	)
	(segment
		(start 47.625 -170.9674)
		(end 48.02124 -171.36364)
		(width 0.127)
		(layer "B.Cu")
		(net "UART_EXP_BMC_TX")
	)
	(segment
		(start 83.5025 -172.8089)
		(end 85.7504 -170.561)
		(width 0.127)
		(layer "B.Cu")
		(net "UART_EXP_BMC_TX")
	)
	(segment
		(start 72.009 -172.410882)
		(end 73.550018 -173.9519)
		(width 0.127)
		(layer "B.Cu")
		(net "UART_EXP_BMC_TX")
	)
	(segment
		(start 83.5025 -173.693836)
		(end 83.5025 -172.8089)
		(width 0.127)
		(layer "B.Cu")
		(net "UART_EXP_BMC_TX")
	)
	(segment
		(start 44.899834 -150.199852)
		(end 44.500038 -150.599648)
		(width 0.127)
		(layer "F.Cu")
		(net "UART_EXP_BMC_RX_R")
	)
	(segment
		(start 40.6908 -163.4363)
		(end 40.894 -163.6395)
		(width 0.127)
		(layer "F.Cu")
		(net "UART_EXP_BMC_RX_R")
	)
	(segment
		(start 44.500038 -150.599648)
		(end 44.500038 -150.599902)
		(width 0.127)
		(layer "F.Cu")
		(net "UART_EXP_BMC_RX_R")
	)
	(segment
		(start 40.6908 -162.4584)
		(end 40.6908 -163.4363)
		(width 0.127)
		(layer "F.Cu")
		(net "UART_EXP_BMC_RX_R")
	)
	(segment
		(start 40.894 -161.1122)
		(end 40.6908 -161.3154)
		(width 0.127)
		(layer "F.Cu")
		(net "UART_EXP_BMC_RX_R")
	)
	(segment
		(start 40.6908 -161.3154)
		(end 40.6908 -162.4584)
		(width 0.127)
		(layer "F.Cu")
		(net "UART_EXP_BMC_RX_R")
	)
	(via
		(at 40.6908 -162.4584)
		(size 0.6604)
		(drill 0.3302)
		(layers "F.Cu" "B.Cu")
		(net "UART_EXP_BMC_RX_R")
	)
	(via
		(at 40.894 -161.1122)
		(size 0.508)
		(drill 0.254)
		(layers "F.Cu" "B.Cu")
		(net "UART_EXP_BMC_RX_R")
	)
	(via
		(at 44.500038 -150.599902)
		(size 0.4572)
		(drill 0.2032)
		(layers "F.Cu" "B.Cu")
		(net "UART_EXP_BMC_RX_R")
	)
	(segment
		(start 42.890948 -154.760422)
		(end 42.890948 -154.618182)
		(width 0.127)
		(layer "B.Cu")
		(net "UART_EXP_BMC_RX_R")
	)
	(segment
		(start 44.500038 -150.84298)
		(end 44.500038 -150.599902)
		(width 0.127)
		(layer "B.Cu")
		(net "UART_EXP_BMC_RX_R")
	)
	(segment
		(start 44.113704 -153.395426)
		(end 44.113704 -153.143458)
		(width 0.127)
		(layer "B.Cu")
		(net "UART_EXP_BMC_RX_R")
	)
	(segment
		(start 40.894 -157.330902)
		(end 41.523412 -156.70149)
		(width 0.127)
		(layer "B.Cu")
		(net "UART_EXP_BMC_RX_R")
	)
	(segment
		(start 44.893738 -151.23668)
		(end 44.500038 -150.84298)
		(width 0.127)
		(layer "B.Cu")
		(net "UART_EXP_BMC_RX_R")
	)
	(segment
		(start 41.523412 -156.70149)
		(end 41.523412 -156.128212)
		(width 0.127)
		(layer "B.Cu")
		(net "UART_EXP_BMC_RX_R")
	)
	(segment
		(start 42.890948 -154.618182)
		(end 44.113704 -153.395426)
		(width 0.127)
		(layer "B.Cu")
		(net "UART_EXP_BMC_RX_R")
	)
	(segment
		(start 44.893738 -152.363424)
		(end 44.893738 -151.23668)
		(width 0.127)
		(layer "B.Cu")
		(net "UART_EXP_BMC_RX_R")
	)
	(segment
		(start 40.894 -161.1122)
		(end 40.894 -157.330902)
		(width 0.127)
		(layer "B.Cu")
		(net "UART_EXP_BMC_RX_R")
	)
	(segment
		(start 44.113704 -153.143458)
		(end 44.893738 -152.363424)
		(width 0.127)
		(layer "B.Cu")
		(net "UART_EXP_BMC_RX_R")
	)
	(segment
		(start 41.523412 -156.128212)
		(end 42.890948 -154.760422)
		(width 0.127)
		(layer "B.Cu")
		(net "UART_EXP_BMC_RX_R")
	)
	(segment
		(start 42.6974 -165.3159)
		(end 41.91 -164.5285)
		(width 0.127)
		(layer "F.Cu")
		(net "UART_EXP_BMC_RX")
	)
	(segment
		(start 48.3108 -170.434)
		(end 47.3456 -169.4688)
		(width 0.127)
		(layer "F.Cu")
		(net "UART_EXP_BMC_RX")
	)
	(segment
		(start 43.808142 -165.3159)
		(end 42.6974 -165.3159)
		(width 0.127)
		(layer "F.Cu")
		(net "UART_EXP_BMC_RX")
	)
	(segment
		(start 40.894 -164.5285)
		(end 41.91 -164.5285)
		(width 0.127)
		(layer "F.Cu")
		(net "UART_EXP_BMC_RX")
	)
	(segment
		(start 47.3456 -169.4688)
		(end 47.3456 -168.853358)
		(width 0.127)
		(layer "F.Cu")
		(net "UART_EXP_BMC_RX")
	)
	(segment
		(start 47.3456 -168.853358)
		(end 43.808142 -165.3159)
		(width 0.127)
		(layer "F.Cu")
		(net "UART_EXP_BMC_RX")
	)
	(via
		(at 77.1652 -173.147228)
		(size 0.6096)
		(drill 0.3048)
		(layers "F.Cu" "B.Cu")
		(net "UART_EXP_BMC_RX")
	)
	(via
		(at 48.3108 -170.434)
		(size 0.508)
		(drill 0.254)
		(layers "F.Cu" "B.Cu")
		(net "UART_EXP_BMC_RX")
	)
	(segment
		(start 62.865 -169.5577)
		(end 68.054982 -169.5577)
		(width 0.127)
		(layer "B.Cu")
		(net "UART_EXP_BMC_RX")
	)
	(segment
		(start 73.64349 -173.147228)
		(end 77.1652 -173.147228)
		(width 0.127)
		(layer "B.Cu")
		(net "UART_EXP_BMC_RX")
	)
	(segment
		(start 48.3108 -170.434)
		(end 48.60544 -170.72864)
		(width 0.127)
		(layer "B.Cu")
		(net "UART_EXP_BMC_RX")
	)
	(segment
		(start 72.644 -171.674282)
		(end 72.644 -172.147738)
		(width 0.127)
		(layer "B.Cu")
		(net "UART_EXP_BMC_RX")
	)
	(segment
		(start 57.92216 -170.72864)
		(end 59.19089 -169.45991)
		(width 0.127)
		(layer "B.Cu")
		(net "UART_EXP_BMC_RX")
	)
	(segment
		(start 78.356968 -173.147228)
		(end 80.320896 -171.1833)
		(width 0.127)
		(layer "B.Cu")
		(net "UART_EXP_BMC_RX")
	)
	(segment
		(start 77.1652 -173.147228)
		(end 78.356968 -173.147228)
		(width 0.127)
		(layer "B.Cu")
		(net "UART_EXP_BMC_RX")
	)
	(segment
		(start 59.19089 -169.45991)
		(end 62.76721 -169.45991)
		(width 0.127)
		(layer "B.Cu")
		(net "UART_EXP_BMC_RX")
	)
	(segment
		(start 62.76721 -169.45991)
		(end 62.865 -169.5577)
		(width 0.127)
		(layer "B.Cu")
		(net "UART_EXP_BMC_RX")
	)
	(segment
		(start 68.054982 -169.5577)
		(end 68.728082 -168.8846)
		(width 0.127)
		(layer "B.Cu")
		(net "UART_EXP_BMC_RX")
	)
	(segment
		(start 48.60544 -170.72864)
		(end 57.92216 -170.72864)
		(width 0.127)
		(layer "B.Cu")
		(net "UART_EXP_BMC_RX")
	)
	(segment
		(start 72.644 -172.147738)
		(end 73.64349 -173.147228)
		(width 0.127)
		(layer "B.Cu")
		(net "UART_EXP_BMC_RX")
	)
	(segment
		(start 69.854318 -168.8846)
		(end 72.644 -171.674282)
		(width 0.127)
		(layer "B.Cu")
		(net "UART_EXP_BMC_RX")
	)
	(segment
		(start 80.320896 -171.1833)
		(end 80.9879 -171.1833)
		(width 0.127)
		(layer "B.Cu")
		(net "UART_EXP_BMC_RX")
	)
	(segment
		(start 68.728082 -168.8846)
		(end 69.854318 -168.8846)
		(width 0.127)
		(layer "B.Cu")
		(net "UART_EXP_BMC_RX")
	)
	(segment
		(start 81.82356 -170.34764)
		(end 82.8802 -170.34764)
		(width 0.127)
		(layer "B.Cu")
		(net "UART_EXP_BMC_RX")
	)
	(segment
		(start 80.9879 -171.1833)
		(end 81.82356 -170.34764)
		(width 0.127)
		(layer "B.Cu")
		(net "UART_EXP_BMC_RX")
	)
	(via
		(at 79.8195 -168.3004)
		(size 0.6096)
		(drill 0.3048)
		(layers "F.Cu" "B.Cu")
		(net "EXP_UART_EN_R")
	)
	(segment
		(start 79.3496 -167.8305)
		(end 79.8195 -168.3004)
		(width 0.127)
		(layer "B.Cu")
		(net "EXP_UART_EN_R")
	)
	(segment
		(start 84.939124 -169.497248)
		(end 84.489036 -169.04716)
		(width 0.127)
		(layer "B.Cu")
		(net "EXP_UART_EN_R")
	)
	(segment
		(start 79.8195 -168.3004)
		(end 80.56626 -169.04716)
		(width 0.127)
		(layer "B.Cu")
		(net "EXP_UART_EN_R")
	)
	(segment
		(start 84.489036 -169.04716)
		(end 82.8802 -169.04716)
		(width 0.127)
		(layer "B.Cu")
		(net "EXP_UART_EN_R")
	)
	(segment
		(start 81.28 -171.8183)
		(end 82.10042 -170.99788)
		(width 0.127)
		(layer "B.Cu")
		(net "EXP_UART_EN_R")
	)
	(segment
		(start 80.56626 -169.04716)
		(end 82.8802 -169.04716)
		(width 0.127)
		(layer "B.Cu")
		(net "EXP_UART_EN_R")
	)
	(segment
		(start 82.10042 -170.99788)
		(end 82.8802 -170.99788)
		(width 0.127)
		(layer "B.Cu")
		(net "EXP_UART_EN_R")
	)
	(segment
		(start 84.83473 -170.457876)
		(end 84.939124 -170.353736)
		(width 0.127)
		(layer "B.Cu")
		(net "EXP_UART_EN_R")
	)
	(segment
		(start 80.08366 -172.31868)
		(end 80.58404 -171.8183)
		(width 0.127)
		(layer "B.Cu")
		(net "EXP_UART_EN_R")
	)
	(segment
		(start 84.939124 -170.353736)
		(end 84.939124 -169.497248)
		(width 0.127)
		(layer "B.Cu")
		(net "EXP_UART_EN_R")
	)
	(segment
		(start 80.58404 -171.8183)
		(end 81.28 -171.8183)
		(width 0.127)
		(layer "B.Cu")
		(net "EXP_UART_EN_R")
	)
	(segment
		(start 84.294726 -170.99788)
		(end 84.83473 -170.457876)
		(width 0.127)
		(layer "B.Cu")
		(net "EXP_UART_EN_R")
	)
	(segment
		(start 79.3496 -167.1447)
		(end 79.3496 -167.8305)
		(width 0.127)
		(layer "B.Cu")
		(net "EXP_UART_EN_R")
	)
	(segment
		(start 82.8802 -170.99788)
		(end 84.294726 -170.99788)
		(width 0.127)
		(layer "B.Cu")
		(net "EXP_UART_EN_R")
	)
	(segment
		(start 42.100246 -137.799826)
		(end 42.100246 -137.80008)
		(width 0.127)
		(layer "F.Cu")
		(net "EXP_UART_EN")
	)
	(segment
		(start 42.100246 -137.80008)
		(end 42.500042 -138.199876)
		(width 0.127)
		(layer "F.Cu")
		(net "EXP_UART_EN")
	)
	(via
		(at 77.1906 -167.9702)
		(size 0.6096)
		(drill 0.3048)
		(layers "F.Cu" "B.Cu")
		(net "EXP_UART_EN")
	)
	(via
		(at 42.100246 -137.799826)
		(size 0.4572)
		(drill 0.2032)
		(layers "F.Cu" "B.Cu")
		(net "EXP_UART_EN")
	)
	(via
		(at 74.444098 -134.765034)
		(size 0.508)
		(drill 0.254)
		(layers "F.Cu" "B.Cu")
		(net "EXP_UART_EN")
	)
	(via
		(at 77.3938 -169.799)
		(size 0.508)
		(drill 0.254)
		(layers "F.Cu" "B.Cu")
		(net "EXP_UART_EN")
	)
	(segment
		(start 78.0161 -167.1447)
		(end 77.1906 -167.9702)
		(width 0.127)
		(layer "B.Cu")
		(net "EXP_UART_EN")
	)
	(segment
		(start 77.3303 -169.799)
		(end 77.3938 -169.799)
		(width 0.127)
		(layer "B.Cu")
		(net "EXP_UART_EN")
	)
	(segment
		(start 76.7207 -168.4401)
		(end 76.7207 -169.1894)
		(width 0.127)
		(layer "B.Cu")
		(net "EXP_UART_EN")
	)
	(segment
		(start 77.1906 -167.9702)
		(end 76.7207 -168.4401)
		(width 0.127)
		(layer "B.Cu")
		(net "EXP_UART_EN")
	)
	(segment
		(start 76.7207 -169.1894)
		(end 77.3303 -169.799)
		(width 0.127)
		(layer "B.Cu")
		(net "EXP_UART_EN")
	)
	(segment
		(start 78.4606 -167.1447)
		(end 78.0161 -167.1447)
		(width 0.127)
		(layer "B.Cu")
		(net "EXP_UART_EN")
	)
	(segment
		(start 79.587344 -163.936934)
		(end 77.707744 -165.816534)
		(width 0.127)
		(layer "In2.Cu")
		(net "EXP_UART_EN")
	)
	(segment
		(start 76.265278 -141.504162)
		(end 76.645008 -141.883892)
		(width 0.127)
		(layer "In2.Cu")
		(net "EXP_UART_EN")
	)
	(segment
		(start 75.279504 -138.294872)
		(end 75.279504 -139.99083)
		(width 0.127)
		(layer "In2.Cu")
		(net "EXP_UART_EN")
	)
	(segment
		(start 78.2955 -152.154382)
		(end 78.2955 -153.607262)
		(width 0.127)
		(layer "In2.Cu")
		(net "EXP_UART_EN")
	)
	(segment
		(start 78.2955 -159.34309)
		(end 79.587344 -160.634934)
		(width 0.127)
		(layer "In2.Cu")
		(net "EXP_UART_EN")
	)
	(segment
		(start 74.444098 -134.765034)
		(end 74.444098 -137.459466)
		(width 0.127)
		(layer "In2.Cu")
		(net "EXP_UART_EN")
	)
	(segment
		(start 78.295246 -154.449272)
		(end 78.2955 -154.449526)
		(width 0.127)
		(layer "In2.Cu")
		(net "EXP_UART_EN")
	)
	(segment
		(start 78.2955 -153.607262)
		(end 78.295246 -153.607516)
		(width 0.127)
		(layer "In2.Cu")
		(net "EXP_UART_EN")
	)
	(segment
		(start 75.279504 -139.99083)
		(end 76.265278 -140.976604)
		(width 0.127)
		(layer "In2.Cu")
		(net "EXP_UART_EN")
	)
	(segment
		(start 79.587344 -160.634934)
		(end 79.587344 -163.936934)
		(width 0.127)
		(layer "In2.Cu")
		(net "EXP_UART_EN")
	)
	(segment
		(start 77.3938 -169.5323)
		(end 77.3938 -169.799)
		(width 0.127)
		(layer "In2.Cu")
		(net "EXP_UART_EN")
	)
	(segment
		(start 76.7969 -147.221702)
		(end 76.5175 -147.501102)
		(width 0.127)
		(layer "In2.Cu")
		(net "EXP_UART_EN")
	)
	(segment
		(start 77.932534 -168.993566)
		(end 77.3938 -169.5323)
		(width 0.127)
		(layer "In2.Cu")
		(net "EXP_UART_EN")
	)
	(segment
		(start 76.265278 -140.976604)
		(end 76.265278 -141.504162)
		(width 0.127)
		(layer "In2.Cu")
		(net "EXP_UART_EN")
	)
	(segment
		(start 77.707744 -165.816534)
		(end 77.707744 -166.290498)
		(width 0.127)
		(layer "In2.Cu")
		(net "EXP_UART_EN")
	)
	(segment
		(start 77.707744 -166.290498)
		(end 77.932534 -166.515288)
		(width 0.127)
		(layer "In2.Cu")
		(net "EXP_UART_EN")
	)
	(segment
		(start 76.645008 -141.884146)
		(end 76.7969 -142.036038)
		(width 0.127)
		(layer "In2.Cu")
		(net "EXP_UART_EN")
	)
	(segment
		(start 77.932534 -166.515288)
		(end 77.932534 -168.993566)
		(width 0.127)
		(layer "In2.Cu")
		(net "EXP_UART_EN")
	)
	(segment
		(start 78.2955 -154.449526)
		(end 78.2955 -159.34309)
		(width 0.127)
		(layer "In2.Cu")
		(net "EXP_UART_EN")
	)
	(segment
		(start 76.5175 -150.376382)
		(end 78.2955 -152.154382)
		(width 0.127)
		(layer "In2.Cu")
		(net "EXP_UART_EN")
	)
	(segment
		(start 74.444098 -137.459466)
		(end 75.279504 -138.294872)
		(width 0.127)
		(layer "In2.Cu")
		(net "EXP_UART_EN")
	)
	(segment
		(start 76.5175 -147.501102)
		(end 76.5175 -150.376382)
		(width 0.127)
		(layer "In2.Cu")
		(net "EXP_UART_EN")
	)
	(segment
		(start 76.645008 -141.883892)
		(end 76.645008 -141.884146)
		(width 0.127)
		(layer "In2.Cu")
		(net "EXP_UART_EN")
	)
	(segment
		(start 76.7969 -142.036038)
		(end 76.7969 -147.221702)
		(width 0.127)
		(layer "In2.Cu")
		(net "EXP_UART_EN")
	)
	(segment
		(start 78.295246 -153.607516)
		(end 78.295246 -154.449272)
		(width 0.127)
		(layer "In2.Cu")
		(net "EXP_UART_EN")
	)
	(segment
		(start 65.3034 -135.1661)
		(end 66.678048 -133.791452)
		(width 0.127)
		(layer "In5.Cu")
		(net "EXP_UART_EN")
	)
	(segment
		(start 73.932796 -134.765034)
		(end 74.444098 -134.765034)
		(width 0.127)
		(layer "In5.Cu")
		(net "EXP_UART_EN")
	)
	(segment
		(start 56.825642 -135.9027)
		(end 60.938918 -135.9027)
		(width 0.127)
		(layer "In5.Cu")
		(net "EXP_UART_EN")
	)
	(segment
		(start 61.675518 -135.1661)
		(end 65.3034 -135.1661)
		(width 0.127)
		(layer "In5.Cu")
		(net "EXP_UART_EN")
	)
	(segment
		(start 72.959214 -133.791452)
		(end 73.932796 -134.765034)
		(width 0.127)
		(layer "In5.Cu")
		(net "EXP_UART_EN")
	)
	(segment
		(start 56.688736 -135.765794)
		(end 56.825642 -135.9027)
		(width 0.127)
		(layer "In5.Cu")
		(net "EXP_UART_EN")
	)
	(segment
		(start 60.938918 -135.9027)
		(end 61.675518 -135.1661)
		(width 0.127)
		(layer "In5.Cu")
		(net "EXP_UART_EN")
	)
	(segment
		(start 66.678048 -133.791452)
		(end 72.959214 -133.791452)
		(width 0.127)
		(layer "In5.Cu")
		(net "EXP_UART_EN")
	)
	(segment
		(start 44.134278 -135.765794)
		(end 56.688736 -135.765794)
		(width 0.127)
		(layer "In5.Cu")
		(net "EXP_UART_EN")
	)
	(segment
		(start 42.100246 -137.799826)
		(end 44.134278 -135.765794)
		(width 0.127)
		(layer "In5.Cu")
		(net "EXP_UART_EN")
	)
	(segment
		(start 40.611806 -134.805166)
		(end 42.078148 -136.271508)
		(width 0.127)
		(layer "F.Cu")
		(net "CONN_A_PRSNTA")
	)
	(segment
		(start 38.84803 -131.02082)
		(end 39.182548 -131.355338)
		(width 0.127)
		(layer "F.Cu")
		(net "CONN_A_PRSNTA")
	)
	(segment
		(start 34.341308 -121.461276)
		(end 34.341308 -123.762008)
		(width 0.127)
		(layer "F.Cu")
		(net "CONN_A_PRSNTA")
	)
	(segment
		(start 42.078148 -136.977882)
		(end 42.500042 -137.399776)
		(width 0.127)
		(layer "F.Cu")
		(net "CONN_A_PRSNTA")
	)
	(segment
		(start 42.078148 -136.271508)
		(end 42.078148 -136.977882)
		(width 0.127)
		(layer "F.Cu")
		(net "CONN_A_PRSNTA")
	)
	(segment
		(start 39.182548 -131.355338)
		(end 39.182548 -133.183884)
		(width 0.127)
		(layer "F.Cu")
		(net "CONN_A_PRSNTA")
	)
	(segment
		(start 40.611806 -134.596886)
		(end 40.611806 -134.805166)
		(width 0.127)
		(layer "F.Cu")
		(net "CONN_A_PRSNTA")
	)
	(segment
		(start 34.341308 -123.762008)
		(end 38.84803 -128.26873)
		(width 0.127)
		(layer "F.Cu")
		(net "CONN_A_PRSNTA")
	)
	(segment
		(start 39.182548 -133.183884)
		(end 39.72814 -133.729476)
		(width 0.127)
		(layer "F.Cu")
		(net "CONN_A_PRSNTA")
	)
	(segment
		(start 39.744396 -133.729476)
		(end 40.611806 -134.596886)
		(width 0.127)
		(layer "F.Cu")
		(net "CONN_A_PRSNTA")
	)
	(segment
		(start 34.8107 -120.991884)
		(end 34.341308 -121.461276)
		(width 0.127)
		(layer "F.Cu")
		(net "CONN_A_PRSNTA")
	)
	(segment
		(start 42.500042 -137.399776)
		(end 42.500042 -137.40003)
		(width 0.127)
		(layer "F.Cu")
		(net "CONN_A_PRSNTA")
	)
	(segment
		(start 38.84803 -128.26873)
		(end 38.84803 -131.02082)
		(width 0.127)
		(layer "F.Cu")
		(net "CONN_A_PRSNTA")
	)
	(segment
		(start 39.72814 -133.729476)
		(end 39.744396 -133.729476)
		(width 0.127)
		(layer "F.Cu")
		(net "CONN_A_PRSNTA")
	)
	(via
		(at 92.602558 -107.955842)
		(size 0.6096)
		(drill 0.3048)
		(layers "F.Cu" "B.Cu")
		(net "CONN_A_PRSNTA")
	)
	(via
		(at 64.7446 -115.2906)
		(size 0.508)
		(drill 0.254)
		(layers "F.Cu" "B.Cu")
		(net "CONN_A_PRSNTA")
	)
	(via
		(at 34.8107 -120.991884)
		(size 0.508)
		(drill 0.254)
		(layers "F.Cu" "B.Cu")
		(net "CONN_A_PRSNTA")
	)
	(segment
		(start 76.39812 -111.325914)
		(end 89.26957 -111.325914)
		(width 0.127)
		(layer "B.Cu")
		(net "CONN_A_PRSNTA")
	)
	(segment
		(start 89.26957 -111.325914)
		(end 92.234258 -108.361226)
		(width 0.127)
		(layer "B.Cu")
		(net "CONN_A_PRSNTA")
	)
	(segment
		(start 90.953844 -95.967296)
		(end 88.692228 -95.967296)
		(width 0.127)
		(layer "B.Cu")
		(net "CONN_A_PRSNTA")
	)
	(segment
		(start 64.7446 -115.2906)
		(end 65.8749 -114.1603)
		(width 0.127)
		(layer "B.Cu")
		(net "CONN_A_PRSNTA")
	)
	(segment
		(start 92.234258 -108.361226)
		(end 92.234258 -108.324142)
		(width 0.127)
		(layer "B.Cu")
		(net "CONN_A_PRSNTA")
	)
	(segment
		(start 87.617554 -95.967296)
		(end 85.415628 -98.169222)
		(width 0.127)
		(layer "B.Cu")
		(net "CONN_A_PRSNTA")
	)
	(segment
		(start 74.770234 -112.9538)
		(end 76.39812 -111.325914)
		(width 0.127)
		(layer "B.Cu")
		(net "CONN_A_PRSNTA")
	)
	(segment
		(start 92.602558 -107.955842)
		(end 93.028262 -107.530138)
		(width 0.127)
		(layer "B.Cu")
		(net "CONN_A_PRSNTA")
	)
	(segment
		(start 69.3801 -114.1603)
		(end 70.5866 -112.9538)
		(width 0.127)
		(layer "B.Cu")
		(net "CONN_A_PRSNTA")
	)
	(segment
		(start 92.234258 -108.324142)
		(end 92.602558 -107.955842)
		(width 0.127)
		(layer "B.Cu")
		(net "CONN_A_PRSNTA")
	)
	(segment
		(start 93.028262 -107.530138)
		(end 93.028262 -98.041714)
		(width 0.127)
		(layer "B.Cu")
		(net "CONN_A_PRSNTA")
	)
	(segment
		(start 93.028262 -98.041714)
		(end 90.953844 -95.967296)
		(width 0.127)
		(layer "B.Cu")
		(net "CONN_A_PRSNTA")
	)
	(segment
		(start 88.692228 -95.967296)
		(end 87.617554 -95.967296)
		(width 0.127)
		(layer "B.Cu")
		(net "CONN_A_PRSNTA")
	)
	(segment
		(start 65.8749 -114.1603)
		(end 69.3801 -114.1603)
		(width 0.127)
		(layer "B.Cu")
		(net "CONN_A_PRSNTA")
	)
	(segment
		(start 70.5866 -112.9538)
		(end 74.770234 -112.9538)
		(width 0.127)
		(layer "B.Cu")
		(net "CONN_A_PRSNTA")
	)
	(segment
		(start 64.4144 -115.6208)
		(end 55.973218 -115.6208)
		(width 0.127)
		(layer "In5.Cu")
		(net "CONN_A_PRSNTA")
	)
	(segment
		(start 46.21657 -118.175024)
		(end 45.087794 -119.3038)
		(width 0.127)
		(layer "In5.Cu")
		(net "CONN_A_PRSNTA")
	)
	(segment
		(start 43.3832 -119.3038)
		(end 42.926 -119.761)
		(width 0.127)
		(layer "In5.Cu")
		(net "CONN_A_PRSNTA")
	)
	(segment
		(start 64.7446 -115.2906)
		(end 64.4144 -115.6208)
		(width 0.127)
		(layer "In5.Cu")
		(net "CONN_A_PRSNTA")
	)
	(segment
		(start 47.741586 -115.290346)
		(end 46.21657 -116.815362)
		(width 0.127)
		(layer "In5.Cu")
		(net "CONN_A_PRSNTA")
	)
	(segment
		(start 42.926 -119.761)
		(end 38.906704 -119.761)
		(width 0.127)
		(layer "In5.Cu")
		(net "CONN_A_PRSNTA")
	)
	(segment
		(start 38.906704 -119.761)
		(end 37.995352 -120.672352)
		(width 0.127)
		(layer "In5.Cu")
		(net "CONN_A_PRSNTA")
	)
	(segment
		(start 37.995352 -120.672352)
		(end 35.130232 -120.672352)
		(width 0.127)
		(layer "In5.Cu")
		(net "CONN_A_PRSNTA")
	)
	(segment
		(start 55.973218 -115.6208)
		(end 55.642764 -115.290346)
		(width 0.127)
		(layer "In5.Cu")
		(net "CONN_A_PRSNTA")
	)
	(segment
		(start 55.642764 -115.290346)
		(end 47.741586 -115.290346)
		(width 0.127)
		(layer "In5.Cu")
		(net "CONN_A_PRSNTA")
	)
	(segment
		(start 35.130232 -120.672352)
		(end 34.8107 -120.991884)
		(width 0.127)
		(layer "In5.Cu")
		(net "CONN_A_PRSNTA")
	)
	(segment
		(start 45.087794 -119.3038)
		(end 43.3832 -119.3038)
		(width 0.127)
		(layer "In5.Cu")
		(net "CONN_A_PRSNTA")
	)
	(segment
		(start 46.21657 -116.815362)
		(end 46.21657 -118.175024)
		(width 0.127)
		(layer "In5.Cu")
		(net "CONN_A_PRSNTA")
	)
	(segment
		(start 53.310028 -136.67486)
		(end 53.310028 -136.462516)
		(width 0.127)
		(layer "F.Cu")
		(net "LPC_CPU_FRAME_N")
	)
	(segment
		(start 52.774342 -136.975088)
		(end 53.0098 -136.975088)
		(width 0.127)
		(layer "F.Cu")
		(net "LPC_CPU_FRAME_N")
	)
	(segment
		(start 54.0004 -132.940044)
		(end 54.225698 -133.165342)
		(width 0.127)
		(layer "F.Cu")
		(net "LPC_CPU_FRAME_N")
	)
	(segment
		(start 54.225698 -134.233666)
		(end 54.225698 -133.165342)
		(width 0.127)
		(layer "F.Cu")
		(net "LPC_CPU_FRAME_N")
	)
	(segment
		(start 53.310028 -136.462516)
		(end 54.1655 -135.607044)
		(width 0.127)
		(layer "F.Cu")
		(net "LPC_CPU_FRAME_N")
	)
	(segment
		(start 54.1655 -135.607044)
		(end 54.1655 -134.293864)
		(width 0.127)
		(layer "F.Cu")
		(net "LPC_CPU_FRAME_N")
	)
	(segment
		(start 53.0098 -136.975088)
		(end 53.310028 -136.67486)
		(width 0.127)
		(layer "F.Cu")
		(net "LPC_CPU_FRAME_N")
	)
	(segment
		(start 52.099972 -137.40003)
		(end 52.3494 -137.40003)
		(width 0.127)
		(layer "F.Cu")
		(net "LPC_CPU_FRAME_N")
	)
	(segment
		(start 54.1655 -134.293864)
		(end 54.225698 -134.233666)
		(width 0.127)
		(layer "F.Cu")
		(net "LPC_CPU_FRAME_N")
	)
	(segment
		(start 52.3494 -137.40003)
		(end 52.774342 -136.975088)
		(width 0.127)
		(layer "F.Cu")
		(net "LPC_CPU_FRAME_N")
	)
	(segment
		(start 54.0004 -132.1943)
		(end 54.0004 -132.940044)
		(width 0.127)
		(layer "F.Cu")
		(net "LPC_CPU_FRAME_N")
	)
	(via
		(at 54.225698 -133.165342)
		(size 0.6604)
		(drill 0.3302)
		(layers "F.Cu" "B.Cu")
		(net "LPC_CPU_FRAME_N")
	)
	(segment
		(start 55.871364 -130.991864)
		(end 56.181498 -131.301998)
		(width 0.127)
		(layer "F.Cu")
		(net "LPC_CPU_CLKOUT0")
	)
	(segment
		(start 56.181498 -131.301998)
		(end 56.181498 -132.128514)
		(width 0.127)
		(layer "F.Cu")
		(net "LPC_CPU_CLKOUT0")
	)
	(segment
		(start 55.0926 -130.991864)
		(end 55.871364 -130.991864)
		(width 0.127)
		(layer "F.Cu")
		(net "LPC_CPU_CLKOUT0")
	)
	(segment
		(start 55.323994 -132.986018)
		(end 55.323994 -135.487664)
		(width 0.127)
		(layer "F.Cu")
		(net "LPC_CPU_CLKOUT0")
	)
	(segment
		(start 56.181498 -132.128514)
		(end 55.323994 -132.986018)
		(width 0.127)
		(layer "F.Cu")
		(net "LPC_CPU_CLKOUT0")
	)
	(segment
		(start 55.323994 -135.487664)
		(end 54.500018 -136.31164)
		(width 0.127)
		(layer "F.Cu")
		(net "LPC_CPU_CLKOUT0")
	)
	(segment
		(start 54.500018 -136.31164)
		(end 54.500018 -136.59993)
		(width 0.127)
		(layer "F.Cu")
		(net "LPC_CPU_CLKOUT0")
	)
	(via
		(at 56.181498 -131.301998)
		(size 0.6604)
		(drill 0.3302)
		(layers "F.Cu" "B.Cu")
		(net "LPC_CPU_CLKOUT0")
	)
	(segment
		(start 52.099972 -136.59993)
		(end 52.099972 -135.733536)
		(width 0.127)
		(layer "F.Cu")
		(net "IRQ_CPU_SERIAL")
	)
	(segment
		(start 51.29784 -134.931404)
		(end 51.29784 -133.948932)
		(width 0.127)
		(layer "F.Cu")
		(net "IRQ_CPU_SERIAL")
	)
	(segment
		(start 51.29784 -133.948932)
		(end 52.007008 -133.239764)
		(width 0.127)
		(layer "F.Cu")
		(net "IRQ_CPU_SERIAL")
	)
	(segment
		(start 52.099972 -135.733536)
		(end 51.29784 -134.931404)
		(width 0.127)
		(layer "F.Cu")
		(net "IRQ_CPU_SERIAL")
	)
	(segment
		(start 52.007008 -132.486908)
		(end 52.007008 -133.239764)
		(width 0.127)
		(layer "F.Cu")
		(net "IRQ_CPU_SERIAL")
	)
	(segment
		(start 51.689 -132.1689)
		(end 52.007008 -132.486908)
		(width 0.127)
		(layer "F.Cu")
		(net "IRQ_CPU_SERIAL")
	)
	(via
		(at 52.007008 -133.239764)
		(size 0.6604)
		(drill 0.3302)
		(layers "F.Cu" "B.Cu")
		(net "IRQ_CPU_SERIAL")
	)
	(via
		(at 92.1258 -170.6626)
		(size 0.6096)
		(drill 0.3048)
		(layers "F.Cu" "B.Cu")
		(net "UART_COMP_IN_RX_AND_R")
	)
	(segment
		(start 89.769696 -169.04716)
		(end 90.064336 -169.3418)
		(width 0.127)
		(layer "B.Cu")
		(net "UART_COMP_IN_RX_AND_R")
	)
	(segment
		(start 90.064336 -169.3418)
		(end 90.4748 -169.3418)
		(width 0.127)
		(layer "B.Cu")
		(net "UART_COMP_IN_RX_AND_R")
	)
	(segment
		(start 93.2307 -170.6626)
		(end 92.1258 -170.6626)
		(width 0.127)
		(layer "B.Cu")
		(net "UART_COMP_IN_RX_AND_R")
	)
	(segment
		(start 88.519 -169.04716)
		(end 89.769696 -169.04716)
		(width 0.127)
		(layer "B.Cu")
		(net "UART_COMP_IN_RX_AND_R")
	)
	(segment
		(start 91.7956 -170.6626)
		(end 92.1258 -170.6626)
		(width 0.127)
		(layer "B.Cu")
		(net "UART_COMP_IN_RX_AND_R")
	)
	(segment
		(start 90.4748 -169.3418)
		(end 91.7956 -170.6626)
		(width 0.127)
		(layer "B.Cu")
		(net "UART_COMP_IN_RX_AND_R")
	)
	(segment
		(start 94.35084 -127.204978)
		(end 94.631002 -127.48514)
		(width 0.127)
		(layer "F.Cu")
		(net "UART_COMP_IN_RX_AND")
	)
	(segment
		(start 94.66834 -127.48514)
		(end 94.9452 -127.762)
		(width 0.127)
		(layer "F.Cu")
		(net "UART_COMP_IN_RX_AND")
	)
	(segment
		(start 94.631002 -127.48514)
		(end 94.66834 -127.48514)
		(width 0.127)
		(layer "F.Cu")
		(net "UART_COMP_IN_RX_AND")
	)
	(segment
		(start 94.35084 -125.3617)
		(end 94.35084 -127.204978)
		(width 0.127)
		(layer "F.Cu")
		(net "UART_COMP_IN_RX_AND")
	)
	(via
		(at 96.16313 -168.89984)
		(size 0.508)
		(drill 0.254)
		(layers "F.Cu" "B.Cu")
		(net "UART_COMP_IN_RX_AND")
	)
	(via
		(at 94.9452 -127.762)
		(size 0.508)
		(drill 0.254)
		(layers "F.Cu" "B.Cu")
		(net "UART_COMP_IN_RX_AND")
	)
	(segment
		(start 94.982792 -170.6626)
		(end 94.1197 -170.6626)
		(width 0.127)
		(layer "B.Cu")
		(net "UART_COMP_IN_RX_AND")
	)
	(segment
		(start 96.16313 -168.89984)
		(end 96.16313 -169.482262)
		(width 0.127)
		(layer "B.Cu")
		(net "UART_COMP_IN_RX_AND")
	)
	(segment
		(start 96.16313 -169.482262)
		(end 94.982792 -170.6626)
		(width 0.127)
		(layer "B.Cu")
		(net "UART_COMP_IN_RX_AND")
	)
	(segment
		(start 95.661988 -141.496796)
		(end 95.540068 -141.618716)
		(width 0.127)
		(layer "In2.Cu")
		(net "UART_COMP_IN_RX_AND")
	)
	(segment
		(start 95.2119 -162.5473)
		(end 96.41713 -163.75253)
		(width 0.127)
		(layer "In2.Cu")
		(net "UART_COMP_IN_RX_AND")
	)
	(segment
		(start 95.2119 -160.882584)
		(end 95.2119 -162.5473)
		(width 0.127)
		(layer "In2.Cu")
		(net "UART_COMP_IN_RX_AND")
	)
	(segment
		(start 96.063308 -135.661654)
		(end 96.063308 -135.661908)
		(width 0.127)
		(layer "In2.Cu")
		(net "UART_COMP_IN_RX_AND")
	)
	(segment
		(start 96.4819 -159.612584)
		(end 95.2119 -160.882584)
		(width 0.127)
		(layer "In2.Cu")
		(net "UART_COMP_IN_RX_AND")
	)
	(segment
		(start 96.7486 -137.337292)
		(end 95.661988 -138.423904)
		(width 0.127)
		(layer "In2.Cu")
		(net "UART_COMP_IN_RX_AND")
	)
	(segment
		(start 95.181166 -127.997966)
		(end 95.181166 -130.564128)
		(width 0.127)
		(layer "In2.Cu")
		(net "UART_COMP_IN_RX_AND")
	)
	(segment
		(start 94.9452 -127.762)
		(end 95.181166 -127.997966)
		(width 0.127)
		(layer "In2.Cu")
		(net "UART_COMP_IN_RX_AND")
	)
	(segment
		(start 95.762064 -131.145026)
		(end 95.762064 -135.36041)
		(width 0.127)
		(layer "In2.Cu")
		(net "UART_COMP_IN_RX_AND")
	)
	(segment
		(start 96.7486 -136.3472)
		(end 96.7486 -137.337292)
		(width 0.127)
		(layer "In2.Cu")
		(net "UART_COMP_IN_RX_AND")
	)
	(segment
		(start 95.661988 -138.423904)
		(end 95.661988 -141.496796)
		(width 0.127)
		(layer "In2.Cu")
		(net "UART_COMP_IN_RX_AND")
	)
	(segment
		(start 95.540068 -141.618716)
		(end 95.540068 -149.55393)
		(width 0.127)
		(layer "In2.Cu")
		(net "UART_COMP_IN_RX_AND")
	)
	(segment
		(start 96.063308 -135.661908)
		(end 96.7486 -136.3472)
		(width 0.127)
		(layer "In2.Cu")
		(net "UART_COMP_IN_RX_AND")
	)
	(segment
		(start 96.41713 -168.64584)
		(end 96.16313 -168.89984)
		(width 0.127)
		(layer "In2.Cu")
		(net "UART_COMP_IN_RX_AND")
	)
	(segment
		(start 95.181166 -130.564128)
		(end 95.762064 -131.145026)
		(width 0.127)
		(layer "In2.Cu")
		(net "UART_COMP_IN_RX_AND")
	)
	(segment
		(start 95.540068 -149.55393)
		(end 96.4819 -150.495762)
		(width 0.127)
		(layer "In2.Cu")
		(net "UART_COMP_IN_RX_AND")
	)
	(segment
		(start 96.4819 -150.495762)
		(end 96.4819 -159.612584)
		(width 0.127)
		(layer "In2.Cu")
		(net "UART_COMP_IN_RX_AND")
	)
	(segment
		(start 96.41713 -163.75253)
		(end 96.41713 -168.64584)
		(width 0.127)
		(layer "In2.Cu")
		(net "UART_COMP_IN_RX_AND")
	)
	(segment
		(start 95.762064 -135.36041)
		(end 96.063308 -135.661654)
		(width 0.127)
		(layer "In2.Cu")
		(net "UART_COMP_IN_RX_AND")
	)
	(segment
		(start 92.813378 -123.473718)
		(end 91.534996 -123.473718)
		(width 0.127)
		(layer "F.Cu")
		(net "UART_COMP_IN_R_RX")
	)
	(segment
		(start 90.95232 -122.891042)
		(end 90.95232 -122.31878)
		(width 0.127)
		(layer "F.Cu")
		(net "UART_COMP_IN_R_RX")
	)
	(segment
		(start 93.05036 -123.7107)
		(end 92.813378 -123.473718)
		(width 0.127)
		(layer "F.Cu")
		(net "UART_COMP_IN_R_RX")
	)
	(segment
		(start 91.534996 -123.473718)
		(end 90.95232 -122.891042)
		(width 0.127)
		(layer "F.Cu")
		(net "UART_COMP_IN_R_RX")
	)
	(via
		(at 91.534996 -123.473718)
		(size 0.6604)
		(drill 0.3302)
		(layers "F.Cu" "B.Cu")
		(net "UART_COMP_IN_R_RX")
	)
	(segment
		(start 93.7006 -122.008392)
		(end 93.609922 -121.917714)
		(width 0.127)
		(layer "F.Cu")
		(net "UART_BMC_COMP_IN_RX_R")
	)
	(segment
		(start 92.342462 -121.846848)
		(end 93.539056 -121.846848)
		(width 0.127)
		(layer "F.Cu")
		(net "UART_BMC_COMP_IN_RX_R")
	)
	(segment
		(start 93.7006 -123.7107)
		(end 93.7006 -122.008392)
		(width 0.127)
		(layer "F.Cu")
		(net "UART_BMC_COMP_IN_RX_R")
	)
	(segment
		(start 93.539056 -121.846848)
		(end 93.609922 -121.917714)
		(width 0.127)
		(layer "F.Cu")
		(net "UART_BMC_COMP_IN_RX_R")
	)
	(via
		(at 93.609922 -121.917714)
		(size 0.6604)
		(drill 0.3302)
		(layers "F.Cu" "B.Cu")
		(net "UART_BMC_COMP_IN_RX_R")
	)
	(segment
		(start 39.1287 -160.232344)
		(end 39.3065 -160.054544)
		(width 0.127)
		(layer "F.Cu")
		(net "UART_BMC_COMP_IN_RX")
	)
	(segment
		(start 91.589352 -120.957848)
		(end 91.1352 -121.412)
		(width 0.127)
		(layer "F.Cu")
		(net "UART_BMC_COMP_IN_RX")
	)
	(segment
		(start 39.66464 -158.452058)
		(end 39.6748 -158.441898)
		(width 0.127)
		(layer "F.Cu")
		(net "UART_BMC_COMP_IN_RX")
	)
	(segment
		(start 38.6715 -160.9979)
		(end 38.5826 -160.9979)
		(width 0.127)
		(layer "F.Cu")
		(net "UART_BMC_COMP_IN_RX")
	)
	(segment
		(start 92.342462 -120.957848)
		(end 91.589352 -120.957848)
		(width 0.127)
		(layer "F.Cu")
		(net "UART_BMC_COMP_IN_RX")
	)
	(segment
		(start 39.6748 -157.655514)
		(end 40.360092 -156.970222)
		(width 0.127)
		(layer "F.Cu")
		(net "UART_BMC_COMP_IN_RX")
	)
	(segment
		(start 40.82288 -154.225498)
		(end 41.674542 -154.225498)
		(width 0.127)
		(layer "F.Cu")
		(net "UART_BMC_COMP_IN_RX")
	)
	(segment
		(start 40.360092 -156.970222)
		(end 40.360092 -156.969968)
		(width 0.127)
		(layer "F.Cu")
		(net "UART_BMC_COMP_IN_RX")
	)
	(segment
		(start 39.6748 -158.804102)
		(end 39.66464 -158.793942)
		(width 0.127)
		(layer "F.Cu")
		(net "UART_BMC_COMP_IN_RX")
	)
	(segment
		(start 39.3065 -160.054544)
		(end 39.3065 -159.71012)
		(width 0.127)
		(layer "F.Cu")
		(net "UART_BMC_COMP_IN_RX")
	)
	(segment
		(start 38.5826 -160.778698)
		(end 39.1287 -160.232598)
		(width 0.127)
		(layer "F.Cu")
		(net "UART_BMC_COMP_IN_RX")
	)
	(segment
		(start 39.242492 -162.306254)
		(end 39.242492 -161.568892)
		(width 0.127)
		(layer "F.Cu")
		(net "UART_BMC_COMP_IN_RX")
	)
	(segment
		(start 40.19042 -156.800296)
		(end 40.19042 -154.857958)
		(width 0.127)
		(layer "F.Cu")
		(net "UART_BMC_COMP_IN_RX")
	)
	(segment
		(start 38.5826 -160.9979)
		(end 38.5826 -160.778698)
		(width 0.127)
		(layer "F.Cu")
		(net "UART_BMC_COMP_IN_RX")
	)
	(segment
		(start 39.1414 -162.4076)
		(end 39.242492 -162.306254)
		(width 0.127)
		(layer "F.Cu")
		(net "UART_BMC_COMP_IN_RX")
	)
	(segment
		(start 40.19042 -154.857958)
		(end 40.82288 -154.225498)
		(width 0.127)
		(layer "F.Cu")
		(net "UART_BMC_COMP_IN_RX")
	)
	(segment
		(start 39.242492 -161.568892)
		(end 38.6715 -160.9979)
		(width 0.127)
		(layer "F.Cu")
		(net "UART_BMC_COMP_IN_RX")
	)
	(segment
		(start 39.1287 -160.232598)
		(end 39.1287 -160.232344)
		(width 0.127)
		(layer "F.Cu")
		(net "UART_BMC_COMP_IN_RX")
	)
	(segment
		(start 39.66464 -158.793942)
		(end 39.66464 -158.452058)
		(width 0.127)
		(layer "F.Cu")
		(net "UART_BMC_COMP_IN_RX")
	)
	(segment
		(start 39.6748 -159.34182)
		(end 39.6748 -158.804102)
		(width 0.127)
		(layer "F.Cu")
		(net "UART_BMC_COMP_IN_RX")
	)
	(segment
		(start 40.360092 -156.969968)
		(end 40.19042 -156.800296)
		(width 0.127)
		(layer "F.Cu")
		(net "UART_BMC_COMP_IN_RX")
	)
	(segment
		(start 39.6748 -158.441898)
		(end 39.6748 -157.655514)
		(width 0.127)
		(layer "F.Cu")
		(net "UART_BMC_COMP_IN_RX")
	)
	(segment
		(start 38.7858 -162.7632)
		(end 39.1414 -162.4076)
		(width 0.127)
		(layer "F.Cu")
		(net "UART_BMC_COMP_IN_RX")
	)
	(segment
		(start 39.3065 -159.71012)
		(end 39.6748 -159.34182)
		(width 0.127)
		(layer "F.Cu")
		(net "UART_BMC_COMP_IN_RX")
	)
	(segment
		(start 41.674542 -154.225498)
		(end 42.500042 -153.399998)
		(width 0.127)
		(layer "F.Cu")
		(net "UART_BMC_COMP_IN_RX")
	)
	(via
		(at 40.360092 -156.970222)
		(size 0.6604)
		(drill 0.3302)
		(layers "F.Cu" "B.Cu")
		(net "UART_BMC_COMP_IN_RX")
	)
	(via
		(at 38.7858 -162.7632)
		(size 0.508)
		(drill 0.254)
		(layers "F.Cu" "B.Cu")
		(net "UART_BMC_COMP_IN_RX")
	)
	(via
		(at 32.464248 -113.046764)
		(size 0.508)
		(drill 0.254)
		(layers "F.Cu" "B.Cu")
		(net "UART_BMC_COMP_IN_RX")
	)
	(via
		(at 91.1352 -121.412)
		(size 0.508)
		(drill 0.254)
		(layers "F.Cu" "B.Cu")
		(net "UART_BMC_COMP_IN_RX")
	)
	(segment
		(start 91.1352 -121.412)
		(end 86.4616 -121.412)
		(width 0.127)
		(layer "B.Cu")
		(net "UART_BMC_COMP_IN_RX")
	)
	(segment
		(start 53.359812 -113.046764)
		(end 32.464248 -113.046764)
		(width 0.127)
		(layer "B.Cu")
		(net "UART_BMC_COMP_IN_RX")
	)
	(segment
		(start 62.741048 -122.428)
		(end 53.359812 -113.046764)
		(width 0.127)
		(layer "B.Cu")
		(net "UART_BMC_COMP_IN_RX")
	)
	(segment
		(start 76.618084 -125.4506)
		(end 73.595484 -122.428)
		(width 0.127)
		(layer "B.Cu")
		(net "UART_BMC_COMP_IN_RX")
	)
	(segment
		(start 73.595484 -122.428)
		(end 62.741048 -122.428)
		(width 0.127)
		(layer "B.Cu")
		(net "UART_BMC_COMP_IN_RX")
	)
	(segment
		(start 82.423 -125.4506)
		(end 76.618084 -125.4506)
		(width 0.127)
		(layer "B.Cu")
		(net "UART_BMC_COMP_IN_RX")
	)
	(segment
		(start 86.4616 -121.412)
		(end 82.423 -125.4506)
		(width 0.127)
		(layer "B.Cu")
		(net "UART_BMC_COMP_IN_RX")
	)
	(segment
		(start 37.672518 -162.7632)
		(end 37.240718 -162.3314)
		(width 0.127)
		(layer "In5.Cu")
		(net "UART_BMC_COMP_IN_RX")
	)
	(segment
		(start 35.6489 -161.83864)
		(end 35.6489 -161.831782)
		(width 0.127)
		(layer "In5.Cu")
		(net "UART_BMC_COMP_IN_RX")
	)
	(segment
		(start 17.448022 -156.563822)
		(end 7.9375 -147.0533)
		(width 0.127)
		(layer "In5.Cu")
		(net "UART_BMC_COMP_IN_RX")
	)
	(segment
		(start 35.36696 -161.5567)
		(end 31.07436 -157.2641)
		(width 0.127)
		(layer "In5.Cu")
		(net "UART_BMC_COMP_IN_RX")
	)
	(segment
		(start 31.07436 -157.2641)
		(end 27.88666 -157.2641)
		(width 0.127)
		(layer "In5.Cu")
		(net "UART_BMC_COMP_IN_RX")
	)
	(segment
		(start 7.9375 -147.0533)
		(end 7.9375 -119.097806)
		(width 0.127)
		(layer "In5.Cu")
		(net "UART_BMC_COMP_IN_RX")
	)
	(segment
		(start 15.746984 -111.288322)
		(end 28.636722 -111.288322)
		(width 0.127)
		(layer "In5.Cu")
		(net "UART_BMC_COMP_IN_RX")
	)
	(segment
		(start 36.14166 -162.3314)
		(end 35.6489 -161.83864)
		(width 0.127)
		(layer "In5.Cu")
		(net "UART_BMC_COMP_IN_RX")
	)
	(segment
		(start 31.837884 -112.4204)
		(end 32.464248 -113.046764)
		(width 0.127)
		(layer "In5.Cu")
		(net "UART_BMC_COMP_IN_RX")
	)
	(segment
		(start 7.9375 -119.097806)
		(end 15.746984 -111.288322)
		(width 0.127)
		(layer "In5.Cu")
		(net "UART_BMC_COMP_IN_RX")
	)
	(segment
		(start 27.316938 -157.833822)
		(end 23.366222 -157.833822)
		(width 0.127)
		(layer "In5.Cu")
		(net "UART_BMC_COMP_IN_RX")
	)
	(segment
		(start 29.7688 -112.4204)
		(end 31.837884 -112.4204)
		(width 0.127)
		(layer "In5.Cu")
		(net "UART_BMC_COMP_IN_RX")
	)
	(segment
		(start 23.366222 -157.833822)
		(end 22.096222 -156.563822)
		(width 0.127)
		(layer "In5.Cu")
		(net "UART_BMC_COMP_IN_RX")
	)
	(segment
		(start 28.636722 -111.288322)
		(end 29.7688 -112.4204)
		(width 0.127)
		(layer "In5.Cu")
		(net "UART_BMC_COMP_IN_RX")
	)
	(segment
		(start 35.373818 -161.5567)
		(end 35.36696 -161.5567)
		(width 0.127)
		(layer "In5.Cu")
		(net "UART_BMC_COMP_IN_RX")
	)
	(segment
		(start 38.7858 -162.7632)
		(end 37.672518 -162.7632)
		(width 0.127)
		(layer "In5.Cu")
		(net "UART_BMC_COMP_IN_RX")
	)
	(segment
		(start 22.096222 -156.563822)
		(end 17.448022 -156.563822)
		(width 0.127)
		(layer "In5.Cu")
		(net "UART_BMC_COMP_IN_RX")
	)
	(segment
		(start 27.88666 -157.2641)
		(end 27.316938 -157.833822)
		(width 0.127)
		(layer "In5.Cu")
		(net "UART_BMC_COMP_IN_RX")
	)
	(segment
		(start 37.240718 -162.3314)
		(end 36.14166 -162.3314)
		(width 0.127)
		(layer "In5.Cu")
		(net "UART_BMC_COMP_IN_RX")
	)
	(segment
		(start 35.6489 -161.831782)
		(end 35.373818 -161.5567)
		(width 0.127)
		(layer "In5.Cu")
		(net "UART_BMC_COMP_IN_RX")
	)
	(segment
		(start 76.467716 -170.013884)
		(end 76.2254 -170.2562)
		(width 0.127)
		(layer "F.Cu")
		(net "P1V15_STBY_PG")
	)
	(segment
		(start 77.4954 -167.1447)
		(end 76.7969 -167.8432)
		(width 0.127)
		(layer "F.Cu")
		(net "P1V15_STBY_PG")
	)
	(segment
		(start 76.1746 -166.4335)
		(end 76.1746 -166.9542)
		(width 0.127)
		(layer "F.Cu")
		(net "P1V15_STBY_PG")
	)
	(segment
		(start 86.851236 -168.349676)
		(end 86.851236 -167.874442)
		(width 0.127)
		(layer "F.Cu")
		(net "P1V15_STBY_PG")
	)
	(segment
		(start 76.7969 -167.8432)
		(end 76.7969 -168.400984)
		(width 0.127)
		(layer "F.Cu")
		(net "P1V15_STBY_PG")
	)
	(segment
		(start 77.3049 -166.9542)
		(end 77.4954 -167.1447)
		(width 0.127)
		(layer "F.Cu")
		(net "P1V15_STBY_PG")
	)
	(segment
		(start 77.150214 -165.457886)
		(end 76.1746 -166.4335)
		(width 0.127)
		(layer "F.Cu")
		(net "P1V15_STBY_PG")
	)
	(segment
		(start 87.123524 -167.602154)
		(end 87.123524 -166.76497)
		(width 0.127)
		(layer "F.Cu")
		(net "P1V15_STBY_PG")
	)
	(segment
		(start 76.467716 -169.347896)
		(end 76.467716 -170.013884)
		(width 0.127)
		(layer "F.Cu")
		(net "P1V15_STBY_PG")
	)
	(segment
		(start 77.150214 -164.679122)
		(end 77.150214 -165.457886)
		(width 0.127)
		(layer "F.Cu")
		(net "P1V15_STBY_PG")
	)
	(segment
		(start 86.851236 -167.874442)
		(end 87.123524 -167.602154)
		(width 0.127)
		(layer "F.Cu")
		(net "P1V15_STBY_PG")
	)
	(segment
		(start 76.467716 -168.730168)
		(end 76.467716 -169.347896)
		(width 0.127)
		(layer "F.Cu")
		(net "P1V15_STBY_PG")
	)
	(segment
		(start 76.1746 -166.9542)
		(end 77.3049 -166.9542)
		(width 0.127)
		(layer "F.Cu")
		(net "P1V15_STBY_PG")
	)
	(segment
		(start 76.7969 -168.400984)
		(end 76.467716 -168.730168)
		(width 0.127)
		(layer "F.Cu")
		(net "P1V15_STBY_PG")
	)
	(via
		(at 76.467716 -169.347896)
		(size 0.6604)
		(drill 0.3302)
		(layers "F.Cu" "B.Cu")
		(net "P1V15_STBY_PG")
	)
	(via
		(at 86.851236 -168.349676)
		(size 0.508)
		(drill 0.254)
		(layers "F.Cu" "B.Cu")
		(net "P1V15_STBY_PG")
	)
	(via
		(at 76.2254 -170.2562)
		(size 0.508)
		(drill 0.254)
		(layers "F.Cu" "B.Cu")
		(net "P1V15_STBY_PG")
	)
	(segment
		(start 77.8764 -170.3832)
		(end 78.5749 -169.6847)
		(width 0.127)
		(layer "In5.Cu")
		(net "P1V15_STBY_PG")
	)
	(segment
		(start 78.5749 -169.6847)
		(end 84.150708 -169.6847)
		(width 0.127)
		(layer "In5.Cu")
		(net "P1V15_STBY_PG")
	)
	(segment
		(start 84.150708 -169.6847)
		(end 84.176108 -169.6593)
		(width 0.127)
		(layer "In5.Cu")
		(net "P1V15_STBY_PG")
	)
	(segment
		(start 76.3524 -170.3832)
		(end 77.8764 -170.3832)
		(width 0.127)
		(layer "In5.Cu")
		(net "P1V15_STBY_PG")
	)
	(segment
		(start 84.660486 -169.733214)
		(end 85.467698 -169.733214)
		(width 0.127)
		(layer "In5.Cu")
		(net "P1V15_STBY_PG")
	)
	(segment
		(start 76.2254 -170.2562)
		(end 76.3524 -170.3832)
		(width 0.127)
		(layer "In5.Cu")
		(net "P1V15_STBY_PG")
	)
	(segment
		(start 84.176108 -169.6593)
		(end 84.586572 -169.6593)
		(width 0.127)
		(layer "In5.Cu")
		(net "P1V15_STBY_PG")
	)
	(segment
		(start 84.586572 -169.6593)
		(end 84.660486 -169.733214)
		(width 0.127)
		(layer "In5.Cu")
		(net "P1V15_STBY_PG")
	)
	(segment
		(start 85.467698 -169.733214)
		(end 86.851236 -168.349676)
		(width 0.127)
		(layer "In5.Cu")
		(net "P1V15_STBY_PG")
	)
	(via
		(at 81.2673 -168.275)
		(size 0.6096)
		(drill 0.3048)
		(layers "F.Cu" "B.Cu")
		(net "UART_SDB_TX_R")
	)
	(segment
		(start 81.38922 -168.39692)
		(end 81.2673 -168.275)
		(width 0.127)
		(layer "B.Cu")
		(net "UART_SDB_TX_R")
	)
	(segment
		(start 81.2673 -168.275)
		(end 81.2673 -167.1574)
		(width 0.127)
		(layer "B.Cu")
		(net "UART_SDB_TX_R")
	)
	(segment
		(start 82.8802 -168.39692)
		(end 81.38922 -168.39692)
		(width 0.127)
		(layer "B.Cu")
		(net "UART_SDB_TX_R")
	)
	(segment
		(start 87.11057 -21.480018)
		(end 88.000078 -21.480018)
		(width 0.508)
		(layer "F.Cu")
		(net "P5V_VBUS_CONN")
	)
	(segment
		(start 88.000078 -21.480018)
		(end 88.000078 -22.369526)
		(width 0.508)
		(layer "F.Cu")
		(net "P5V_VBUS_CONN")
	)
	(segment
		(start 88.000078 -20.59051)
		(end 88.000078 -21.480018)
		(width 0.508)
		(layer "F.Cu")
		(net "P5V_VBUS_CONN")
	)
	(segment
		(start 88.000078 -21.480018)
		(end 88.889586 -21.480018)
		(width 0.508)
		(layer "F.Cu")
		(net "P5V_VBUS_CONN")
	)
	(segment
		(start 96.68764 -172.75556)
		(end 96.999552 -172.443648)
		(width 0.127)
		(layer "F.Cu")
		(net "I2C_DPB_MISC_SDA_R")
	)
	(segment
		(start 95.15094 -172.75556)
		(end 96.68764 -172.75556)
		(width 0.127)
		(layer "F.Cu")
		(net "I2C_DPB_MISC_SDA_R")
	)
	(segment
		(start 97.2566 -172.1866)
		(end 98.0821 -172.1866)
		(width 0.127)
		(layer "F.Cu")
		(net "I2C_DPB_MISC_SDA_R")
	)
	(segment
		(start 96.999552 -172.443648)
		(end 97.2566 -172.1866)
		(width 0.127)
		(layer "F.Cu")
		(net "I2C_DPB_MISC_SDA_R")
	)
	(via
		(at 96.999552 -172.443648)
		(size 0.6604)
		(drill 0.3302)
		(layers "F.Cu" "B.Cu")
		(net "I2C_DPB_MISC_SDA_R")
	)
	(segment
		(start 86.6267 -179.0573)
		(end 86.631018 -179.0573)
		(width 0.127)
		(layer "F.Cu")
		(net "I2C_DPB_MISC_SDA_OUT")
	)
	(segment
		(start 85.788246 -180.806598)
		(end 85.788246 -179.895754)
		(width 0.127)
		(layer "F.Cu")
		(net "I2C_DPB_MISC_SDA_OUT")
	)
	(segment
		(start 82.945986 -185.053986)
		(end 82.945986 -183.648858)
		(width 0.127)
		(layer "F.Cu")
		(net "I2C_DPB_MISC_SDA_OUT")
	)
	(segment
		(start 48.101504 -160.107884)
		(end 47.7266 -159.73298)
		(width 0.127)
		(layer "F.Cu")
		(net "I2C_DPB_MISC_SDA_OUT")
	)
	(segment
		(start 80.571594 -187.428378)
		(end 82.945986 -185.053986)
		(width 0.127)
		(layer "F.Cu")
		(net "I2C_DPB_MISC_SDA_OUT")
	)
	(segment
		(start 48.101504 -160.735772)
		(end 48.101504 -160.107884)
		(width 0.127)
		(layer "F.Cu")
		(net "I2C_DPB_MISC_SDA_OUT")
	)
	(segment
		(start 82.945986 -183.648858)
		(end 85.788246 -180.806598)
		(width 0.127)
		(layer "F.Cu")
		(net "I2C_DPB_MISC_SDA_OUT")
	)
	(segment
		(start 91.182444 -174.019972)
		(end 90.568272 -173.4058)
		(width 0.127)
		(layer "F.Cu")
		(net "I2C_DPB_MISC_SDA_OUT")
	)
	(segment
		(start 88.137746 -177.72634)
		(end 90.54592 -177.72634)
		(width 0.127)
		(layer "F.Cu")
		(net "I2C_DPB_MISC_SDA_OUT")
	)
	(segment
		(start 90.568272 -173.4058)
		(end 89.51214 -173.4058)
		(width 0.127)
		(layer "F.Cu")
		(net "I2C_DPB_MISC_SDA_OUT")
	)
	(segment
		(start 47.7266 -159.73298)
		(end 47.7266 -159.639)
		(width 0.127)
		(layer "F.Cu")
		(net "I2C_DPB_MISC_SDA_OUT")
	)
	(segment
		(start 79.7814 -187.7822)
		(end 80.135222 -187.428378)
		(width 0.127)
		(layer "F.Cu")
		(net "I2C_DPB_MISC_SDA_OUT")
	)
	(segment
		(start 91.182444 -177.089816)
		(end 91.182444 -174.019972)
		(width 0.127)
		(layer "F.Cu")
		(net "I2C_DPB_MISC_SDA_OUT")
	)
	(segment
		(start 87.95766 -177.726086)
		(end 88.137492 -177.726086)
		(width 0.127)
		(layer "F.Cu")
		(net "I2C_DPB_MISC_SDA_OUT")
	)
	(segment
		(start 86.9061 -178.782218)
		(end 86.9061 -178.777646)
		(width 0.127)
		(layer "F.Cu")
		(net "I2C_DPB_MISC_SDA_OUT")
	)
	(segment
		(start 47.7266 -159.447484)
		(end 48.05299 -159.121094)
		(width 0.127)
		(layer "F.Cu")
		(net "I2C_DPB_MISC_SDA_OUT")
	)
	(segment
		(start 88.137492 -177.726086)
		(end 88.137746 -177.72634)
		(width 0.127)
		(layer "F.Cu")
		(net "I2C_DPB_MISC_SDA_OUT")
	)
	(segment
		(start 90.54592 -177.72634)
		(end 91.182444 -177.089816)
		(width 0.127)
		(layer "F.Cu")
		(net "I2C_DPB_MISC_SDA_OUT")
	)
	(segment
		(start 47.7266 -159.639)
		(end 47.7266 -159.447484)
		(width 0.127)
		(layer "F.Cu")
		(net "I2C_DPB_MISC_SDA_OUT")
	)
	(segment
		(start 80.135222 -187.428378)
		(end 80.571594 -187.428378)
		(width 0.127)
		(layer "F.Cu")
		(net "I2C_DPB_MISC_SDA_OUT")
	)
	(segment
		(start 48.05299 -159.121094)
		(end 48.05299 -158.6357)
		(width 0.127)
		(layer "F.Cu")
		(net "I2C_DPB_MISC_SDA_OUT")
	)
	(segment
		(start 85.788246 -179.895754)
		(end 86.6267 -179.0573)
		(width 0.127)
		(layer "F.Cu")
		(net "I2C_DPB_MISC_SDA_OUT")
	)
	(segment
		(start 86.9061 -178.777646)
		(end 87.95766 -177.726086)
		(width 0.127)
		(layer "F.Cu")
		(net "I2C_DPB_MISC_SDA_OUT")
	)
	(segment
		(start 86.631018 -179.0573)
		(end 86.9061 -178.782218)
		(width 0.127)
		(layer "F.Cu")
		(net "I2C_DPB_MISC_SDA_OUT")
	)
	(via
		(at 46.9392 -180.1622)
		(size 0.508)
		(drill 0.254)
		(layers "F.Cu" "B.Cu")
		(net "I2C_DPB_MISC_SDA_OUT")
	)
	(via
		(at 79.7814 -187.7822)
		(size 0.508)
		(drill 0.254)
		(layers "F.Cu" "B.Cu")
		(net "I2C_DPB_MISC_SDA_OUT")
	)
	(via
		(at 47.7266 -159.639)
		(size 0.508)
		(drill 0.254)
		(layers "F.Cu" "B.Cu")
		(net "I2C_DPB_MISC_SDA_OUT")
	)
	(segment
		(start 45.4787 -178.9557)
		(end 46.6852 -180.1622)
		(width 0.127)
		(layer "In2.Cu")
		(net "I2C_DPB_MISC_SDA_OUT")
	)
	(segment
		(start 46.511718 -162.581082)
		(end 46.511718 -162.809682)
		(width 0.127)
		(layer "In2.Cu")
		(net "I2C_DPB_MISC_SDA_OUT")
	)
	(segment
		(start 47.7266 -161.3662)
		(end 46.511718 -162.581082)
		(width 0.127)
		(layer "In2.Cu")
		(net "I2C_DPB_MISC_SDA_OUT")
	)
	(segment
		(start 45.4787 -163.8427)
		(end 45.4787 -178.9557)
		(width 0.127)
		(layer "In2.Cu")
		(net "I2C_DPB_MISC_SDA_OUT")
	)
	(segment
		(start 47.7266 -159.639)
		(end 47.7266 -161.3662)
		(width 0.127)
		(layer "In2.Cu")
		(net "I2C_DPB_MISC_SDA_OUT")
	)
	(segment
		(start 46.511718 -162.809682)
		(end 45.4787 -163.8427)
		(width 0.127)
		(layer "In2.Cu")
		(net "I2C_DPB_MISC_SDA_OUT")
	)
	(segment
		(start 46.6852 -180.1622)
		(end 46.9392 -180.1622)
		(width 0.127)
		(layer "In2.Cu")
		(net "I2C_DPB_MISC_SDA_OUT")
	)
	(segment
		(start 68.344034 -189.3316)
		(end 73.946766 -189.3316)
		(width 0.127)
		(layer "In5.Cu")
		(net "I2C_DPB_MISC_SDA_OUT")
	)
	(segment
		(start 56.901334 -178.4223)
		(end 60.165234 -181.6862)
		(width 0.127)
		(layer "In5.Cu")
		(net "I2C_DPB_MISC_SDA_OUT")
	)
	(segment
		(start 79.5782 -187.579)
		(end 79.7814 -187.7822)
		(width 0.127)
		(layer "In5.Cu")
		(net "I2C_DPB_MISC_SDA_OUT")
	)
	(segment
		(start 60.165234 -181.6862)
		(end 63.187834 -181.6862)
		(width 0.127)
		(layer "In5.Cu")
		(net "I2C_DPB_MISC_SDA_OUT")
	)
	(segment
		(start 73.946766 -189.3316)
		(end 75.699366 -187.579)
		(width 0.127)
		(layer "In5.Cu")
		(net "I2C_DPB_MISC_SDA_OUT")
	)
	(segment
		(start 65.6082 -186.595766)
		(end 68.344034 -189.3316)
		(width 0.127)
		(layer "In5.Cu")
		(net "I2C_DPB_MISC_SDA_OUT")
	)
	(segment
		(start 63.187834 -181.6862)
		(end 65.6082 -184.106566)
		(width 0.127)
		(layer "In5.Cu")
		(net "I2C_DPB_MISC_SDA_OUT")
	)
	(segment
		(start 75.699366 -187.579)
		(end 79.5782 -187.579)
		(width 0.127)
		(layer "In5.Cu")
		(net "I2C_DPB_MISC_SDA_OUT")
	)
	(segment
		(start 46.9392 -180.1622)
		(end 48.6791 -178.4223)
		(width 0.127)
		(layer "In5.Cu")
		(net "I2C_DPB_MISC_SDA_OUT")
	)
	(segment
		(start 65.6082 -184.106566)
		(end 65.6082 -186.595766)
		(width 0.127)
		(layer "In5.Cu")
		(net "I2C_DPB_MISC_SDA_OUT")
	)
	(segment
		(start 48.6791 -178.4223)
		(end 56.901334 -178.4223)
		(width 0.127)
		(layer "In5.Cu")
		(net "I2C_DPB_MISC_SDA_OUT")
	)
	(segment
		(start 97.16262 -173.4058)
		(end 97.50679 -173.74997)
		(width 0.127)
		(layer "F.Cu")
		(net "I2C_DPB_MISC_SCL_R")
	)
	(segment
		(start 98.70567 -173.899576)
		(end 97.656396 -173.899576)
		(width 0.127)
		(layer "F.Cu")
		(net "I2C_DPB_MISC_SCL_R")
	)
	(segment
		(start 95.15094 -173.4058)
		(end 97.16262 -173.4058)
		(width 0.127)
		(layer "F.Cu")
		(net "I2C_DPB_MISC_SCL_R")
	)
	(segment
		(start 97.656396 -173.899576)
		(end 97.50679 -173.74997)
		(width 0.127)
		(layer "F.Cu")
		(net "I2C_DPB_MISC_SCL_R")
	)
	(via
		(at 97.50679 -173.74997)
		(size 0.6604)
		(drill 0.3302)
		(layers "F.Cu" "B.Cu")
		(net "I2C_DPB_MISC_SCL_R")
	)
	(segment
		(start 85.9663 -178.392582)
		(end 85.9663 -178.6001)
		(width 0.127)
		(layer "F.Cu")
		(net "I2C_DPB_MISC_SCL_OUT")
	)
	(segment
		(start 86.241382 -178.1175)
		(end 85.9663 -178.392582)
		(width 0.127)
		(layer "F.Cu")
		(net "I2C_DPB_MISC_SCL_OUT")
	)
	(segment
		(start 49.142904 -160.735772)
		(end 49.01184 -160.604708)
		(width 0.127)
		(layer "F.Cu")
		(net "I2C_DPB_MISC_SCL_OUT")
	)
	(segment
		(start 49.01184 -159.64154)
		(end 49.01184 -159.62376)
		(width 0.127)
		(layer "F.Cu")
		(net "I2C_DPB_MISC_SCL_OUT")
	)
	(segment
		(start 90.224864 -177.193194)
		(end 88.173306 -177.193194)
		(width 0.127)
		(layer "F.Cu")
		(net "I2C_DPB_MISC_SCL_OUT")
	)
	(segment
		(start 49.01184 -159.62376)
		(end 49.09439 -159.54121)
		(width 0.127)
		(layer "F.Cu")
		(net "I2C_DPB_MISC_SCL_OUT")
	)
	(segment
		(start 85.280246 -180.596032)
		(end 82.437986 -183.438292)
		(width 0.127)
		(layer "F.Cu")
		(net "I2C_DPB_MISC_SCL_OUT")
	)
	(segment
		(start 85.280246 -179.286408)
		(end 85.280246 -180.596032)
		(width 0.127)
		(layer "F.Cu")
		(net "I2C_DPB_MISC_SCL_OUT")
	)
	(segment
		(start 49.09439 -159.54121)
		(end 49.09439 -158.6357)
		(width 0.127)
		(layer "F.Cu")
		(net "I2C_DPB_MISC_SCL_OUT")
	)
	(segment
		(start 89.51214 -174.05604)
		(end 90.364056 -174.05604)
		(width 0.127)
		(layer "F.Cu")
		(net "I2C_DPB_MISC_SCL_OUT")
	)
	(segment
		(start 90.578432 -176.839626)
		(end 90.224864 -177.193194)
		(width 0.127)
		(layer "F.Cu")
		(net "I2C_DPB_MISC_SCL_OUT")
	)
	(segment
		(start 82.437986 -184.84342)
		(end 80.361028 -186.920378)
		(width 0.127)
		(layer "F.Cu")
		(net "I2C_DPB_MISC_SCL_OUT")
	)
	(segment
		(start 86.84768 -178.1175)
		(end 86.241382 -178.1175)
		(width 0.127)
		(layer "F.Cu")
		(net "I2C_DPB_MISC_SCL_OUT")
	)
	(segment
		(start 49.01184 -160.604708)
		(end 49.01184 -159.64154)
		(width 0.127)
		(layer "F.Cu")
		(net "I2C_DPB_MISC_SCL_OUT")
	)
	(segment
		(start 88.148414 -177.218086)
		(end 87.747094 -177.218086)
		(width 0.127)
		(layer "F.Cu")
		(net "I2C_DPB_MISC_SCL_OUT")
	)
	(segment
		(start 88.173306 -177.193194)
		(end 88.148414 -177.218086)
		(width 0.127)
		(layer "F.Cu")
		(net "I2C_DPB_MISC_SCL_OUT")
	)
	(segment
		(start 85.9663 -178.6001)
		(end 85.280246 -179.286408)
		(width 0.127)
		(layer "F.Cu")
		(net "I2C_DPB_MISC_SCL_OUT")
	)
	(segment
		(start 90.364056 -174.05604)
		(end 90.578432 -174.270416)
		(width 0.127)
		(layer "F.Cu")
		(net "I2C_DPB_MISC_SCL_OUT")
	)
	(segment
		(start 90.578432 -174.270416)
		(end 90.578432 -176.839626)
		(width 0.127)
		(layer "F.Cu")
		(net "I2C_DPB_MISC_SCL_OUT")
	)
	(segment
		(start 82.437986 -183.438292)
		(end 82.437986 -184.84342)
		(width 0.127)
		(layer "F.Cu")
		(net "I2C_DPB_MISC_SCL_OUT")
	)
	(segment
		(start 87.747094 -177.218086)
		(end 86.84768 -178.1175)
		(width 0.127)
		(layer "F.Cu")
		(net "I2C_DPB_MISC_SCL_OUT")
	)
	(segment
		(start 80.361028 -186.920378)
		(end 79.723742 -186.920378)
		(width 0.127)
		(layer "F.Cu")
		(net "I2C_DPB_MISC_SCL_OUT")
	)
	(via
		(at 47.0154 -179.2224)
		(size 0.508)
		(drill 0.254)
		(layers "F.Cu" "B.Cu")
		(net "I2C_DPB_MISC_SCL_OUT")
	)
	(via
		(at 79.723742 -186.920378)
		(size 0.508)
		(drill 0.254)
		(layers "F.Cu" "B.Cu")
		(net "I2C_DPB_MISC_SCL_OUT")
	)
	(via
		(at 49.01184 -159.64154)
		(size 0.508)
		(drill 0.254)
		(layers "F.Cu" "B.Cu")
		(net "I2C_DPB_MISC_SCL_OUT")
	)
	(segment
		(start 49.01184 -159.64154)
		(end 48.641 -160.01238)
		(width 0.127)
		(layer "In2.Cu")
		(net "I2C_DPB_MISC_SCL_OUT")
	)
	(segment
		(start 46.5201 -178.7271)
		(end 47.0154 -179.2224)
		(width 0.127)
		(layer "In2.Cu")
		(net "I2C_DPB_MISC_SCL_OUT")
	)
	(segment
		(start 48.641 -161.311082)
		(end 47.6504 -162.301682)
		(width 0.127)
		(layer "In2.Cu")
		(net "I2C_DPB_MISC_SCL_OUT")
	)
	(segment
		(start 47.6504 -163.6522)
		(end 46.5201 -164.7825)
		(width 0.127)
		(layer "In2.Cu")
		(net "I2C_DPB_MISC_SCL_OUT")
	)
	(segment
		(start 48.641 -160.01238)
		(end 48.641 -161.311082)
		(width 0.127)
		(layer "In2.Cu")
		(net "I2C_DPB_MISC_SCL_OUT")
	)
	(segment
		(start 47.6504 -162.301682)
		(end 47.6504 -163.6522)
		(width 0.127)
		(layer "In2.Cu")
		(net "I2C_DPB_MISC_SCL_OUT")
	)
	(segment
		(start 46.5201 -164.7825)
		(end 46.5201 -178.7271)
		(width 0.127)
		(layer "In2.Cu")
		(net "I2C_DPB_MISC_SCL_OUT")
	)
	(segment
		(start 57.1119 -177.9143)
		(end 60.3758 -181.1782)
		(width 0.127)
		(layer "In5.Cu")
		(net "I2C_DPB_MISC_SCL_OUT")
	)
	(segment
		(start 48.3235 -177.9143)
		(end 57.1119 -177.9143)
		(width 0.127)
		(layer "In5.Cu")
		(net "I2C_DPB_MISC_SCL_OUT")
	)
	(segment
		(start 47.0154 -179.2224)
		(end 48.3235 -177.9143)
		(width 0.127)
		(layer "In5.Cu")
		(net "I2C_DPB_MISC_SCL_OUT")
	)
	(segment
		(start 63.3984 -181.1782)
		(end 66.1162 -183.896)
		(width 0.127)
		(layer "In5.Cu")
		(net "I2C_DPB_MISC_SCL_OUT")
	)
	(segment
		(start 68.5546 -188.8236)
		(end 73.7362 -188.8236)
		(width 0.127)
		(layer "In5.Cu")
		(net "I2C_DPB_MISC_SCL_OUT")
	)
	(segment
		(start 66.1162 -183.896)
		(end 66.1162 -186.3852)
		(width 0.127)
		(layer "In5.Cu")
		(net "I2C_DPB_MISC_SCL_OUT")
	)
	(segment
		(start 73.7362 -188.8236)
		(end 75.4888 -187.071)
		(width 0.127)
		(layer "In5.Cu")
		(net "I2C_DPB_MISC_SCL_OUT")
	)
	(segment
		(start 60.3758 -181.1782)
		(end 63.3984 -181.1782)
		(width 0.127)
		(layer "In5.Cu")
		(net "I2C_DPB_MISC_SCL_OUT")
	)
	(segment
		(start 79.57312 -187.071)
		(end 79.723742 -186.920378)
		(width 0.127)
		(layer "In5.Cu")
		(net "I2C_DPB_MISC_SCL_OUT")
	)
	(segment
		(start 75.4888 -187.071)
		(end 79.57312 -187.071)
		(width 0.127)
		(layer "In5.Cu")
		(net "I2C_DPB_MISC_SCL_OUT")
	)
	(segment
		(start 66.1162 -186.3852)
		(end 68.5546 -188.8236)
		(width 0.127)
		(layer "In5.Cu")
		(net "I2C_DPB_MISC_SCL_OUT")
	)
	(segment
		(start 29.5402 -156.718)
		(end 29.5656 -156.6926)
		(width 0.127)
		(layer "F.Cu")
		(net "FLA0_WP_N_R")
	)
	(segment
		(start 28.6385 -156.718)
		(end 29.5402 -156.718)
		(width 0.127)
		(layer "F.Cu")
		(net "FLA0_WP_N_R")
	)
	(segment
		(start 42.500042 -150.199852)
		(end 42.099992 -150.599902)
		(width 0.127)
		(layer "F.Cu")
		(net "FLA0_WP_N_R")
	)
	(via
		(at 29.5656 -156.6926)
		(size 0.508)
		(drill 0.254)
		(layers "F.Cu" "B.Cu")
		(net "FLA0_WP_N_R")
	)
	(via
		(at 42.099992 -150.599902)
		(size 0.4572)
		(drill 0.2032)
		(layers "F.Cu" "B.Cu")
		(net "FLA0_WP_N_R")
	)
	(segment
		(start 32.138366 -157.861)
		(end 30.734 -157.861)
		(width 0.127)
		(layer "In2.Cu")
		(net "FLA0_WP_N_R")
	)
	(segment
		(start 30.734 -157.861)
		(end 29.5656 -156.6926)
		(width 0.127)
		(layer "In2.Cu")
		(net "FLA0_WP_N_R")
	)
	(segment
		(start 42.099992 -150.599902)
		(end 42.061638 -150.599902)
		(width 0.127)
		(layer "In2.Cu")
		(net "FLA0_WP_N_R")
	)
	(segment
		(start 40.650414 -151.806402)
		(end 40.33647 -151.806402)
		(width 0.127)
		(layer "In2.Cu")
		(net "FLA0_WP_N_R")
	)
	(segment
		(start 39.2938 -154.7749)
		(end 36.94684 -157.12186)
		(width 0.127)
		(layer "In2.Cu")
		(net "FLA0_WP_N_R")
	)
	(segment
		(start 41.655238 -151.006302)
		(end 41.13657 -151.006302)
		(width 0.127)
		(layer "In2.Cu")
		(net "FLA0_WP_N_R")
	)
	(segment
		(start 40.03802 -153.719022)
		(end 39.2938 -154.463242)
		(width 0.127)
		(layer "In2.Cu")
		(net "FLA0_WP_N_R")
	)
	(segment
		(start 36.94684 -157.12186)
		(end 32.877506 -157.12186)
		(width 0.127)
		(layer "In2.Cu")
		(net "FLA0_WP_N_R")
	)
	(segment
		(start 40.03802 -152.1206)
		(end 40.03802 -153.719022)
		(width 0.127)
		(layer "In2.Cu")
		(net "FLA0_WP_N_R")
	)
	(segment
		(start 40.33647 -151.806402)
		(end 40.106092 -152.03678)
		(width 0.127)
		(layer "In2.Cu")
		(net "FLA0_WP_N_R")
	)
	(segment
		(start 40.893492 -151.563324)
		(end 40.650414 -151.806402)
		(width 0.127)
		(layer "In2.Cu")
		(net "FLA0_WP_N_R")
	)
	(segment
		(start 32.877506 -157.12186)
		(end 32.138366 -157.861)
		(width 0.127)
		(layer "In2.Cu")
		(net "FLA0_WP_N_R")
	)
	(segment
		(start 40.106092 -152.03678)
		(end 40.106092 -152.052528)
		(width 0.127)
		(layer "In2.Cu")
		(net "FLA0_WP_N_R")
	)
	(segment
		(start 40.893492 -151.24938)
		(end 40.893492 -151.563324)
		(width 0.127)
		(layer "In2.Cu")
		(net "FLA0_WP_N_R")
	)
	(segment
		(start 41.13657 -151.006302)
		(end 40.893492 -151.24938)
		(width 0.127)
		(layer "In2.Cu")
		(net "FLA0_WP_N_R")
	)
	(segment
		(start 39.2938 -154.463242)
		(end 39.2938 -154.7749)
		(width 0.127)
		(layer "In2.Cu")
		(net "FLA0_WP_N_R")
	)
	(segment
		(start 40.106092 -152.052528)
		(end 40.03802 -152.1206)
		(width 0.127)
		(layer "In2.Cu")
		(net "FLA0_WP_N_R")
	)
	(segment
		(start 42.061638 -150.599902)
		(end 41.655238 -151.006302)
		(width 0.127)
		(layer "In2.Cu")
		(net "FLA0_WP_N_R")
	)
	(segment
		(start 28.7655 -157.734)
		(end 28.7655 -158.674054)
		(width 0.127)
		(layer "F.Cu")
		(net "DEBUG_GPIO_BMC_R_6")
	)
	(segment
		(start 29.211524 -158.940754)
		(end 29.591 -158.561278)
		(width 0.127)
		(layer "F.Cu")
		(net "DEBUG_GPIO_BMC_R_6")
	)
	(segment
		(start 28.7655 -158.674054)
		(end 29.0322 -158.940754)
		(width 0.127)
		(layer "F.Cu")
		(net "DEBUG_GPIO_BMC_R_6")
	)
	(segment
		(start 42.500042 -150.999952)
		(end 42.099992 -151.400002)
		(width 0.127)
		(layer "F.Cu")
		(net "DEBUG_GPIO_BMC_R_6")
	)
	(segment
		(start 29.0322 -158.940754)
		(end 29.211524 -158.940754)
		(width 0.127)
		(layer "F.Cu")
		(net "DEBUG_GPIO_BMC_R_6")
	)
	(segment
		(start 29.591 -158.561278)
		(end 29.591 -157.734)
		(width 0.127)
		(layer "F.Cu")
		(net "DEBUG_GPIO_BMC_R_6")
	)
	(via
		(at 29.211524 -158.940754)
		(size 0.6604)
		(drill 0.3302)
		(layers "F.Cu" "B.Cu")
		(net "DEBUG_GPIO_BMC_R_6")
	)
	(via
		(at 29.591 -157.734)
		(size 0.508)
		(drill 0.254)
		(layers "F.Cu" "B.Cu")
		(net "DEBUG_GPIO_BMC_R_6")
	)
	(via
		(at 42.099992 -151.400002)
		(size 0.4572)
		(drill 0.2032)
		(layers "F.Cu" "B.Cu")
		(net "DEBUG_GPIO_BMC_R_6")
	)
	(segment
		(start 41.497758 -151.806402)
		(end 41.12387 -151.806402)
		(width 0.127)
		(layer "In2.Cu")
		(net "DEBUG_GPIO_BMC_R_6")
	)
	(segment
		(start 37.1475 -158.0769)
		(end 35.53714 -158.0769)
		(width 0.127)
		(layer "In2.Cu")
		(net "DEBUG_GPIO_BMC_R_6")
	)
	(segment
		(start 40.893492 -152.03678)
		(end 40.893492 -152.363424)
		(width 0.127)
		(layer "In2.Cu")
		(net "DEBUG_GPIO_BMC_R_6")
	)
	(segment
		(start 30.226 -158.369)
		(end 29.591 -157.734)
		(width 0.127)
		(layer "In2.Cu")
		(net "DEBUG_GPIO_BMC_R_6")
	)
	(segment
		(start 40.623236 -153.457148)
		(end 39.5224 -154.557984)
		(width 0.127)
		(layer "In2.Cu")
		(net "DEBUG_GPIO_BMC_R_6")
	)
	(segment
		(start 41.726358 -151.577802)
		(end 41.497758 -151.806402)
		(width 0.127)
		(layer "In2.Cu")
		(net "DEBUG_GPIO_BMC_R_6")
	)
	(segment
		(start 32.06623 -158.687262)
		(end 31.747968 -158.369)
		(width 0.127)
		(layer "In2.Cu")
		(net "DEBUG_GPIO_BMC_R_6")
	)
	(segment
		(start 40.623236 -152.63368)
		(end 40.623236 -153.457148)
		(width 0.127)
		(layer "In2.Cu")
		(net "DEBUG_GPIO_BMC_R_6")
	)
	(segment
		(start 41.12387 -151.806402)
		(end 40.893492 -152.03678)
		(width 0.127)
		(layer "In2.Cu")
		(net "DEBUG_GPIO_BMC_R_6")
	)
	(segment
		(start 42.099992 -151.400002)
		(end 41.922192 -151.577802)
		(width 0.127)
		(layer "In2.Cu")
		(net "DEBUG_GPIO_BMC_R_6")
	)
	(segment
		(start 31.747968 -158.369)
		(end 30.226 -158.369)
		(width 0.127)
		(layer "In2.Cu")
		(net "DEBUG_GPIO_BMC_R_6")
	)
	(segment
		(start 39.5224 -154.557984)
		(end 39.5224 -155.702)
		(width 0.127)
		(layer "In2.Cu")
		(net "DEBUG_GPIO_BMC_R_6")
	)
	(segment
		(start 39.5224 -155.702)
		(end 37.1475 -158.0769)
		(width 0.127)
		(layer "In2.Cu")
		(net "DEBUG_GPIO_BMC_R_6")
	)
	(segment
		(start 35.53714 -158.0769)
		(end 34.926778 -158.687262)
		(width 0.127)
		(layer "In2.Cu")
		(net "DEBUG_GPIO_BMC_R_6")
	)
	(segment
		(start 34.926778 -158.687262)
		(end 32.06623 -158.687262)
		(width 0.127)
		(layer "In2.Cu")
		(net "DEBUG_GPIO_BMC_R_6")
	)
	(segment
		(start 40.893492 -152.363424)
		(end 40.623236 -152.63368)
		(width 0.127)
		(layer "In2.Cu")
		(net "DEBUG_GPIO_BMC_R_6")
	)
	(segment
		(start 41.922192 -151.577802)
		(end 41.726358 -151.577802)
		(width 0.127)
		(layer "In2.Cu")
		(net "DEBUG_GPIO_BMC_R_6")
	)
	(segment
		(start 28.6385 -155.702)
		(end 29.0195 -156.083)
		(width 0.127)
		(layer "F.Cu")
		(net "DEBUG_GPIO_BMC_R_5")
	)
	(segment
		(start 30.226 -156.083)
		(end 30.3276 -155.9814)
		(width 0.127)
		(layer "F.Cu")
		(net "DEBUG_GPIO_BMC_R_5")
	)
	(segment
		(start 42.500042 -149.400006)
		(end 42.099992 -149.800056)
		(width 0.127)
		(layer "F.Cu")
		(net "DEBUG_GPIO_BMC_R_5")
	)
	(segment
		(start 29.0195 -156.083)
		(end 30.226 -156.083)
		(width 0.127)
		(layer "F.Cu")
		(net "DEBUG_GPIO_BMC_R_5")
	)
	(via
		(at 42.099992 -149.800056)
		(size 0.4572)
		(drill 0.2032)
		(layers "F.Cu" "B.Cu")
		(net "DEBUG_GPIO_BMC_R_5")
	)
	(via
		(at 30.3276 -155.9814)
		(size 0.508)
		(drill 0.254)
		(layers "F.Cu" "B.Cu")
		(net "DEBUG_GPIO_BMC_R_5")
	)
	(segment
		(start 41.149016 -150.193756)
		(end 40.894 -150.448772)
		(width 0.127)
		(layer "In2.Cu")
		(net "DEBUG_GPIO_BMC_R_5")
	)
	(segment
		(start 41.856914 -149.800056)
		(end 41.463214 -150.193756)
		(width 0.127)
		(layer "In2.Cu")
		(net "DEBUG_GPIO_BMC_R_5")
	)
	(segment
		(start 40.894 -150.75408)
		(end 40.893492 -150.754588)
		(width 0.127)
		(layer "In2.Cu")
		(net "DEBUG_GPIO_BMC_R_5")
	)
	(segment
		(start 39.56304 -153.68016)
		(end 39.293546 -153.949654)
		(width 0.127)
		(layer "In2.Cu")
		(net "DEBUG_GPIO_BMC_R_5")
	)
	(segment
		(start 42.099992 -149.800056)
		(end 41.856914 -149.800056)
		(width 0.127)
		(layer "In2.Cu")
		(net "DEBUG_GPIO_BMC_R_5")
	)
	(segment
		(start 39.049198 -154.194002)
		(end 36.62934 -156.61386)
		(width 0.127)
		(layer "In2.Cu")
		(net "DEBUG_GPIO_BMC_R_5")
	)
	(segment
		(start 36.62934 -156.61386)
		(end 32.66694 -156.61386)
		(width 0.127)
		(layer "In2.Cu")
		(net "DEBUG_GPIO_BMC_R_5")
	)
	(segment
		(start 31.95066 -157.33014)
		(end 30.99054 -157.33014)
		(width 0.127)
		(layer "In2.Cu")
		(net "DEBUG_GPIO_BMC_R_5")
	)
	(segment
		(start 39.809166 -152.333452)
		(end 39.56304 -152.579832)
		(width 0.127)
		(layer "In2.Cu")
		(net "DEBUG_GPIO_BMC_R_5")
	)
	(segment
		(start 41.463214 -150.193756)
		(end 41.149016 -150.193756)
		(width 0.127)
		(layer "In2.Cu")
		(net "DEBUG_GPIO_BMC_R_5")
	)
	(segment
		(start 39.809166 -152.010364)
		(end 39.809166 -152.333452)
		(width 0.127)
		(layer "In2.Cu")
		(net "DEBUG_GPIO_BMC_R_5")
	)
	(segment
		(start 32.66694 -156.61386)
		(end 31.95066 -157.33014)
		(width 0.127)
		(layer "In2.Cu")
		(net "DEBUG_GPIO_BMC_R_5")
	)
	(segment
		(start 30.3276 -156.6672)
		(end 30.3276 -155.9814)
		(width 0.127)
		(layer "In2.Cu")
		(net "DEBUG_GPIO_BMC_R_5")
	)
	(segment
		(start 40.084756 -151.734774)
		(end 39.809166 -152.010364)
		(width 0.127)
		(layer "In2.Cu")
		(net "DEBUG_GPIO_BMC_R_5")
	)
	(segment
		(start 40.894 -150.448772)
		(end 40.894 -150.75408)
		(width 0.127)
		(layer "In2.Cu")
		(net "DEBUG_GPIO_BMC_R_5")
	)
	(segment
		(start 30.99054 -157.33014)
		(end 30.3276 -156.6672)
		(width 0.127)
		(layer "In2.Cu")
		(net "DEBUG_GPIO_BMC_R_5")
	)
	(segment
		(start 40.347392 -150.99538)
		(end 40.084756 -151.258016)
		(width 0.127)
		(layer "In2.Cu")
		(net "DEBUG_GPIO_BMC_R_5")
	)
	(segment
		(start 39.293546 -153.949654)
		(end 39.293546 -153.963624)
		(width 0.127)
		(layer "In2.Cu")
		(net "DEBUG_GPIO_BMC_R_5")
	)
	(segment
		(start 40.661336 -150.99538)
		(end 40.347392 -150.99538)
		(width 0.127)
		(layer "In2.Cu")
		(net "DEBUG_GPIO_BMC_R_5")
	)
	(segment
		(start 40.893492 -150.763224)
		(end 40.661336 -150.99538)
		(width 0.127)
		(layer "In2.Cu")
		(net "DEBUG_GPIO_BMC_R_5")
	)
	(segment
		(start 39.56304 -152.579832)
		(end 39.56304 -153.68016)
		(width 0.127)
		(layer "In2.Cu")
		(net "DEBUG_GPIO_BMC_R_5")
	)
	(segment
		(start 40.893492 -150.754588)
		(end 40.893492 -150.763224)
		(width 0.127)
		(layer "In2.Cu")
		(net "DEBUG_GPIO_BMC_R_5")
	)
	(segment
		(start 40.084756 -151.258016)
		(end 40.084756 -151.734774)
		(width 0.127)
		(layer "In2.Cu")
		(net "DEBUG_GPIO_BMC_R_5")
	)
	(segment
		(start 39.063168 -154.194002)
		(end 39.049198 -154.194002)
		(width 0.127)
		(layer "In2.Cu")
		(net "DEBUG_GPIO_BMC_R_5")
	)
	(segment
		(start 39.293546 -153.963624)
		(end 39.063168 -154.194002)
		(width 0.127)
		(layer "In2.Cu")
		(net "DEBUG_GPIO_BMC_R_5")
	)
	(segment
		(start 41.699942 -149.400006)
		(end 41.299892 -149.800056)
		(width 0.127)
		(layer "F.Cu")
		(net "DEBUG_GPIO_BMC_R_4")
	)
	(segment
		(start 29.469842 -154.205686)
		(end 28.934156 -153.67)
		(width 0.127)
		(layer "F.Cu")
		(net "DEBUG_GPIO_BMC_R_4")
	)
	(segment
		(start 28.934156 -153.67)
		(end 28.6385 -153.67)
		(width 0.127)
		(layer "F.Cu")
		(net "DEBUG_GPIO_BMC_R_4")
	)
	(segment
		(start 29.469842 -154.285442)
		(end 29.469842 -154.205686)
		(width 0.127)
		(layer "F.Cu")
		(net "DEBUG_GPIO_BMC_R_4")
	)
	(via
		(at 29.469842 -154.285442)
		(size 0.508)
		(drill 0.254)
		(layers "F.Cu" "B.Cu")
		(net "DEBUG_GPIO_BMC_R_4")
	)
	(via
		(at 41.299892 -149.800056)
		(size 0.4572)
		(drill 0.2032)
		(layers "F.Cu" "B.Cu")
		(net "DEBUG_GPIO_BMC_R_4")
	)
	(segment
		(start 39.56812 -151.604726)
		(end 39.56812 -150.974552)
		(width 0.127)
		(layer "In2.Cu")
		(net "DEBUG_GPIO_BMC_R_4")
	)
	(segment
		(start 40.674798 -150.206202)
		(end 41.080944 -149.800056)
		(width 0.127)
		(layer "In2.Cu")
		(net "DEBUG_GPIO_BMC_R_4")
	)
	(segment
		(start 39.56812 -150.974552)
		(end 40.33647 -150.206202)
		(width 0.127)
		(layer "In2.Cu")
		(net "DEBUG_GPIO_BMC_R_4")
	)
	(segment
		(start 39.351966 -152.021794)
		(end 39.351966 -151.82088)
		(width 0.127)
		(layer "In2.Cu")
		(net "DEBUG_GPIO_BMC_R_4")
	)
	(segment
		(start 29.596842 -154.4955)
		(end 29.867606 -154.4955)
		(width 0.127)
		(layer "In2.Cu")
		(net "DEBUG_GPIO_BMC_R_4")
	)
	(segment
		(start 32.144462 -154.64536)
		(end 32.154622 -154.65552)
		(width 0.127)
		(layer "In2.Cu")
		(net "DEBUG_GPIO_BMC_R_4")
	)
	(segment
		(start 29.469842 -154.285442)
		(end 29.469842 -154.3685)
		(width 0.127)
		(layer "In2.Cu")
		(net "DEBUG_GPIO_BMC_R_4")
	)
	(segment
		(start 41.080944 -149.800056)
		(end 41.299892 -149.800056)
		(width 0.127)
		(layer "In2.Cu")
		(net "DEBUG_GPIO_BMC_R_4")
	)
	(segment
		(start 32.154622 -154.65552)
		(end 36.71824 -154.65552)
		(width 0.127)
		(layer "In2.Cu")
		(net "DEBUG_GPIO_BMC_R_4")
	)
	(segment
		(start 30.017466 -154.64536)
		(end 32.144462 -154.64536)
		(width 0.127)
		(layer "In2.Cu")
		(net "DEBUG_GPIO_BMC_R_4")
	)
	(segment
		(start 40.33647 -150.206202)
		(end 40.674798 -150.206202)
		(width 0.127)
		(layer "In2.Cu")
		(net "DEBUG_GPIO_BMC_R_4")
	)
	(segment
		(start 36.71824 -154.65552)
		(end 39.351966 -152.021794)
		(width 0.127)
		(layer "In2.Cu")
		(net "DEBUG_GPIO_BMC_R_4")
	)
	(segment
		(start 39.351966 -151.82088)
		(end 39.56812 -151.604726)
		(width 0.127)
		(layer "In2.Cu")
		(net "DEBUG_GPIO_BMC_R_4")
	)
	(segment
		(start 29.867606 -154.4955)
		(end 30.017466 -154.64536)
		(width 0.127)
		(layer "In2.Cu")
		(net "DEBUG_GPIO_BMC_R_4")
	)
	(segment
		(start 29.469842 -154.3685)
		(end 29.596842 -154.4955)
		(width 0.127)
		(layer "In2.Cu")
		(net "DEBUG_GPIO_BMC_R_4")
	)
	(segment
		(start 40.899842 -150.199852)
		(end 40.499792 -150.599902)
		(width 0.127)
		(layer "F.Cu")
		(net "DEBUG_GPIO_BMC_R_3")
	)
	(segment
		(start 29.5148 -155.3464)
		(end 29.4386 -155.3464)
		(width 0.127)
		(layer "F.Cu")
		(net "DEBUG_GPIO_BMC_R_3")
	)
	(segment
		(start 28.7782 -154.686)
		(end 28.6385 -154.686)
		(width 0.127)
		(layer "F.Cu")
		(net "DEBUG_GPIO_BMC_R_3")
	)
	(segment
		(start 29.4386 -155.3464)
		(end 28.7782 -154.686)
		(width 0.127)
		(layer "F.Cu")
		(net "DEBUG_GPIO_BMC_R_3")
	)
	(via
		(at 29.5148 -155.3464)
		(size 0.508)
		(drill 0.254)
		(layers "F.Cu" "B.Cu")
		(net "DEBUG_GPIO_BMC_R_3")
	)
	(via
		(at 40.499792 -150.599902)
		(size 0.4572)
		(drill 0.2032)
		(layers "F.Cu" "B.Cu")
		(net "DEBUG_GPIO_BMC_R_3")
	)
	(segment
		(start 39.796974 -151.222456)
		(end 39.796974 -151.699214)
		(width 0.127)
		(layer "In2.Cu")
		(net "DEBUG_GPIO_BMC_R_3")
	)
	(segment
		(start 29.64053 -155.3464)
		(end 29.5148 -155.3464)
		(width 0.127)
		(layer "In2.Cu")
		(net "DEBUG_GPIO_BMC_R_3")
	)
	(segment
		(start 39.580566 -151.915622)
		(end 39.580566 -152.116536)
		(width 0.127)
		(layer "In2.Cu")
		(net "DEBUG_GPIO_BMC_R_3")
	)
	(segment
		(start 30.46349 -155.452572)
		(end 29.746702 -155.452572)
		(width 0.127)
		(layer "In2.Cu")
		(net "DEBUG_GPIO_BMC_R_3")
	)
	(segment
		(start 36.0299 -156.1973)
		(end 31.174182 -156.1973)
		(width 0.127)
		(layer "In2.Cu")
		(net "DEBUG_GPIO_BMC_R_3")
	)
	(segment
		(start 30.7975 -155.820618)
		(end 30.7975 -155.786582)
		(width 0.127)
		(layer "In2.Cu")
		(net "DEBUG_GPIO_BMC_R_3")
	)
	(segment
		(start 40.252904 -150.766526)
		(end 39.796974 -151.222456)
		(width 0.127)
		(layer "In2.Cu")
		(net "DEBUG_GPIO_BMC_R_3")
	)
	(segment
		(start 38.18001 -153.517092)
		(end 38.18001 -154.04719)
		(width 0.127)
		(layer "In2.Cu")
		(net "DEBUG_GPIO_BMC_R_3")
	)
	(segment
		(start 30.7975 -155.786582)
		(end 30.46349 -155.452572)
		(width 0.127)
		(layer "In2.Cu")
		(net "DEBUG_GPIO_BMC_R_3")
	)
	(segment
		(start 38.18001 -154.04719)
		(end 36.0299 -156.1973)
		(width 0.127)
		(layer "In2.Cu")
		(net "DEBUG_GPIO_BMC_R_3")
	)
	(segment
		(start 39.796974 -151.699214)
		(end 39.580566 -151.915622)
		(width 0.127)
		(layer "In2.Cu")
		(net "DEBUG_GPIO_BMC_R_3")
	)
	(segment
		(start 39.580566 -152.116536)
		(end 38.18001 -153.517092)
		(width 0.127)
		(layer "In2.Cu")
		(net "DEBUG_GPIO_BMC_R_3")
	)
	(segment
		(start 40.333168 -150.766526)
		(end 40.252904 -150.766526)
		(width 0.127)
		(layer "In2.Cu")
		(net "DEBUG_GPIO_BMC_R_3")
	)
	(segment
		(start 29.746702 -155.452572)
		(end 29.64053 -155.3464)
		(width 0.127)
		(layer "In2.Cu")
		(net "DEBUG_GPIO_BMC_R_3")
	)
	(segment
		(start 31.174182 -156.1973)
		(end 30.7975 -155.820618)
		(width 0.127)
		(layer "In2.Cu")
		(net "DEBUG_GPIO_BMC_R_3")
	)
	(segment
		(start 40.499792 -150.599902)
		(end 40.333168 -150.766526)
		(width 0.127)
		(layer "In2.Cu")
		(net "DEBUG_GPIO_BMC_R_3")
	)
	(segment
		(start 40.899842 -149.400006)
		(end 40.499792 -149.800056)
		(width 0.127)
		(layer "F.Cu")
		(net "DEBUG_GPIO_BMC_R_2")
	)
	(segment
		(start 29.7307 -152.8699)
		(end 29.9974 -152.6032)
		(width 0.127)
		(layer "F.Cu")
		(net "DEBUG_GPIO_BMC_R_2")
	)
	(segment
		(start 29.6545 -151.638)
		(end 29.718 -151.638)
		(width 0.127)
		(layer "F.Cu")
		(net "DEBUG_GPIO_BMC_R_2")
	)
	(segment
		(start 29.9974 -151.9174)
		(end 29.718 -151.638)
		(width 0.127)
		(layer "F.Cu")
		(net "DEBUG_GPIO_BMC_R_2")
	)
	(segment
		(start 29.9974 -152.6032)
		(end 29.9974 -151.9174)
		(width 0.127)
		(layer "F.Cu")
		(net "DEBUG_GPIO_BMC_R_2")
	)
	(segment
		(start 29.7307 -152.908)
		(end 29.7307 -152.8699)
		(width 0.127)
		(layer "F.Cu")
		(net "DEBUG_GPIO_BMC_R_2")
	)
	(segment
		(start 28.6385 -152.654)
		(end 29.6545 -151.638)
		(width 0.127)
		(layer "F.Cu")
		(net "DEBUG_GPIO_BMC_R_2")
	)
	(via
		(at 29.718 -151.638)
		(size 0.6604)
		(drill 0.3302)
		(layers "F.Cu" "B.Cu")
		(net "DEBUG_GPIO_BMC_R_2")
	)
	(via
		(at 29.7307 -152.908)
		(size 0.508)
		(drill 0.254)
		(layers "F.Cu" "B.Cu")
		(net "DEBUG_GPIO_BMC_R_2")
	)
	(via
		(at 40.499792 -149.800056)
		(size 0.4572)
		(drill 0.2032)
		(layers "F.Cu" "B.Cu")
		(net "DEBUG_GPIO_BMC_R_2")
	)
	(segment
		(start 37.264848 -153.035)
		(end 40.499792 -149.800056)
		(width 0.127)
		(layer "In5.Cu")
		(net "DEBUG_GPIO_BMC_R_2")
	)
	(segment
		(start 29.7307 -152.908)
		(end 29.8577 -153.035)
		(width 0.127)
		(layer "In5.Cu")
		(net "DEBUG_GPIO_BMC_R_2")
	)
	(segment
		(start 29.8577 -153.035)
		(end 37.264848 -153.035)
		(width 0.127)
		(layer "In5.Cu")
		(net "DEBUG_GPIO_BMC_R_2")
	)
	(segment
		(start 33.172146 -150.992586)
		(end 33.1724 -150.992332)
		(width 0.127)
		(layer "F.Cu")
		(net "DEBUG_GPIO_BMC_R_1")
	)
	(segment
		(start 28.6385 -151.638)
		(end 29.2608 -151.0157)
		(width 0.127)
		(layer "F.Cu")
		(net "DEBUG_GPIO_BMC_R_1")
	)
	(segment
		(start 31.377636 -150.810722)
		(end 31.5595 -150.992586)
		(width 0.127)
		(layer "F.Cu")
		(net "DEBUG_GPIO_BMC_R_1")
	)
	(segment
		(start 29.2608 -151.0157)
		(end 31.172658 -151.0157)
		(width 0.127)
		(layer "F.Cu")
		(net "DEBUG_GPIO_BMC_R_1")
	)
	(segment
		(start 31.5595 -150.992586)
		(end 33.172146 -150.992586)
		(width 0.127)
		(layer "F.Cu")
		(net "DEBUG_GPIO_BMC_R_1")
	)
	(segment
		(start 37.443664 -150.4569)
		(end 38.817042 -150.4569)
		(width 0.127)
		(layer "F.Cu")
		(net "DEBUG_GPIO_BMC_R_1")
	)
	(segment
		(start 38.817042 -150.4569)
		(end 39.07409 -150.199852)
		(width 0.127)
		(layer "F.Cu")
		(net "DEBUG_GPIO_BMC_R_1")
	)
	(segment
		(start 39.07409 -150.199852)
		(end 39.299896 -150.199852)
		(width 0.127)
		(layer "F.Cu")
		(net "DEBUG_GPIO_BMC_R_1")
	)
	(segment
		(start 36.908232 -150.992332)
		(end 37.443664 -150.4569)
		(width 0.127)
		(layer "F.Cu")
		(net "DEBUG_GPIO_BMC_R_1")
	)
	(segment
		(start 31.172658 -151.0157)
		(end 31.377636 -150.810722)
		(width 0.127)
		(layer "F.Cu")
		(net "DEBUG_GPIO_BMC_R_1")
	)
	(segment
		(start 33.1724 -150.992332)
		(end 36.908232 -150.992332)
		(width 0.127)
		(layer "F.Cu")
		(net "DEBUG_GPIO_BMC_R_1")
	)
	(via
		(at 31.377636 -150.810722)
		(size 0.6604)
		(drill 0.3302)
		(layers "F.Cu" "B.Cu")
		(net "DEBUG_GPIO_BMC_R_1")
	)
	(segment
		(start 97.10166 -142.978886)
		(end 95.996506 -142.978886)
		(width 0.127)
		(layer "F.Cu")
		(net "DEBUG_GPIO_BMC_6")
	)
	(segment
		(start 26.797 -157.734)
		(end 27.8765 -157.734)
		(width 0.127)
		(layer "F.Cu")
		(net "DEBUG_GPIO_BMC_6")
	)
	(segment
		(start 97.296224 -143.17345)
		(end 97.10166 -142.978886)
		(width 0.127)
		(layer "F.Cu")
		(net "DEBUG_GPIO_BMC_6")
	)
	(segment
		(start 26.543 -157.48)
		(end 26.797 -157.734)
		(width 0.127)
		(layer "F.Cu")
		(net "DEBUG_GPIO_BMC_6")
	)
	(segment
		(start 26.543 -157.1752)
		(end 26.543 -157.48)
		(width 0.127)
		(layer "F.Cu")
		(net "DEBUG_GPIO_BMC_6")
	)
	(via
		(at 97.296224 -143.17345)
		(size 0.508)
		(drill 0.254)
		(layers "F.Cu" "B.Cu")
		(net "DEBUG_GPIO_BMC_6")
	)
	(via
		(at 34.549334 -114.654076)
		(size 0.508)
		(drill 0.254)
		(layers "F.Cu" "B.Cu")
		(net "DEBUG_GPIO_BMC_6")
	)
	(via
		(at 26.543 -157.1752)
		(size 0.508)
		(drill 0.254)
		(layers "F.Cu" "B.Cu")
		(net "DEBUG_GPIO_BMC_6")
	)
	(segment
		(start 35.78733 -114.964718)
		(end 34.859976 -114.964718)
		(width 0.127)
		(layer "B.Cu")
		(net "DEBUG_GPIO_BMC_6")
	)
	(segment
		(start 96.3295 -142.91945)
		(end 96.3295 -137.933176)
		(width 0.127)
		(layer "B.Cu")
		(net "DEBUG_GPIO_BMC_6")
	)
	(segment
		(start 96.900492 -137.362184)
		(end 96.900492 -131.958842)
		(width 0.127)
		(layer "B.Cu")
		(net "DEBUG_GPIO_BMC_6")
	)
	(segment
		(start 83.00212 -126.8476)
		(end 76.038964 -126.8476)
		(width 0.127)
		(layer "B.Cu")
		(net "DEBUG_GPIO_BMC_6")
	)
	(segment
		(start 36.260024 -114.492024)
		(end 35.78733 -114.964718)
		(width 0.127)
		(layer "B.Cu")
		(net "DEBUG_GPIO_BMC_6")
	)
	(segment
		(start 97.296224 -143.17345)
		(end 96.5835 -143.17345)
		(width 0.127)
		(layer "B.Cu")
		(net "DEBUG_GPIO_BMC_6")
	)
	(segment
		(start 96.3295 -137.933176)
		(end 96.900492 -137.362184)
		(width 0.127)
		(layer "B.Cu")
		(net "DEBUG_GPIO_BMC_6")
	)
	(segment
		(start 97.048828 -127.737616)
		(end 93.669612 -124.3584)
		(width 0.127)
		(layer "B.Cu")
		(net "DEBUG_GPIO_BMC_6")
	)
	(segment
		(start 96.900492 -131.958842)
		(end 97.672398 -131.186936)
		(width 0.127)
		(layer "B.Cu")
		(net "DEBUG_GPIO_BMC_6")
	)
	(segment
		(start 85.49132 -124.3584)
		(end 83.00212 -126.8476)
		(width 0.127)
		(layer "B.Cu")
		(net "DEBUG_GPIO_BMC_6")
	)
	(segment
		(start 76.038964 -126.8476)
		(end 73.143364 -123.952)
		(width 0.127)
		(layer "B.Cu")
		(net "DEBUG_GPIO_BMC_6")
	)
	(segment
		(start 34.859976 -114.964718)
		(end 34.549334 -114.654076)
		(width 0.127)
		(layer "B.Cu")
		(net "DEBUG_GPIO_BMC_6")
	)
	(segment
		(start 52.794408 -114.492024)
		(end 36.260024 -114.492024)
		(width 0.127)
		(layer "B.Cu")
		(net "DEBUG_GPIO_BMC_6")
	)
	(segment
		(start 97.672398 -130.137916)
		(end 97.048828 -129.514346)
		(width 0.127)
		(layer "B.Cu")
		(net "DEBUG_GPIO_BMC_6")
	)
	(segment
		(start 62.254384 -123.952)
		(end 52.794408 -114.492024)
		(width 0.127)
		(layer "B.Cu")
		(net "DEBUG_GPIO_BMC_6")
	)
	(segment
		(start 97.048828 -129.514346)
		(end 97.048828 -127.737616)
		(width 0.127)
		(layer "B.Cu")
		(net "DEBUG_GPIO_BMC_6")
	)
	(segment
		(start 97.672398 -131.186936)
		(end 97.672398 -130.137916)
		(width 0.127)
		(layer "B.Cu")
		(net "DEBUG_GPIO_BMC_6")
	)
	(segment
		(start 96.5835 -143.17345)
		(end 96.3295 -142.91945)
		(width 0.127)
		(layer "B.Cu")
		(net "DEBUG_GPIO_BMC_6")
	)
	(segment
		(start 93.669612 -124.3584)
		(end 85.49132 -124.3584)
		(width 0.127)
		(layer "B.Cu")
		(net "DEBUG_GPIO_BMC_6")
	)
	(segment
		(start 73.143364 -123.952)
		(end 62.254384 -123.952)
		(width 0.127)
		(layer "B.Cu")
		(net "DEBUG_GPIO_BMC_6")
	)
	(segment
		(start 9.099804 -130.733292)
		(end 9.099804 -118.833646)
		(width 0.127)
		(layer "In5.Cu")
		(net "DEBUG_GPIO_BMC_6")
	)
	(segment
		(start 25.296622 -155.928822)
		(end 17.874234 -155.928822)
		(width 0.127)
		(layer "In5.Cu")
		(net "DEBUG_GPIO_BMC_6")
	)
	(segment
		(start 10.1346 -148.189188)
		(end 10.1346 -131.768088)
		(width 0.127)
		(layer "In5.Cu")
		(net "DEBUG_GPIO_BMC_6")
	)
	(segment
		(start 16.010128 -111.923322)
		(end 28.335478 -111.923322)
		(width 0.127)
		(layer "In5.Cu")
		(net "DEBUG_GPIO_BMC_6")
	)
	(segment
		(start 33.569148 -113.67389)
		(end 34.549334 -114.654076)
		(width 0.127)
		(layer "In5.Cu")
		(net "DEBUG_GPIO_BMC_6")
	)
	(segment
		(start 17.874234 -155.928822)
		(end 10.1346 -148.189188)
		(width 0.127)
		(layer "In5.Cu")
		(net "DEBUG_GPIO_BMC_6")
	)
	(segment
		(start 28.335478 -111.923322)
		(end 29.467556 -113.0554)
		(width 0.127)
		(layer "In5.Cu")
		(net "DEBUG_GPIO_BMC_6")
	)
	(segment
		(start 29.467556 -113.0554)
		(end 31.258256 -113.0554)
		(width 0.127)
		(layer "In5.Cu")
		(net "DEBUG_GPIO_BMC_6")
	)
	(segment
		(start 10.1346 -131.768088)
		(end 9.099804 -130.733292)
		(width 0.127)
		(layer "In5.Cu")
		(net "DEBUG_GPIO_BMC_6")
	)
	(segment
		(start 9.099804 -118.833646)
		(end 16.010128 -111.923322)
		(width 0.127)
		(layer "In5.Cu")
		(net "DEBUG_GPIO_BMC_6")
	)
	(segment
		(start 31.258256 -113.0554)
		(end 31.876746 -113.67389)
		(width 0.127)
		(layer "In5.Cu")
		(net "DEBUG_GPIO_BMC_6")
	)
	(segment
		(start 26.543 -157.1752)
		(end 25.296622 -155.928822)
		(width 0.127)
		(layer "In5.Cu")
		(net "DEBUG_GPIO_BMC_6")
	)
	(segment
		(start 31.876746 -113.67389)
		(end 33.569148 -113.67389)
		(width 0.127)
		(layer "In5.Cu")
		(net "DEBUG_GPIO_BMC_6")
	)
	(segment
		(start 97.7773 -141.348714)
		(end 96.797368 -142.328646)
		(width 0.127)
		(layer "F.Cu")
		(net "DEBUG_GPIO_BMC_5")
	)
	(segment
		(start 96.797368 -142.328646)
		(end 95.996506 -142.328646)
		(width 0.127)
		(layer "F.Cu")
		(net "DEBUG_GPIO_BMC_5")
	)
	(segment
		(start 26.8224 -155.702)
		(end 27.7495 -155.702)
		(width 0.127)
		(layer "F.Cu")
		(net "DEBUG_GPIO_BMC_5")
	)
	(segment
		(start 97.7773 -141.040104)
		(end 97.7773 -141.348714)
		(width 0.127)
		(layer "F.Cu")
		(net "DEBUG_GPIO_BMC_5")
	)
	(segment
		(start 26.5684 -155.956)
		(end 26.8224 -155.702)
		(width 0.127)
		(layer "F.Cu")
		(net "DEBUG_GPIO_BMC_5")
	)
	(via
		(at 97.7773 -141.040104)
		(size 0.508)
		(drill 0.254)
		(layers "F.Cu" "B.Cu")
		(net "DEBUG_GPIO_BMC_5")
	)
	(via
		(at 33.555686 -114.604546)
		(size 0.508)
		(drill 0.254)
		(layers "F.Cu" "B.Cu")
		(net "DEBUG_GPIO_BMC_5")
	)
	(via
		(at 26.5684 -155.956)
		(size 0.508)
		(drill 0.254)
		(layers "F.Cu" "B.Cu")
		(net "DEBUG_GPIO_BMC_5")
	)
	(segment
		(start 93.8276 -123.9774)
		(end 85.333332 -123.9774)
		(width 0.127)
		(layer "B.Cu")
		(net "DEBUG_GPIO_BMC_5")
	)
	(segment
		(start 97.429828 -126.060708)
		(end 96.12122 -124.7521)
		(width 0.127)
		(layer "B.Cu")
		(net "DEBUG_GPIO_BMC_5")
	)
	(segment
		(start 34.088832 -114.0714)
		(end 33.555686 -114.604546)
		(width 0.127)
		(layer "B.Cu")
		(net "DEBUG_GPIO_BMC_5")
	)
	(segment
		(start 96.7105 -140.12418)
		(end 96.7105 -138.091164)
		(width 0.127)
		(layer "B.Cu")
		(net "DEBUG_GPIO_BMC_5")
	)
	(segment
		(start 98.053398 -131.42722)
		(end 98.053398 -129.979928)
		(width 0.127)
		(layer "B.Cu")
		(net "DEBUG_GPIO_BMC_5")
	)
	(segment
		(start 96.12122 -124.7521)
		(end 94.6023 -124.7521)
		(width 0.127)
		(layer "B.Cu")
		(net "DEBUG_GPIO_BMC_5")
	)
	(segment
		(start 97.281492 -132.199126)
		(end 98.053398 -131.42722)
		(width 0.127)
		(layer "B.Cu")
		(net "DEBUG_GPIO_BMC_5")
	)
	(segment
		(start 52.912772 -114.0714)
		(end 34.088832 -114.0714)
		(width 0.127)
		(layer "B.Cu")
		(net "DEBUG_GPIO_BMC_5")
	)
	(segment
		(start 97.7773 -141.040104)
		(end 97.626424 -141.040104)
		(width 0.127)
		(layer "B.Cu")
		(net "DEBUG_GPIO_BMC_5")
	)
	(segment
		(start 94.6023 -124.7521)
		(end 93.8276 -123.9774)
		(width 0.127)
		(layer "B.Cu")
		(net "DEBUG_GPIO_BMC_5")
	)
	(segment
		(start 85.333332 -123.9774)
		(end 82.844132 -126.4666)
		(width 0.127)
		(layer "B.Cu")
		(net "DEBUG_GPIO_BMC_5")
	)
	(segment
		(start 98.053398 -129.979928)
		(end 97.429828 -129.356358)
		(width 0.127)
		(layer "B.Cu")
		(net "DEBUG_GPIO_BMC_5")
	)
	(segment
		(start 62.412372 -123.571)
		(end 52.912772 -114.0714)
		(width 0.127)
		(layer "B.Cu")
		(net "DEBUG_GPIO_BMC_5")
	)
	(segment
		(start 96.7105 -138.091164)
		(end 97.281492 -137.520172)
		(width 0.127)
		(layer "B.Cu")
		(net "DEBUG_GPIO_BMC_5")
	)
	(segment
		(start 76.196952 -126.4666)
		(end 73.301352 -123.571)
		(width 0.127)
		(layer "B.Cu")
		(net "DEBUG_GPIO_BMC_5")
	)
	(segment
		(start 82.844132 -126.4666)
		(end 76.196952 -126.4666)
		(width 0.127)
		(layer "B.Cu")
		(net "DEBUG_GPIO_BMC_5")
	)
	(segment
		(start 73.301352 -123.571)
		(end 62.412372 -123.571)
		(width 0.127)
		(layer "B.Cu")
		(net "DEBUG_GPIO_BMC_5")
	)
	(segment
		(start 97.281492 -137.520172)
		(end 97.281492 -132.199126)
		(width 0.127)
		(layer "B.Cu")
		(net "DEBUG_GPIO_BMC_5")
	)
	(segment
		(start 97.626424 -141.040104)
		(end 96.7105 -140.12418)
		(width 0.127)
		(layer "B.Cu")
		(net "DEBUG_GPIO_BMC_5")
	)
	(segment
		(start 97.429828 -129.356358)
		(end 97.429828 -126.060708)
		(width 0.127)
		(layer "B.Cu")
		(net "DEBUG_GPIO_BMC_5")
	)
	(segment
		(start 9.480804 -118.991634)
		(end 16.168116 -112.304322)
		(width 0.127)
		(layer "In5.Cu")
		(net "DEBUG_GPIO_BMC_5")
	)
	(segment
		(start 31.100268 -113.4364)
		(end 31.718758 -114.05489)
		(width 0.127)
		(layer "In5.Cu")
		(net "DEBUG_GPIO_BMC_5")
	)
	(segment
		(start 9.480804 -130.575304)
		(end 9.480804 -118.991634)
		(width 0.127)
		(layer "In5.Cu")
		(net "DEBUG_GPIO_BMC_5")
	)
	(segment
		(start 29.309568 -113.4364)
		(end 31.100268 -113.4364)
		(width 0.127)
		(layer "In5.Cu")
		(net "DEBUG_GPIO_BMC_5")
	)
	(segment
		(start 26.160222 -155.547822)
		(end 18.032222 -155.547822)
		(width 0.127)
		(layer "In5.Cu")
		(net "DEBUG_GPIO_BMC_5")
	)
	(segment
		(start 31.718758 -114.05489)
		(end 33.00603 -114.05489)
		(width 0.127)
		(layer "In5.Cu")
		(net "DEBUG_GPIO_BMC_5")
	)
	(segment
		(start 11.2903 -148.8059)
		(end 11.2903 -132.3848)
		(width 0.127)
		(layer "In5.Cu")
		(net "DEBUG_GPIO_BMC_5")
	)
	(segment
		(start 11.2903 -132.3848)
		(end 9.480804 -130.575304)
		(width 0.127)
		(layer "In5.Cu")
		(net "DEBUG_GPIO_BMC_5")
	)
	(segment
		(start 26.5684 -155.956)
		(end 26.160222 -155.547822)
		(width 0.127)
		(layer "In5.Cu")
		(net "DEBUG_GPIO_BMC_5")
	)
	(segment
		(start 33.00603 -114.05489)
		(end 33.555686 -114.604546)
		(width 0.127)
		(layer "In5.Cu")
		(net "DEBUG_GPIO_BMC_5")
	)
	(segment
		(start 18.032222 -155.547822)
		(end 11.2903 -148.8059)
		(width 0.127)
		(layer "In5.Cu")
		(net "DEBUG_GPIO_BMC_5")
	)
	(segment
		(start 16.168116 -112.304322)
		(end 28.17749 -112.304322)
		(width 0.127)
		(layer "In5.Cu")
		(net "DEBUG_GPIO_BMC_5")
	)
	(segment
		(start 28.17749 -112.304322)
		(end 29.309568 -113.4364)
		(width 0.127)
		(layer "In5.Cu")
		(net "DEBUG_GPIO_BMC_5")
	)
	(segment
		(start 97.10039 -140.853414)
		(end 97.10039 -141.416278)
		(width 0.127)
		(layer "F.Cu")
		(net "DEBUG_GPIO_BMC_4")
	)
	(segment
		(start 97.10039 -141.416278)
		(end 96.838262 -141.678406)
		(width 0.127)
		(layer "F.Cu")
		(net "DEBUG_GPIO_BMC_4")
	)
	(segment
		(start 27.7495 -153.67)
		(end 27.051 -153.67)
		(width 0.127)
		(layer "F.Cu")
		(net "DEBUG_GPIO_BMC_4")
	)
	(segment
		(start 97.7773 -140.176504)
		(end 97.10039 -140.853414)
		(width 0.127)
		(layer "F.Cu")
		(net "DEBUG_GPIO_BMC_4")
	)
	(segment
		(start 96.838262 -141.678406)
		(end 95.996506 -141.678406)
		(width 0.127)
		(layer "F.Cu")
		(net "DEBUG_GPIO_BMC_4")
	)
	(segment
		(start 27.051 -153.67)
		(end 26.8224 -153.8986)
		(width 0.127)
		(layer "F.Cu")
		(net "DEBUG_GPIO_BMC_4")
	)
	(via
		(at 31.839662 -114.90579)
		(size 0.508)
		(drill 0.254)
		(layers "F.Cu" "B.Cu")
		(net "DEBUG_GPIO_BMC_4")
	)
	(via
		(at 97.7773 -140.176504)
		(size 0.508)
		(drill 0.254)
		(layers "F.Cu" "B.Cu")
		(net "DEBUG_GPIO_BMC_4")
	)
	(via
		(at 26.8224 -153.8986)
		(size 0.508)
		(drill 0.254)
		(layers "F.Cu" "B.Cu")
		(net "DEBUG_GPIO_BMC_4")
	)
	(segment
		(start 82.686144 -126.0856)
		(end 76.35494 -126.0856)
		(width 0.127)
		(layer "B.Cu")
		(net "DEBUG_GPIO_BMC_4")
	)
	(segment
		(start 93.985588 -123.5964)
		(end 85.175344 -123.5964)
		(width 0.127)
		(layer "B.Cu")
		(net "DEBUG_GPIO_BMC_4")
	)
	(segment
		(start 33.063688 -113.681764)
		(end 31.839662 -114.90579)
		(width 0.127)
		(layer "B.Cu")
		(net "DEBUG_GPIO_BMC_4")
	)
	(segment
		(start 94.760288 -124.3711)
		(end 93.985588 -123.5964)
		(width 0.127)
		(layer "B.Cu")
		(net "DEBUG_GPIO_BMC_4")
	)
	(segment
		(start 97.281746 -138.058906)
		(end 97.662492 -137.67816)
		(width 0.127)
		(layer "B.Cu")
		(net "DEBUG_GPIO_BMC_4")
	)
	(segment
		(start 97.810828 -129.19837)
		(end 97.810828 -125.90272)
		(width 0.127)
		(layer "B.Cu")
		(net "DEBUG_GPIO_BMC_4")
	)
	(segment
		(start 53.096668 -113.681764)
		(end 33.063688 -113.681764)
		(width 0.127)
		(layer "B.Cu")
		(net "DEBUG_GPIO_BMC_4")
	)
	(segment
		(start 76.35494 -126.0856)
		(end 73.33234 -123.063)
		(width 0.127)
		(layer "B.Cu")
		(net "DEBUG_GPIO_BMC_4")
	)
	(segment
		(start 98.434398 -129.82194)
		(end 97.810828 -129.19837)
		(width 0.127)
		(layer "B.Cu")
		(net "DEBUG_GPIO_BMC_4")
	)
	(segment
		(start 85.175344 -123.5964)
		(end 82.686144 -126.0856)
		(width 0.127)
		(layer "B.Cu")
		(net "DEBUG_GPIO_BMC_4")
	)
	(segment
		(start 96.279208 -124.3711)
		(end 94.760288 -124.3711)
		(width 0.127)
		(layer "B.Cu")
		(net "DEBUG_GPIO_BMC_4")
	)
	(segment
		(start 97.281746 -139.68095)
		(end 97.281746 -138.058906)
		(width 0.127)
		(layer "B.Cu")
		(net "DEBUG_GPIO_BMC_4")
	)
	(segment
		(start 97.662492 -137.67816)
		(end 97.662492 -135.494776)
		(width 0.127)
		(layer "B.Cu")
		(net "DEBUG_GPIO_BMC_4")
	)
	(segment
		(start 98.434398 -134.72287)
		(end 98.434398 -129.82194)
		(width 0.127)
		(layer "B.Cu")
		(net "DEBUG_GPIO_BMC_4")
	)
	(segment
		(start 97.7773 -140.176504)
		(end 97.281746 -139.68095)
		(width 0.127)
		(layer "B.Cu")
		(net "DEBUG_GPIO_BMC_4")
	)
	(segment
		(start 97.662492 -135.494776)
		(end 98.434398 -134.72287)
		(width 0.127)
		(layer "B.Cu")
		(net "DEBUG_GPIO_BMC_4")
	)
	(segment
		(start 62.477904 -123.063)
		(end 53.096668 -113.681764)
		(width 0.127)
		(layer "B.Cu")
		(net "DEBUG_GPIO_BMC_4")
	)
	(segment
		(start 97.810828 -125.90272)
		(end 96.279208 -124.3711)
		(width 0.127)
		(layer "B.Cu")
		(net "DEBUG_GPIO_BMC_4")
	)
	(segment
		(start 73.33234 -123.063)
		(end 62.477904 -123.063)
		(width 0.127)
		(layer "B.Cu")
		(net "DEBUG_GPIO_BMC_4")
	)
	(segment
		(start 16.484092 -113.066322)
		(end 11.208004 -118.34241)
		(width 0.127)
		(layer "In5.Cu")
		(net "DEBUG_GPIO_BMC_4")
	)
	(segment
		(start 11.208004 -118.34241)
		(end 11.208004 -128.039114)
		(width 0.127)
		(layer "In5.Cu")
		(net "DEBUG_GPIO_BMC_4")
	)
	(segment
		(start 11.208004 -128.039114)
		(end 12.4333 -129.26441)
		(width 0.127)
		(layer "In5.Cu")
		(net "DEBUG_GPIO_BMC_4")
	)
	(segment
		(start 31.491682 -114.90579)
		(end 30.784292 -114.1984)
		(width 0.127)
		(layer "In5.Cu")
		(net "DEBUG_GPIO_BMC_4")
	)
	(segment
		(start 12.4333 -148.0439)
		(end 17.9197 -153.5303)
		(width 0.127)
		(layer "In5.Cu")
		(net "DEBUG_GPIO_BMC_4")
	)
	(segment
		(start 12.4333 -129.26441)
		(end 12.4333 -148.0439)
		(width 0.127)
		(layer "In5.Cu")
		(net "DEBUG_GPIO_BMC_4")
	)
	(segment
		(start 27.836114 -113.066322)
		(end 16.484092 -113.066322)
		(width 0.127)
		(layer "In5.Cu")
		(net "DEBUG_GPIO_BMC_4")
	)
	(segment
		(start 30.784292 -114.1984)
		(end 28.968192 -114.1984)
		(width 0.127)
		(layer "In5.Cu")
		(net "DEBUG_GPIO_BMC_4")
	)
	(segment
		(start 26.4541 -153.5303)
		(end 26.8224 -153.8986)
		(width 0.127)
		(layer "In5.Cu")
		(net "DEBUG_GPIO_BMC_4")
	)
	(segment
		(start 28.968192 -114.1984)
		(end 27.836114 -113.066322)
		(width 0.127)
		(layer "In5.Cu")
		(net "DEBUG_GPIO_BMC_4")
	)
	(segment
		(start 31.839662 -114.90579)
		(end 31.491682 -114.90579)
		(width 0.127)
		(layer "In5.Cu")
		(net "DEBUG_GPIO_BMC_4")
	)
	(segment
		(start 17.9197 -153.5303)
		(end 26.4541 -153.5303)
		(width 0.127)
		(layer "In5.Cu")
		(net "DEBUG_GPIO_BMC_4")
	)
	(segment
		(start 94.856808 -141.028166)
		(end 95.996506 -141.028166)
		(width 0.127)
		(layer "F.Cu")
		(net "DEBUG_GPIO_BMC_3")
	)
	(segment
		(start 94.036642 -140.208)
		(end 94.856808 -141.028166)
		(width 0.127)
		(layer "F.Cu")
		(net "DEBUG_GPIO_BMC_3")
	)
	(segment
		(start 26.797 -154.686)
		(end 27.7495 -154.686)
		(width 0.127)
		(layer "F.Cu")
		(net "DEBUG_GPIO_BMC_3")
	)
	(segment
		(start 26.5684 -154.9146)
		(end 26.797 -154.686)
		(width 0.127)
		(layer "F.Cu")
		(net "DEBUG_GPIO_BMC_3")
	)
	(segment
		(start 94.036642 -139.69111)
		(end 94.036642 -140.208)
		(width 0.127)
		(layer "F.Cu")
		(net "DEBUG_GPIO_BMC_3")
	)
	(via
		(at 32.757872 -114.996214)
		(size 0.508)
		(drill 0.254)
		(layers "F.Cu" "B.Cu")
		(net "DEBUG_GPIO_BMC_3")
	)
	(via
		(at 94.036642 -139.69111)
		(size 0.508)
		(drill 0.254)
		(layers "F.Cu" "B.Cu")
		(net "DEBUG_GPIO_BMC_3")
	)
	(via
		(at 26.5684 -154.9146)
		(size 0.508)
		(drill 0.254)
		(layers "F.Cu" "B.Cu")
		(net "DEBUG_GPIO_BMC_3")
	)
	(segment
		(start 94.982792 -127.145288)
		(end 93.187774 -125.35027)
		(width 0.127)
		(layer "B.Cu")
		(net "DEBUG_GPIO_BMC_3")
	)
	(segment
		(start 95.4659 -128.3843)
		(end 95.4659 -127.471932)
		(width 0.127)
		(layer "B.Cu")
		(net "DEBUG_GPIO_BMC_3")
	)
	(segment
		(start 35.945318 -115.345718)
		(end 33.107376 -115.345718)
		(width 0.127)
		(layer "B.Cu")
		(net "DEBUG_GPIO_BMC_3")
	)
	(segment
		(start 62.172596 -124.4092)
		(end 52.656486 -114.89309)
		(width 0.127)
		(layer "B.Cu")
		(net "DEBUG_GPIO_BMC_3")
	)
	(segment
		(start 95.139256 -127.145288)
		(end 94.982792 -127.145288)
		(width 0.127)
		(layer "B.Cu")
		(net "DEBUG_GPIO_BMC_3")
	)
	(segment
		(start 88.266524 -125.2347)
		(end 85.154008 -125.2347)
		(width 0.127)
		(layer "B.Cu")
		(net "DEBUG_GPIO_BMC_3")
	)
	(segment
		(start 67.5386 -125.222)
		(end 66.7258 -124.4092)
		(width 0.127)
		(layer "B.Cu")
		(net "DEBUG_GPIO_BMC_3")
	)
	(segment
		(start 96.519492 -135.585962)
		(end 96.519492 -129.437892)
		(width 0.127)
		(layer "B.Cu")
		(net "DEBUG_GPIO_BMC_3")
	)
	(segment
		(start 36.397946 -114.89309)
		(end 35.945318 -115.345718)
		(width 0.127)
		(layer "B.Cu")
		(net "DEBUG_GPIO_BMC_3")
	)
	(segment
		(start 95.726504 -138.726672)
		(end 95.726504 -136.37895)
		(width 0.127)
		(layer "B.Cu")
		(net "DEBUG_GPIO_BMC_3")
	)
	(segment
		(start 93.187774 -125.35027)
		(end 88.382094 -125.35027)
		(width 0.127)
		(layer "B.Cu")
		(net "DEBUG_GPIO_BMC_3")
	)
	(segment
		(start 96.519492 -129.437892)
		(end 95.4659 -128.3843)
		(width 0.127)
		(layer "B.Cu")
		(net "DEBUG_GPIO_BMC_3")
	)
	(segment
		(start 94.036642 -139.69111)
		(end 94.762066 -139.69111)
		(width 0.127)
		(layer "B.Cu")
		(net "DEBUG_GPIO_BMC_3")
	)
	(segment
		(start 52.656486 -114.89309)
		(end 36.397946 -114.89309)
		(width 0.127)
		(layer "B.Cu")
		(net "DEBUG_GPIO_BMC_3")
	)
	(segment
		(start 88.382094 -125.35027)
		(end 88.266524 -125.2347)
		(width 0.127)
		(layer "B.Cu")
		(net "DEBUG_GPIO_BMC_3")
	)
	(segment
		(start 95.4659 -127.471932)
		(end 95.139256 -127.145288)
		(width 0.127)
		(layer "B.Cu")
		(net "DEBUG_GPIO_BMC_3")
	)
	(segment
		(start 33.107376 -115.345718)
		(end 32.757872 -114.996214)
		(width 0.127)
		(layer "B.Cu")
		(net "DEBUG_GPIO_BMC_3")
	)
	(segment
		(start 83.160108 -127.2286)
		(end 75.880976 -127.2286)
		(width 0.127)
		(layer "B.Cu")
		(net "DEBUG_GPIO_BMC_3")
	)
	(segment
		(start 95.726504 -136.37895)
		(end 96.519492 -135.585962)
		(width 0.127)
		(layer "B.Cu")
		(net "DEBUG_GPIO_BMC_3")
	)
	(segment
		(start 75.880976 -127.2286)
		(end 73.874376 -125.222)
		(width 0.127)
		(layer "B.Cu")
		(net "DEBUG_GPIO_BMC_3")
	)
	(segment
		(start 85.154008 -125.2347)
		(end 83.160108 -127.2286)
		(width 0.127)
		(layer "B.Cu")
		(net "DEBUG_GPIO_BMC_3")
	)
	(segment
		(start 73.874376 -125.222)
		(end 67.5386 -125.222)
		(width 0.127)
		(layer "B.Cu")
		(net "DEBUG_GPIO_BMC_3")
	)
	(segment
		(start 66.7258 -124.4092)
		(end 62.172596 -124.4092)
		(width 0.127)
		(layer "B.Cu")
		(net "DEBUG_GPIO_BMC_3")
	)
	(segment
		(start 94.762066 -139.69111)
		(end 95.726504 -138.726672)
		(width 0.127)
		(layer "B.Cu")
		(net "DEBUG_GPIO_BMC_3")
	)
	(segment
		(start 9.861804 -130.417316)
		(end 11.6713 -132.226812)
		(width 0.127)
		(layer "In5.Cu")
		(net "DEBUG_GPIO_BMC_3")
	)
	(segment
		(start 29.12618 -113.8174)
		(end 27.994102 -112.685322)
		(width 0.127)
		(layer "In5.Cu")
		(net "DEBUG_GPIO_BMC_3")
	)
	(segment
		(start 11.6713 -132.226812)
		(end 11.6713 -148.3995)
		(width 0.127)
		(layer "In5.Cu")
		(net "DEBUG_GPIO_BMC_3")
	)
	(segment
		(start 11.6713 -148.3995)
		(end 18.1864 -154.9146)
		(width 0.127)
		(layer "In5.Cu")
		(net "DEBUG_GPIO_BMC_3")
	)
	(segment
		(start 16.326104 -112.685322)
		(end 9.861804 -119.149622)
		(width 0.127)
		(layer "In5.Cu")
		(net "DEBUG_GPIO_BMC_3")
	)
	(segment
		(start 27.994102 -112.685322)
		(end 16.326104 -112.685322)
		(width 0.127)
		(layer "In5.Cu")
		(net "DEBUG_GPIO_BMC_3")
	)
	(segment
		(start 9.861804 -119.149622)
		(end 9.861804 -130.417316)
		(width 0.127)
		(layer "In5.Cu")
		(net "DEBUG_GPIO_BMC_3")
	)
	(segment
		(start 30.94228 -113.8174)
		(end 29.12618 -113.8174)
		(width 0.127)
		(layer "In5.Cu")
		(net "DEBUG_GPIO_BMC_3")
	)
	(segment
		(start 31.56077 -114.43589)
		(end 30.94228 -113.8174)
		(width 0.127)
		(layer "In5.Cu")
		(net "DEBUG_GPIO_BMC_3")
	)
	(segment
		(start 18.1864 -154.9146)
		(end 26.5684 -154.9146)
		(width 0.127)
		(layer "In5.Cu")
		(net "DEBUG_GPIO_BMC_3")
	)
	(segment
		(start 32.757872 -114.996214)
		(end 32.197548 -114.43589)
		(width 0.127)
		(layer "In5.Cu")
		(net "DEBUG_GPIO_BMC_3")
	)
	(segment
		(start 32.197548 -114.43589)
		(end 31.56077 -114.43589)
		(width 0.127)
		(layer "In5.Cu")
		(net "DEBUG_GPIO_BMC_3")
	)
	(segment
		(start 94.528386 -139.90828)
		(end 94.528386 -139.208256)
		(width 0.127)
		(layer "F.Cu")
		(net "DEBUG_GPIO_BMC_2")
	)
	(segment
		(start 94.059502 -138.739372)
		(end 94.042738 -138.739372)
		(width 0.127)
		(layer "F.Cu")
		(net "DEBUG_GPIO_BMC_2")
	)
	(segment
		(start 95.996506 -140.377926)
		(end 94.998032 -140.377926)
		(width 0.127)
		(layer "F.Cu")
		(net "DEBUG_GPIO_BMC_2")
	)
	(segment
		(start 26.7716 -152.7302)
		(end 26.8478 -152.654)
		(width 0.127)
		(layer "F.Cu")
		(net "DEBUG_GPIO_BMC_2")
	)
	(segment
		(start 94.998032 -140.377926)
		(end 94.528386 -139.90828)
		(width 0.127)
		(layer "F.Cu")
		(net "DEBUG_GPIO_BMC_2")
	)
	(segment
		(start 26.8478 -152.654)
		(end 27.7495 -152.654)
		(width 0.127)
		(layer "F.Cu")
		(net "DEBUG_GPIO_BMC_2")
	)
	(segment
		(start 94.528386 -139.208256)
		(end 94.059502 -138.739372)
		(width 0.127)
		(layer "F.Cu")
		(net "DEBUG_GPIO_BMC_2")
	)
	(via
		(at 94.042738 -138.739372)
		(size 0.508)
		(drill 0.254)
		(layers "F.Cu" "B.Cu")
		(net "DEBUG_GPIO_BMC_2")
	)
	(via
		(at 30.943804 -115.101624)
		(size 0.508)
		(drill 0.254)
		(layers "F.Cu" "B.Cu")
		(net "DEBUG_GPIO_BMC_2")
	)
	(via
		(at 26.7716 -152.7302)
		(size 0.508)
		(drill 0.254)
		(layers "F.Cu" "B.Cu")
		(net "DEBUG_GPIO_BMC_2")
	)
	(segment
		(start 62.014608 -124.7902)
		(end 52.498498 -115.27409)
		(width 0.127)
		(layer "B.Cu")
		(net "DEBUG_GPIO_BMC_2")
	)
	(segment
		(start 94.042738 -138.739372)
		(end 94.064582 -138.717528)
		(width 0.127)
		(layer "B.Cu")
		(net "DEBUG_GPIO_BMC_2")
	)
	(segment
		(start 88.224106 -125.73127)
		(end 88.108536 -125.6157)
		(width 0.127)
		(layer "B.Cu")
		(net "DEBUG_GPIO_BMC_2")
	)
	(segment
		(start 95.3389 -136.33958)
		(end 95.339408 -136.138412)
		(width 0.127)
		(layer "B.Cu")
		(net "DEBUG_GPIO_BMC_2")
	)
	(segment
		(start 83.318096 -127.6096)
		(end 75.722988 -127.6096)
		(width 0.127)
		(layer "B.Cu")
		(net "DEBUG_GPIO_BMC_2")
	)
	(segment
		(start 91.411552 -125.73127)
		(end 88.224106 -125.73127)
		(width 0.127)
		(layer "B.Cu")
		(net "DEBUG_GPIO_BMC_2")
	)
	(segment
		(start 95.339408 -135.902192)
		(end 96.138492 -135.103108)
		(width 0.127)
		(layer "B.Cu")
		(net "DEBUG_GPIO_BMC_2")
	)
	(segment
		(start 85.311996 -125.6157)
		(end 83.318096 -127.6096)
		(width 0.127)
		(layer "B.Cu")
		(net "DEBUG_GPIO_BMC_2")
	)
	(segment
		(start 52.498498 -115.27409)
		(end 36.555934 -115.27409)
		(width 0.127)
		(layer "B.Cu")
		(net "DEBUG_GPIO_BMC_2")
	)
	(segment
		(start 94.064582 -138.717528)
		(end 94.365318 -138.717528)
		(width 0.127)
		(layer "B.Cu")
		(net "DEBUG_GPIO_BMC_2")
	)
	(segment
		(start 67.380612 -125.603)
		(end 66.567812 -124.7902)
		(width 0.127)
		(layer "B.Cu")
		(net "DEBUG_GPIO_BMC_2")
	)
	(segment
		(start 94.392242 -127.9652)
		(end 93.645482 -127.9652)
		(width 0.127)
		(layer "B.Cu")
		(net "DEBUG_GPIO_BMC_2")
	)
	(segment
		(start 96.138492 -129.71145)
		(end 94.392242 -127.9652)
		(width 0.127)
		(layer "B.Cu")
		(net "DEBUG_GPIO_BMC_2")
	)
	(segment
		(start 73.716388 -125.603)
		(end 67.380612 -125.603)
		(width 0.127)
		(layer "B.Cu")
		(net "DEBUG_GPIO_BMC_2")
	)
	(segment
		(start 95.339408 -136.138412)
		(end 95.339408 -135.902192)
		(width 0.127)
		(layer "B.Cu")
		(net "DEBUG_GPIO_BMC_2")
	)
	(segment
		(start 96.138492 -135.103108)
		(end 96.138492 -129.71145)
		(width 0.127)
		(layer "B.Cu")
		(net "DEBUG_GPIO_BMC_2")
	)
	(segment
		(start 31.64078 -115.7986)
		(end 30.943804 -115.101624)
		(width 0.127)
		(layer "B.Cu")
		(net "DEBUG_GPIO_BMC_2")
	)
	(segment
		(start 93.645482 -127.9652)
		(end 91.411552 -125.73127)
		(width 0.127)
		(layer "B.Cu")
		(net "DEBUG_GPIO_BMC_2")
	)
	(segment
		(start 95.3389 -137.743946)
		(end 95.3389 -136.33958)
		(width 0.127)
		(layer "B.Cu")
		(net "DEBUG_GPIO_BMC_2")
	)
	(segment
		(start 36.031424 -115.7986)
		(end 31.64078 -115.7986)
		(width 0.127)
		(layer "B.Cu")
		(net "DEBUG_GPIO_BMC_2")
	)
	(segment
		(start 88.108536 -125.6157)
		(end 85.311996 -125.6157)
		(width 0.127)
		(layer "B.Cu")
		(net "DEBUG_GPIO_BMC_2")
	)
	(segment
		(start 36.555934 -115.27409)
		(end 36.031424 -115.7986)
		(width 0.127)
		(layer "B.Cu")
		(net "DEBUG_GPIO_BMC_2")
	)
	(segment
		(start 75.722988 -127.6096)
		(end 73.716388 -125.603)
		(width 0.127)
		(layer "B.Cu")
		(net "DEBUG_GPIO_BMC_2")
	)
	(segment
		(start 94.365318 -138.717528)
		(end 95.3389 -137.743946)
		(width 0.127)
		(layer "B.Cu")
		(net "DEBUG_GPIO_BMC_2")
	)
	(segment
		(start 66.567812 -124.7902)
		(end 62.014608 -124.7902)
		(width 0.127)
		(layer "B.Cu")
		(net "DEBUG_GPIO_BMC_2")
	)
	(segment
		(start 18.236692 -153.011886)
		(end 26.489914 -153.011886)
		(width 0.127)
		(layer "In5.Cu")
		(net "DEBUG_GPIO_BMC_2")
	)
	(segment
		(start 11.589004 -127.881126)
		(end 12.8143 -129.106422)
		(width 0.127)
		(layer "In5.Cu")
		(net "DEBUG_GPIO_BMC_2")
	)
	(segment
		(start 30.42158 -114.5794)
		(end 28.8036 -114.5794)
		(width 0.127)
		(layer "In5.Cu")
		(net "DEBUG_GPIO_BMC_2")
	)
	(segment
		(start 28.8036 -114.5794)
		(end 27.671522 -113.447322)
		(width 0.127)
		(layer "In5.Cu")
		(net "DEBUG_GPIO_BMC_2")
	)
	(segment
		(start 27.671522 -113.447322)
		(end 16.64208 -113.447322)
		(width 0.127)
		(layer "In5.Cu")
		(net "DEBUG_GPIO_BMC_2")
	)
	(segment
		(start 16.64208 -113.447322)
		(end 11.589004 -118.500398)
		(width 0.127)
		(layer "In5.Cu")
		(net "DEBUG_GPIO_BMC_2")
	)
	(segment
		(start 12.8143 -147.589494)
		(end 18.236692 -153.011886)
		(width 0.127)
		(layer "In5.Cu")
		(net "DEBUG_GPIO_BMC_2")
	)
	(segment
		(start 12.8143 -129.106422)
		(end 12.8143 -147.589494)
		(width 0.127)
		(layer "In5.Cu")
		(net "DEBUG_GPIO_BMC_2")
	)
	(segment
		(start 30.943804 -115.101624)
		(end 30.42158 -114.5794)
		(width 0.127)
		(layer "In5.Cu")
		(net "DEBUG_GPIO_BMC_2")
	)
	(segment
		(start 26.489914 -153.011886)
		(end 26.7716 -152.7302)
		(width 0.127)
		(layer "In5.Cu")
		(net "DEBUG_GPIO_BMC_2")
	)
	(segment
		(start 11.589004 -118.500398)
		(end 11.589004 -127.881126)
		(width 0.127)
		(layer "In5.Cu")
		(net "DEBUG_GPIO_BMC_2")
	)
	(segment
		(start 94.368874 -136.557766)
		(end 94.798388 -136.128252)
		(width 0.127)
		(layer "F.Cu")
		(net "DEBUG_GPIO_BMC_1")
	)
	(segment
		(start 94.368874 -137.507726)
		(end 94.368874 -136.557766)
		(width 0.127)
		(layer "F.Cu")
		(net "DEBUG_GPIO_BMC_1")
	)
	(segment
		(start 94.909386 -138.048238)
		(end 94.368874 -137.507726)
		(width 0.127)
		(layer "F.Cu")
		(net "DEBUG_GPIO_BMC_1")
	)
	(segment
		(start 27.7495 -151.638)
		(end 26.8224 -151.638)
		(width 0.127)
		(layer "F.Cu")
		(net "DEBUG_GPIO_BMC_1")
	)
	(segment
		(start 94.909386 -139.257786)
		(end 94.909386 -138.048238)
		(width 0.127)
		(layer "F.Cu")
		(net "DEBUG_GPIO_BMC_1")
	)
	(segment
		(start 95.379286 -139.727686)
		(end 94.909386 -139.257786)
		(width 0.127)
		(layer "F.Cu")
		(net "DEBUG_GPIO_BMC_1")
	)
	(segment
		(start 95.996506 -139.727686)
		(end 95.379286 -139.727686)
		(width 0.127)
		(layer "F.Cu")
		(net "DEBUG_GPIO_BMC_1")
	)
	(via
		(at 26.8224 -151.638)
		(size 0.508)
		(drill 0.254)
		(layers "F.Cu" "B.Cu")
		(net "DEBUG_GPIO_BMC_1")
	)
	(via
		(at 29.999432 -115.102386)
		(size 0.508)
		(drill 0.254)
		(layers "F.Cu" "B.Cu")
		(net "DEBUG_GPIO_BMC_1")
	)
	(via
		(at 94.798388 -136.128252)
		(size 0.508)
		(drill 0.254)
		(layers "F.Cu" "B.Cu")
		(net "DEBUG_GPIO_BMC_1")
	)
	(segment
		(start 94.798388 -136.128252)
		(end 94.798388 -135.452612)
		(width 0.127)
		(layer "B.Cu")
		(net "DEBUG_GPIO_BMC_1")
	)
	(segment
		(start 88.066118 -126.11227)
		(end 87.950548 -125.9967)
		(width 0.127)
		(layer "B.Cu")
		(net "DEBUG_GPIO_BMC_1")
	)
	(segment
		(start 95.757492 -134.493508)
		(end 95.757492 -129.960116)
		(width 0.127)
		(layer "B.Cu")
		(net "DEBUG_GPIO_BMC_1")
	)
	(segment
		(start 63.879476 -127.208026)
		(end 52.32654 -115.65509)
		(width 0.127)
		(layer "B.Cu")
		(net "DEBUG_GPIO_BMC_1")
	)
	(segment
		(start 94.143576 -128.3462)
		(end 93.354144 -128.3462)
		(width 0.127)
		(layer "B.Cu")
		(net "DEBUG_GPIO_BMC_1")
	)
	(segment
		(start 52.32654 -115.65509)
		(end 36.713922 -115.65509)
		(width 0.127)
		(layer "B.Cu")
		(net "DEBUG_GPIO_BMC_1")
	)
	(segment
		(start 95.757492 -129.960116)
		(end 94.143576 -128.3462)
		(width 0.127)
		(layer "B.Cu")
		(net "DEBUG_GPIO_BMC_1")
	)
	(segment
		(start 85.469984 -125.9967)
		(end 83.476084 -127.9906)
		(width 0.127)
		(layer "B.Cu")
		(net "DEBUG_GPIO_BMC_1")
	)
	(segment
		(start 91.120214 -126.11227)
		(end 88.066118 -126.11227)
		(width 0.127)
		(layer "B.Cu")
		(net "DEBUG_GPIO_BMC_1")
	)
	(segment
		(start 75.06208 -127.9906)
		(end 74.279506 -127.208026)
		(width 0.127)
		(layer "B.Cu")
		(net "DEBUG_GPIO_BMC_1")
	)
	(segment
		(start 87.950548 -125.9967)
		(end 85.469984 -125.9967)
		(width 0.127)
		(layer "B.Cu")
		(net "DEBUG_GPIO_BMC_1")
	)
	(segment
		(start 36.713922 -115.65509)
		(end 36.189412 -116.1796)
		(width 0.127)
		(layer "B.Cu")
		(net "DEBUG_GPIO_BMC_1")
	)
	(segment
		(start 74.279506 -127.208026)
		(end 63.879476 -127.208026)
		(width 0.127)
		(layer "B.Cu")
		(net "DEBUG_GPIO_BMC_1")
	)
	(segment
		(start 94.798388 -135.452612)
		(end 95.757492 -134.493508)
		(width 0.127)
		(layer "B.Cu")
		(net "DEBUG_GPIO_BMC_1")
	)
	(segment
		(start 31.076646 -116.1796)
		(end 29.999432 -115.102386)
		(width 0.127)
		(layer "B.Cu")
		(net "DEBUG_GPIO_BMC_1")
	)
	(segment
		(start 36.189412 -116.1796)
		(end 31.076646 -116.1796)
		(width 0.127)
		(layer "B.Cu")
		(net "DEBUG_GPIO_BMC_1")
	)
	(segment
		(start 93.354144 -128.3462)
		(end 91.120214 -126.11227)
		(width 0.127)
		(layer "B.Cu")
		(net "DEBUG_GPIO_BMC_1")
	)
	(segment
		(start 83.476084 -127.9906)
		(end 75.06208 -127.9906)
		(width 0.127)
		(layer "B.Cu")
		(net "DEBUG_GPIO_BMC_1")
	)
	(segment
		(start 11.970004 -118.658386)
		(end 11.970004 -127.723138)
		(width 0.127)
		(layer "In5.Cu")
		(net "DEBUG_GPIO_BMC_1")
	)
	(segment
		(start 14.4526 -130.205734)
		(end 14.4526 -148.688806)
		(width 0.127)
		(layer "In5.Cu")
		(net "DEBUG_GPIO_BMC_1")
	)
	(segment
		(start 11.970004 -127.723138)
		(end 14.4526 -130.205734)
		(width 0.127)
		(layer "In5.Cu")
		(net "DEBUG_GPIO_BMC_1")
	)
	(segment
		(start 28.8798 -115.6462)
		(end 27.061922 -113.828322)
		(width 0.127)
		(layer "In5.Cu")
		(net "DEBUG_GPIO_BMC_1")
	)
	(segment
		(start 16.800068 -113.828322)
		(end 11.970004 -118.658386)
		(width 0.127)
		(layer "In5.Cu")
		(net "DEBUG_GPIO_BMC_1")
	)
	(segment
		(start 27.061922 -113.828322)
		(end 16.800068 -113.828322)
		(width 0.127)
		(layer "In5.Cu")
		(net "DEBUG_GPIO_BMC_1")
	)
	(segment
		(start 18.265394 -152.5016)
		(end 25.9588 -152.5016)
		(width 0.127)
		(layer "In5.Cu")
		(net "DEBUG_GPIO_BMC_1")
	)
	(segment
		(start 25.9588 -152.5016)
		(end 26.8224 -151.638)
		(width 0.127)
		(layer "In5.Cu")
		(net "DEBUG_GPIO_BMC_1")
	)
	(segment
		(start 14.4526 -148.688806)
		(end 18.265394 -152.5016)
		(width 0.127)
		(layer "In5.Cu")
		(net "DEBUG_GPIO_BMC_1")
	)
	(segment
		(start 29.999432 -115.102386)
		(end 29.455618 -115.6462)
		(width 0.127)
		(layer "In5.Cu")
		(net "DEBUG_GPIO_BMC_1")
	)
	(segment
		(start 29.455618 -115.6462)
		(end 28.8798 -115.6462)
		(width 0.127)
		(layer "In5.Cu")
		(net "DEBUG_GPIO_BMC_1")
	)
	(segment
		(start 49.96942 -166.027862)
		(end 49.948592 -166.007034)
		(width 0.127)
		(layer "F.Cu")
		(net "ADC_P2V5_STBY")
	)
	(segment
		(start 52.099972 -151.800052)
		(end 52.099972 -151.800306)
		(width 0.127)
		(layer "F.Cu")
		(net "ADC_P2V5_STBY")
	)
	(segment
		(start 48.708818 -166.007034)
		(end 48.703484 -166.012368)
		(width 0.127)
		(layer "F.Cu")
		(net "ADC_P2V5_STBY")
	)
	(segment
		(start 50.935128 -166.027862)
		(end 49.96942 -166.027862)
		(width 0.127)
		(layer "F.Cu")
		(net "ADC_P2V5_STBY")
	)
	(segment
		(start 52.099972 -151.800306)
		(end 52.499768 -152.200102)
		(width 0.127)
		(layer "F.Cu")
		(net "ADC_P2V5_STBY")
	)
	(segment
		(start 49.948592 -166.007034)
		(end 48.708818 -166.007034)
		(width 0.127)
		(layer "F.Cu")
		(net "ADC_P2V5_STBY")
	)
	(segment
		(start 50.935128 -166.027862)
		(end 50.935128 -165.362128)
		(width 0.127)
		(layer "F.Cu")
		(net "ADC_P2V5_STBY")
	)
	(segment
		(start 50.935128 -165.362128)
		(end 50.6984 -165.1254)
		(width 0.127)
		(layer "F.Cu")
		(net "ADC_P2V5_STBY")
	)
	(via
		(at 50.6984 -165.1254)
		(size 0.508)
		(drill 0.254)
		(layers "F.Cu" "B.Cu")
		(net "ADC_P2V5_STBY")
	)
	(via
		(at 52.499768 -152.200102)
		(size 0.4572)
		(drill 0.2032)
		(layers "F.Cu" "B.Cu")
		(net "ADC_P2V5_STBY")
	)
	(segment
		(start 52.4002 -158.94939)
		(end 51.509168 -158.058358)
		(width 0.127)
		(layer "In2.Cu")
		(net "ADC_P2V5_STBY")
	)
	(segment
		(start 52.321968 -152.022302)
		(end 52.499768 -152.200102)
		(width 0.127)
		(layer "In2.Cu")
		(net "ADC_P2V5_STBY")
	)
	(segment
		(start 51.536346 -151.806402)
		(end 51.86299 -151.806402)
		(width 0.127)
		(layer "In2.Cu")
		(net "ADC_P2V5_STBY")
	)
	(segment
		(start 50.98288 -164.37102)
		(end 52.02428 -164.37102)
		(width 0.127)
		(layer "In2.Cu")
		(net "ADC_P2V5_STBY")
	)
	(segment
		(start 52.1335 -164.48024)
		(end 52.98186 -164.48024)
		(width 0.127)
		(layer "In2.Cu")
		(net "ADC_P2V5_STBY")
	)
	(segment
		(start 53.2765 -163.39312)
		(end 53.0098 -163.12642)
		(width 0.127)
		(layer "In2.Cu")
		(net "ADC_P2V5_STBY")
	)
	(segment
		(start 51.305968 -153.93162)
		(end 51.305968 -152.03678)
		(width 0.127)
		(layer "In2.Cu")
		(net "ADC_P2V5_STBY")
	)
	(segment
		(start 50.6984 -165.1254)
		(end 50.6984 -164.6555)
		(width 0.127)
		(layer "In2.Cu")
		(net "ADC_P2V5_STBY")
	)
	(segment
		(start 51.86299 -151.806402)
		(end 52.07889 -152.022302)
		(width 0.127)
		(layer "In2.Cu")
		(net "ADC_P2V5_STBY")
	)
	(segment
		(start 51.509168 -158.058358)
		(end 51.509168 -154.13482)
		(width 0.127)
		(layer "In2.Cu")
		(net "ADC_P2V5_STBY")
	)
	(segment
		(start 52.07889 -152.022302)
		(end 52.321968 -152.022302)
		(width 0.127)
		(layer "In2.Cu")
		(net "ADC_P2V5_STBY")
	)
	(segment
		(start 53.0098 -159.564832)
		(end 52.4002 -158.955232)
		(width 0.127)
		(layer "In2.Cu")
		(net "ADC_P2V5_STBY")
	)
	(segment
		(start 50.6984 -164.6555)
		(end 50.98288 -164.37102)
		(width 0.127)
		(layer "In2.Cu")
		(net "ADC_P2V5_STBY")
	)
	(segment
		(start 52.4002 -158.955232)
		(end 52.4002 -158.94939)
		(width 0.127)
		(layer "In2.Cu")
		(net "ADC_P2V5_STBY")
	)
	(segment
		(start 52.02428 -164.37102)
		(end 52.1335 -164.48024)
		(width 0.127)
		(layer "In2.Cu")
		(net "ADC_P2V5_STBY")
	)
	(segment
		(start 51.509168 -154.13482)
		(end 51.305968 -153.93162)
		(width 0.127)
		(layer "In2.Cu")
		(net "ADC_P2V5_STBY")
	)
	(segment
		(start 53.2765 -164.1856)
		(end 53.2765 -163.39312)
		(width 0.127)
		(layer "In2.Cu")
		(net "ADC_P2V5_STBY")
	)
	(segment
		(start 51.305968 -152.03678)
		(end 51.536346 -151.806402)
		(width 0.127)
		(layer "In2.Cu")
		(net "ADC_P2V5_STBY")
	)
	(segment
		(start 52.98186 -164.48024)
		(end 53.2765 -164.1856)
		(width 0.127)
		(layer "In2.Cu")
		(net "ADC_P2V5_STBY")
	)
	(segment
		(start 53.0098 -163.12642)
		(end 53.0098 -159.564832)
		(width 0.127)
		(layer "In2.Cu")
		(net "ADC_P2V5_STBY")
	)
	(segment
		(start 53.96103 -165.64483)
		(end 53.6956 -165.3794)
		(width 0.127)
		(layer "F.Cu")
		(net "ADC_P1V2_STBY")
	)
	(segment
		(start 52.985162 -165.998652)
		(end 52.963064 -165.976554)
		(width 0.127)
		(layer "F.Cu")
		(net "ADC_P1V2_STBY")
	)
	(segment
		(start 52.963064 -165.976554)
		(end 51.910488 -165.976554)
		(width 0.127)
		(layer "F.Cu")
		(net "ADC_P1V2_STBY")
	)
	(segment
		(start 53.13934 -165.3794)
		(end 51.906932 -164.146992)
		(width 0.127)
		(layer "F.Cu")
		(net "ADC_P1V2_STBY")
	)
	(segment
		(start 52.899818 -151.800052)
		(end 53.299614 -152.199848)
		(width 0.127)
		(layer "F.Cu")
		(net "ADC_P1V2_STBY")
	)
	(segment
		(start 53.6956 -165.3794)
		(end 53.13934 -165.3794)
		(width 0.127)
		(layer "F.Cu")
		(net "ADC_P1V2_STBY")
	)
	(segment
		(start 53.96103 -165.998652)
		(end 52.985162 -165.998652)
		(width 0.127)
		(layer "F.Cu")
		(net "ADC_P1V2_STBY")
	)
	(segment
		(start 51.906932 -164.146992)
		(end 51.906932 -164.1221)
		(width 0.127)
		(layer "F.Cu")
		(net "ADC_P1V2_STBY")
	)
	(segment
		(start 53.96103 -165.998652)
		(end 53.96103 -165.64483)
		(width 0.127)
		(layer "F.Cu")
		(net "ADC_P1V2_STBY")
	)
	(segment
		(start 51.906932 -164.1221)
		(end 51.8541 -164.069268)
		(width 0.127)
		(layer "F.Cu")
		(net "ADC_P1V2_STBY")
	)
	(segment
		(start 51.8541 -164.069268)
		(end 51.8541 -163.87572)
		(width 0.127)
		(layer "F.Cu")
		(net "ADC_P1V2_STBY")
	)
	(segment
		(start 51.910488 -165.976554)
		(end 51.906678 -165.972744)
		(width 0.127)
		(layer "F.Cu")
		(net "ADC_P1V2_STBY")
	)
	(via
		(at 53.299614 -152.199848)
		(size 0.4572)
		(drill 0.2032)
		(layers "F.Cu" "B.Cu")
		(net "ADC_P1V2_STBY")
	)
	(via
		(at 51.8541 -163.87572)
		(size 0.508)
		(drill 0.254)
		(layers "F.Cu" "B.Cu")
		(net "ADC_P1V2_STBY")
	)
	(segment
		(start 52.53736 -159.63138)
		(end 50.2793 -157.37332)
		(width 0.127)
		(layer "In2.Cu")
		(net "ADC_P1V2_STBY")
	)
	(segment
		(start 52.66309 -151.006302)
		(end 52.905914 -151.249126)
		(width 0.127)
		(layer "In2.Cu")
		(net "ADC_P1V2_STBY")
	)
	(segment
		(start 50.506122 -151.23668)
		(end 50.7365 -151.006302)
		(width 0.127)
		(layer "In2.Cu")
		(net "ADC_P1V2_STBY")
	)
	(segment
		(start 50.506122 -152.167082)
		(end 50.506122 -151.23668)
		(width 0.127)
		(layer "In2.Cu")
		(net "ADC_P1V2_STBY")
	)
	(segment
		(start 50.772822 -152.433782)
		(end 50.506122 -152.167082)
		(width 0.127)
		(layer "In2.Cu")
		(net "ADC_P1V2_STBY")
	)
	(segment
		(start 52.905914 -151.249126)
		(end 52.905914 -151.563324)
		(width 0.127)
		(layer "In2.Cu")
		(net "ADC_P1V2_STBY")
	)
	(segment
		(start 53.299614 -151.957024)
		(end 53.299614 -152.199848)
		(width 0.127)
		(layer "In2.Cu")
		(net "ADC_P1V2_STBY")
	)
	(segment
		(start 50.2793 -154.9019)
		(end 50.772822 -154.408378)
		(width 0.127)
		(layer "In2.Cu")
		(net "ADC_P1V2_STBY")
	)
	(segment
		(start 50.772822 -154.408378)
		(end 50.772822 -152.433782)
		(width 0.127)
		(layer "In2.Cu")
		(net "ADC_P1V2_STBY")
	)
	(segment
		(start 50.7365 -151.006302)
		(end 52.66309 -151.006302)
		(width 0.127)
		(layer "In2.Cu")
		(net "ADC_P1V2_STBY")
	)
	(segment
		(start 52.905914 -151.563324)
		(end 53.299614 -151.957024)
		(width 0.127)
		(layer "In2.Cu")
		(net "ADC_P1V2_STBY")
	)
	(segment
		(start 52.53736 -162.80384)
		(end 52.53736 -159.63138)
		(width 0.127)
		(layer "In2.Cu")
		(net "ADC_P1V2_STBY")
	)
	(segment
		(start 51.8541 -163.4871)
		(end 52.53736 -162.80384)
		(width 0.127)
		(layer "In2.Cu")
		(net "ADC_P1V2_STBY")
	)
	(segment
		(start 50.2793 -157.37332)
		(end 50.2793 -154.9019)
		(width 0.127)
		(layer "In2.Cu")
		(net "ADC_P1V2_STBY")
	)
	(segment
		(start 51.8541 -163.87572)
		(end 51.8541 -163.4871)
		(width 0.127)
		(layer "In2.Cu")
		(net "ADC_P1V2_STBY")
	)
	(segment
		(start 65.437766 -158.071566)
		(end 65.978278 -158.612078)
		(width 0.127)
		(layer "F.Cu")
		(net "ADC_P1V15_STBY")
	)
	(segment
		(start 65.950084 -161.078164)
		(end 65.995042 -161.123122)
		(width 0.127)
		(layer "F.Cu")
		(net "ADC_P1V15_STBY")
	)
	(segment
		(start 50.899822 -150.599902)
		(end 51.299872 -150.199852)
		(width 0.127)
		(layer "F.Cu")
		(net "ADC_P1V15_STBY")
	)
	(segment
		(start 66.953892 -162.25774)
		(end 67.229482 -162.25774)
		(width 0.127)
		(layer "F.Cu")
		(net "ADC_P1V15_STBY")
	)
	(segment
		(start 65.995042 -161.29889)
		(end 66.953892 -162.25774)
		(width 0.127)
		(layer "F.Cu")
		(net "ADC_P1V15_STBY")
	)
	(segment
		(start 65.995042 -161.123122)
		(end 65.995042 -161.29889)
		(width 0.127)
		(layer "F.Cu")
		(net "ADC_P1V15_STBY")
	)
	(segment
		(start 65.950084 -160.038034)
		(end 65.950084 -159.096456)
		(width 0.127)
		(layer "F.Cu")
		(net "ADC_P1V15_STBY")
	)
	(segment
		(start 65.950084 -160.038034)
		(end 65.950084 -161.078164)
		(width 0.127)
		(layer "F.Cu")
		(net "ADC_P1V15_STBY")
	)
	(segment
		(start 65.978278 -158.612078)
		(end 65.978278 -159.068262)
		(width 0.127)
		(layer "F.Cu")
		(net "ADC_P1V15_STBY")
	)
	(segment
		(start 65.950084 -159.096456)
		(end 65.978278 -159.068262)
		(width 0.127)
		(layer "F.Cu")
		(net "ADC_P1V15_STBY")
	)
	(segment
		(start 64.956182 -158.071566)
		(end 65.437766 -158.071566)
		(width 0.127)
		(layer "F.Cu")
		(net "ADC_P1V15_STBY")
	)
	(via
		(at 64.956182 -158.071566)
		(size 0.508)
		(drill 0.254)
		(layers "F.Cu" "B.Cu")
		(net "ADC_P1V15_STBY")
	)
	(via
		(at 67.229482 -162.25774)
		(size 0.6604)
		(drill 0.3302)
		(layers "F.Cu" "B.Cu")
		(net "ADC_P1V15_STBY")
	)
	(via
		(at 50.899822 -150.599902)
		(size 0.4572)
		(drill 0.2032)
		(layers "F.Cu" "B.Cu")
		(net "ADC_P1V15_STBY")
	)
	(segment
		(start 51.293776 -150.205948)
		(end 50.899822 -150.599902)
		(width 0.127)
		(layer "In2.Cu")
		(net "ADC_P1V15_STBY")
	)
	(segment
		(start 52.705 -150.205948)
		(end 51.293776 -150.205948)
		(width 0.127)
		(layer "In2.Cu")
		(net "ADC_P1V15_STBY")
	)
	(segment
		(start 55.504334 -154.424634)
		(end 55.504334 -151.973534)
		(width 0.127)
		(layer "In2.Cu")
		(net "ADC_P1V15_STBY")
	)
	(segment
		(start 64.956182 -158.071566)
		(end 64.663828 -158.36392)
		(width 0.127)
		(layer "In2.Cu")
		(net "ADC_P1V15_STBY")
	)
	(segment
		(start 54.524402 -150.993602)
		(end 53.136292 -150.993602)
		(width 0.127)
		(layer "In2.Cu")
		(net "ADC_P1V15_STBY")
	)
	(segment
		(start 52.893468 -150.750778)
		(end 52.893468 -150.394416)
		(width 0.127)
		(layer "In2.Cu")
		(net "ADC_P1V15_STBY")
	)
	(segment
		(start 52.893468 -150.394416)
		(end 52.705 -150.205948)
		(width 0.127)
		(layer "In2.Cu")
		(net "ADC_P1V15_STBY")
	)
	(segment
		(start 56.0705 -156.5529)
		(end 56.0705 -154.9908)
		(width 0.127)
		(layer "In2.Cu")
		(net "ADC_P1V15_STBY")
	)
	(segment
		(start 55.504334 -151.973534)
		(end 54.524402 -150.993602)
		(width 0.127)
		(layer "In2.Cu")
		(net "ADC_P1V15_STBY")
	)
	(segment
		(start 55.6387 -158.0642)
		(end 55.6387 -156.9847)
		(width 0.127)
		(layer "In2.Cu")
		(net "ADC_P1V15_STBY")
	)
	(segment
		(start 53.136292 -150.993602)
		(end 52.893468 -150.750778)
		(width 0.127)
		(layer "In2.Cu")
		(net "ADC_P1V15_STBY")
	)
	(segment
		(start 55.6387 -156.9847)
		(end 56.0705 -156.5529)
		(width 0.127)
		(layer "In2.Cu")
		(net "ADC_P1V15_STBY")
	)
	(segment
		(start 56.0705 -154.9908)
		(end 55.504334 -154.424634)
		(width 0.127)
		(layer "In2.Cu")
		(net "ADC_P1V15_STBY")
	)
	(segment
		(start 64.663828 -158.36392)
		(end 55.93842 -158.36392)
		(width 0.127)
		(layer "In2.Cu")
		(net "ADC_P1V15_STBY")
	)
	(segment
		(start 55.93842 -158.36392)
		(end 55.6387 -158.0642)
		(width 0.127)
		(layer "In2.Cu")
		(net "ADC_P1V15_STBY")
	)
	(segment
		(start 75.475084 -61.74994)
		(end 77.151738 -61.74994)
		(width 0.127)
		(layer "F.Cu")
		(net "PCIE_WAKE_N")
	)
	(segment
		(start 46.49978 -150.999952)
		(end 46.099984 -151.399748)
		(width 0.127)
		(layer "F.Cu")
		(net "PCIE_WAKE_N")
	)
	(segment
		(start 46.500034 -150.999952)
		(end 46.49978 -150.999952)
		(width 0.127)
		(layer "F.Cu")
		(net "PCIE_WAKE_N")
	)
	(segment
		(start 77.151738 -61.74994)
		(end 77.668374 -61.233304)
		(width 0.127)
		(layer "F.Cu")
		(net "PCIE_WAKE_N")
	)
	(via
		(at 70.7136 -117.6782)
		(size 0.508)
		(drill 0.254)
		(layers "F.Cu" "B.Cu")
		(net "PCIE_WAKE_N")
	)
	(via
		(at 79.756 -99.187)
		(size 0.508)
		(drill 0.254)
		(layers "F.Cu" "B.Cu")
		(net "PCIE_WAKE_N")
	)
	(via
		(at 14.0462 -125.8824)
		(size 0.508)
		(drill 0.254)
		(layers "F.Cu" "B.Cu")
		(net "PCIE_WAKE_N")
	)
	(via
		(at 77.668374 -61.233304)
		(size 0.508)
		(drill 0.254)
		(layers "F.Cu" "B.Cu")
		(net "PCIE_WAKE_N")
	)
	(via
		(at 46.099984 -151.399748)
		(size 0.4572)
		(drill 0.2032)
		(layers "F.Cu" "B.Cu")
		(net "PCIE_WAKE_N")
	)
	(via
		(at 32.9692 -160.1978)
		(size 0.508)
		(drill 0.254)
		(layers "F.Cu" "B.Cu")
		(net "PCIE_WAKE_N")
	)
	(via
		(at 45.0342 -159.2072)
		(size 0.508)
		(drill 0.254)
		(layers "F.Cu" "B.Cu")
		(net "PCIE_WAKE_N")
	)
	(segment
		(start 38.54704 -162.13328)
		(end 40.77716 -162.13328)
		(width 0.127)
		(layer "B.Cu")
		(net "PCIE_WAKE_N")
	)
	(segment
		(start 32.9692 -160.1978)
		(end 35.4457 -160.1978)
		(width 0.127)
		(layer "B.Cu")
		(net "PCIE_WAKE_N")
	)
	(segment
		(start 36.550346 -161.302446)
		(end 37.716206 -161.302446)
		(width 0.127)
		(layer "B.Cu")
		(net "PCIE_WAKE_N")
	)
	(segment
		(start 41.529254 -159.892746)
		(end 42.073576 -159.348424)
		(width 0.127)
		(layer "B.Cu")
		(net "PCIE_WAKE_N")
	)
	(segment
		(start 41.529254 -161.37509)
		(end 41.529254 -159.892746)
		(width 0.127)
		(layer "B.Cu")
		(net "PCIE_WAKE_N")
	)
	(segment
		(start 45.0342 -159.2072)
		(end 44.698412 -159.2072)
		(width 0.127)
		(layer "B.Cu")
		(net "PCIE_WAKE_N")
	)
	(segment
		(start 41.4909 -161.41954)
		(end 41.4909 -161.413444)
		(width 0.127)
		(layer "B.Cu")
		(net "PCIE_WAKE_N")
	)
	(segment
		(start 42.073576 -159.348424)
		(end 43.302428 -159.348424)
		(width 0.127)
		(layer "B.Cu")
		(net "PCIE_WAKE_N")
	)
	(segment
		(start 43.302428 -159.348424)
		(end 43.929808 -159.975804)
		(width 0.127)
		(layer "B.Cu")
		(net "PCIE_WAKE_N")
	)
	(segment
		(start 41.4909 -161.413444)
		(end 41.529254 -161.37509)
		(width 0.127)
		(layer "B.Cu")
		(net "PCIE_WAKE_N")
	)
	(segment
		(start 40.77716 -162.13328)
		(end 41.4909 -161.41954)
		(width 0.127)
		(layer "B.Cu")
		(net "PCIE_WAKE_N")
	)
	(segment
		(start 37.716206 -161.302446)
		(end 38.54704 -162.13328)
		(width 0.127)
		(layer "B.Cu")
		(net "PCIE_WAKE_N")
	)
	(segment
		(start 44.698412 -159.2072)
		(end 43.929808 -159.975804)
		(width 0.127)
		(layer "B.Cu")
		(net "PCIE_WAKE_N")
	)
	(segment
		(start 35.4457 -160.1978)
		(end 36.550346 -161.302446)
		(width 0.127)
		(layer "B.Cu")
		(net "PCIE_WAKE_N")
	)
	(segment
		(start 21.77923 -157.27807)
		(end 17.643348 -157.27807)
		(width 0.127)
		(layer "In2.Cu")
		(net "PCIE_WAKE_N")
	)
	(segment
		(start 11.5062 -144.25168)
		(end 10.59815 -143.34363)
		(width 0.127)
		(layer "In2.Cu")
		(net "PCIE_WAKE_N")
	)
	(segment
		(start 82.274664 -110.0074)
		(end 85.280246 -107.001818)
		(width 0.127)
		(layer "In2.Cu")
		(net "PCIE_WAKE_N")
	)
	(segment
		(start 11.5062 -151.140922)
		(end 11.5062 -144.25168)
		(width 0.127)
		(layer "In2.Cu")
		(net "PCIE_WAKE_N")
	)
	(segment
		(start 10.59815 -143.34363)
		(end 10.59815 -131.647438)
		(width 0.127)
		(layer "In2.Cu")
		(net "PCIE_WAKE_N")
	)
	(segment
		(start 17.643348 -157.27807)
		(end 11.5062 -151.140922)
		(width 0.127)
		(layer "In2.Cu")
		(net "PCIE_WAKE_N")
	)
	(segment
		(start 85.280246 -107.001818)
		(end 85.280246 -102.857046)
		(width 0.127)
		(layer "In2.Cu")
		(net "PCIE_WAKE_N")
	)
	(segment
		(start 78.707234 -110.0074)
		(end 82.274664 -110.0074)
		(width 0.127)
		(layer "In2.Cu")
		(net "PCIE_WAKE_N")
	)
	(segment
		(start 70.612 -117.5766)
		(end 70.612 -115.1636)
		(width 0.127)
		(layer "In2.Cu")
		(net "PCIE_WAKE_N")
	)
	(segment
		(start 46.099984 -157.404816)
		(end 46.099984 -151.399748)
		(width 0.127)
		(layer "In2.Cu")
		(net "PCIE_WAKE_N")
	)
	(segment
		(start 11.851894 -130.393694)
		(end 11.851894 -127.949706)
		(width 0.127)
		(layer "In2.Cu")
		(net "PCIE_WAKE_N")
	)
	(segment
		(start 80.4926 -99.9236)
		(end 79.756 -99.187)
		(width 0.127)
		(layer "In2.Cu")
		(net "PCIE_WAKE_N")
	)
	(segment
		(start 45.0342 -159.2072)
		(end 45.0342 -158.4706)
		(width 0.127)
		(layer "In2.Cu")
		(net "PCIE_WAKE_N")
	)
	(segment
		(start 82.3468 -99.9236)
		(end 80.4926 -99.9236)
		(width 0.127)
		(layer "In2.Cu")
		(net "PCIE_WAKE_N")
	)
	(segment
		(start 71.28891 -114.48669)
		(end 74.227944 -114.48669)
		(width 0.127)
		(layer "In2.Cu")
		(net "PCIE_WAKE_N")
	)
	(segment
		(start 10.59815 -131.647438)
		(end 11.851894 -130.393694)
		(width 0.127)
		(layer "In2.Cu")
		(net "PCIE_WAKE_N")
	)
	(segment
		(start 70.7136 -117.6782)
		(end 70.612 -117.5766)
		(width 0.127)
		(layer "In2.Cu")
		(net "PCIE_WAKE_N")
	)
	(segment
		(start 24.69896 -160.1978)
		(end 21.77923 -157.27807)
		(width 0.127)
		(layer "In2.Cu")
		(net "PCIE_WAKE_N")
	)
	(segment
		(start 13.9192 -125.8824)
		(end 14.0462 -125.8824)
		(width 0.127)
		(layer "In2.Cu")
		(net "PCIE_WAKE_N")
	)
	(segment
		(start 32.9692 -160.1978)
		(end 24.69896 -160.1978)
		(width 0.127)
		(layer "In2.Cu")
		(net "PCIE_WAKE_N")
	)
	(segment
		(start 70.612 -115.1636)
		(end 71.28891 -114.48669)
		(width 0.127)
		(layer "In2.Cu")
		(net "PCIE_WAKE_N")
	)
	(segment
		(start 85.280246 -102.857046)
		(end 82.3468 -99.9236)
		(width 0.127)
		(layer "In2.Cu")
		(net "PCIE_WAKE_N")
	)
	(segment
		(start 74.227944 -114.48669)
		(end 78.707234 -110.0074)
		(width 0.127)
		(layer "In2.Cu")
		(net "PCIE_WAKE_N")
	)
	(segment
		(start 45.0342 -158.4706)
		(end 46.099984 -157.404816)
		(width 0.127)
		(layer "In2.Cu")
		(net "PCIE_WAKE_N")
	)
	(segment
		(start 11.851894 -127.949706)
		(end 13.9192 -125.8824)
		(width 0.127)
		(layer "In2.Cu")
		(net "PCIE_WAKE_N")
	)
	(segment
		(start 70.7136 -117.6782)
		(end 70.5104 -117.475)
		(width 0.127)
		(layer "In5.Cu")
		(net "PCIE_WAKE_N")
	)
	(segment
		(start 30.283912 -121.8184)
		(end 26.381964 -125.720348)
		(width 0.127)
		(layer "In5.Cu")
		(net "PCIE_WAKE_N")
	)
	(segment
		(start 26.381964 -125.720348)
		(end 18.246852 -125.720348)
		(width 0.127)
		(layer "In5.Cu")
		(net "PCIE_WAKE_N")
	)
	(segment
		(start 36.825682 -121.8184)
		(end 30.283912 -121.8184)
		(width 0.127)
		(layer "In5.Cu")
		(net "PCIE_WAKE_N")
	)
	(segment
		(start 44.7294 -122.301)
		(end 42.5704 -120.142)
		(width 0.127)
		(layer "In5.Cu")
		(net "PCIE_WAKE_N")
	)
	(segment
		(start 18.246852 -125.720348)
		(end 17.9705 -125.9967)
		(width 0.127)
		(layer "In5.Cu")
		(net "PCIE_WAKE_N")
	)
	(segment
		(start 42.5704 -120.142)
		(end 39.064692 -120.142)
		(width 0.127)
		(layer "In5.Cu")
		(net "PCIE_WAKE_N")
	)
	(segment
		(start 48.1203 -120.668796)
		(end 48.1203 -121.5517)
		(width 0.127)
		(layer "In5.Cu")
		(net "PCIE_WAKE_N")
	)
	(segment
		(start 69.0118 -118.1608)
		(end 54.9148 -118.1608)
		(width 0.127)
		(layer "In5.Cu")
		(net "PCIE_WAKE_N")
	)
	(segment
		(start 37.028882 -121.6152)
		(end 36.825682 -121.8184)
		(width 0.127)
		(layer "In5.Cu")
		(net "PCIE_WAKE_N")
	)
	(segment
		(start 14.1605 -125.9967)
		(end 14.0462 -125.8824)
		(width 0.127)
		(layer "In5.Cu")
		(net "PCIE_WAKE_N")
	)
	(segment
		(start 54.6862 -117.9322)
		(end 50.856896 -117.9322)
		(width 0.127)
		(layer "In5.Cu")
		(net "PCIE_WAKE_N")
	)
	(segment
		(start 17.9705 -125.9967)
		(end 14.1605 -125.9967)
		(width 0.127)
		(layer "In5.Cu")
		(net "PCIE_WAKE_N")
	)
	(segment
		(start 48.1203 -121.5517)
		(end 47.371 -122.301)
		(width 0.127)
		(layer "In5.Cu")
		(net "PCIE_WAKE_N")
	)
	(segment
		(start 78.569058 -98.000058)
		(end 79.756 -99.187)
		(width 0.127)
		(layer "In5.Cu")
		(net "PCIE_WAKE_N")
	)
	(segment
		(start 70.5104 -117.475)
		(end 69.6976 -117.475)
		(width 0.127)
		(layer "In5.Cu")
		(net "PCIE_WAKE_N")
	)
	(segment
		(start 78.569058 -62.133988)
		(end 78.569058 -98.000058)
		(width 0.127)
		(layer "In5.Cu")
		(net "PCIE_WAKE_N")
	)
	(segment
		(start 77.668374 -61.233304)
		(end 78.569058 -62.133988)
		(width 0.127)
		(layer "In5.Cu")
		(net "PCIE_WAKE_N")
	)
	(segment
		(start 37.591492 -121.6152)
		(end 37.028882 -121.6152)
		(width 0.127)
		(layer "In5.Cu")
		(net "PCIE_WAKE_N")
	)
	(segment
		(start 69.6976 -117.475)
		(end 69.0118 -118.1608)
		(width 0.127)
		(layer "In5.Cu")
		(net "PCIE_WAKE_N")
	)
	(segment
		(start 47.371 -122.301)
		(end 44.7294 -122.301)
		(width 0.127)
		(layer "In5.Cu")
		(net "PCIE_WAKE_N")
	)
	(segment
		(start 50.856896 -117.9322)
		(end 48.1203 -120.668796)
		(width 0.127)
		(layer "In5.Cu")
		(net "PCIE_WAKE_N")
	)
	(segment
		(start 39.064692 -120.142)
		(end 37.591492 -121.6152)
		(width 0.127)
		(layer "In5.Cu")
		(net "PCIE_WAKE_N")
	)
	(segment
		(start 54.9148 -118.1608)
		(end 54.6862 -117.9322)
		(width 0.127)
		(layer "In5.Cu")
		(net "PCIE_WAKE_N")
	)
	(segment
		(start 178.40706 -123.10618)
		(end 178.42484 -123.0884)
		(width 0.127)
		(layer "F.Cu")
		(net "P1V8_EN")
	)
	(segment
		(start 179.11318 -124.15774)
		(end 180.42382 -122.8471)
		(width 0.127)
		(layer "F.Cu")
		(net "P1V8_EN")
	)
	(segment
		(start 175.875188 -121.953528)
		(end 175.387 -121.46534)
		(width 0.127)
		(layer "F.Cu")
		(net "P1V8_EN")
	)
	(segment
		(start 178.42484 -123.0884)
		(end 177.289968 -121.953528)
		(width 0.127)
		(layer "F.Cu")
		(net "P1V8_EN")
	)
	(segment
		(start 178.40706 -124.15774)
		(end 179.11318 -124.15774)
		(width 0.127)
		(layer "F.Cu")
		(net "P1V8_EN")
	)
	(segment
		(start 177.289968 -121.953528)
		(end 177.06213 -121.953528)
		(width 0.127)
		(layer "F.Cu")
		(net "P1V8_EN")
	)
	(segment
		(start 175.387 -121.46534)
		(end 175.387 -121.223786)
		(width 0.127)
		(layer "F.Cu")
		(net "P1V8_EN")
	)
	(segment
		(start 177.06213 -121.953528)
		(end 175.875188 -121.953528)
		(width 0.127)
		(layer "F.Cu")
		(net "P1V8_EN")
	)
	(segment
		(start 178.40706 -124.15774)
		(end 178.40706 -123.10618)
		(width 0.127)
		(layer "F.Cu")
		(net "P1V8_EN")
	)
	(via
		(at 177.06213 -121.953528)
		(size 0.6604)
		(drill 0.3302)
		(layers "F.Cu" "B.Cu")
		(net "P1V8_EN")
	)
	(segment
		(start 53.8861 -126.8222)
		(end 53.8861 -125.8062)
		(width 0.127)
		(layer "F.Cu")
		(net "FLA1_WP_N")
	)
	(segment
		(start 53.8861 -128.9939)
		(end 53.8861 -126.8222)
		(width 0.127)
		(layer "F.Cu")
		(net "FLA1_WP_N")
	)
	(segment
		(start 53.34 -129.54)
		(end 53.8861 -128.9939)
		(width 0.127)
		(layer "F.Cu")
		(net "FLA1_WP_N")
	)
	(segment
		(start 53.8861 -125.8062)
		(end 56.012334 -125.8062)
		(width 0.0889)
		(layer "F.Cu")
		(net "FLA1_WP_N")
	)
	(via
		(at 53.34 -129.54)
		(size 0.6604)
		(drill 0.3302)
		(layers "F.Cu" "B.Cu")
		(net "FLA1_WP_N")
	)
	(segment
		(start 68.0593 -119.4562)
		(end 68.0339 -119.4816)
		(width 0.127)
		(layer "F.Cu")
		(net "FLA1_SPI_RST")
	)
	(segment
		(start 65.806066 -119.4562)
		(end 68.0593 -119.4562)
		(width 0.127)
		(layer "F.Cu")
		(net "FLA1_SPI_RST")
	)
	(segment
		(start 68.0339 -119.4816)
		(end 68.0339 -120.523)
		(width 0.127)
		(layer "F.Cu")
		(net "FLA1_SPI_RST")
	)
	(segment
		(start 65.62725 -119.4562)
		(end 65.806066 -119.4562)
		(width 0.127)
		(layer "F.Cu")
		(net "FLA1_SPI_RST")
	)
	(segment
		(start 29.993336 -125.254512)
		(end 27.99588 -125.254512)
		(width 0.127)
		(layer "F.Cu")
		(net "FLA0_WP_N")
	)
	(segment
		(start 31.872174 -125.805946)
		(end 30.54477 -125.805946)
		(width 0.127)
		(layer "F.Cu")
		(net "FLA0_WP_N")
	)
	(segment
		(start 27.6225 -156.591)
		(end 25.0444 -156.591)
		(width 0.127)
		(layer "F.Cu")
		(net "FLA0_WP_N")
	)
	(segment
		(start 25.0444 -156.591)
		(end 24.9428 -156.6926)
		(width 0.127)
		(layer "F.Cu")
		(net "FLA0_WP_N")
	)
	(segment
		(start 26.90368 -125.264672)
		(end 25.899872 -125.264672)
		(width 0.127)
		(layer "F.Cu")
		(net "FLA0_WP_N")
	)
	(segment
		(start 27.98572 -125.264672)
		(end 27.99588 -125.254512)
		(width 0.127)
		(layer "F.Cu")
		(net "FLA0_WP_N")
	)
	(segment
		(start 32.05099 -125.805946)
		(end 31.872174 -125.805946)
		(width 0.127)
		(layer "F.Cu")
		(net "FLA0_WP_N")
	)
	(segment
		(start 27.7495 -156.718)
		(end 27.6225 -156.591)
		(width 0.127)
		(layer "F.Cu")
		(net "FLA0_WP_N")
	)
	(segment
		(start 26.90368 -125.264672)
		(end 27.98572 -125.264672)
		(width 0.127)
		(layer "F.Cu")
		(net "FLA0_WP_N")
	)
	(segment
		(start 30.54477 -125.805946)
		(end 29.993336 -125.254512)
		(width 0.127)
		(layer "F.Cu")
		(net "FLA0_WP_N")
	)
	(segment
		(start 25.899872 -125.264672)
		(end 25.8572 -125.222)
		(width 0.127)
		(layer "F.Cu")
		(net "FLA0_WP_N")
	)
	(via
		(at 24.9428 -156.6926)
		(size 0.508)
		(drill 0.254)
		(layers "F.Cu" "B.Cu")
		(net "FLA0_WP_N")
	)
	(via
		(at 25.8572 -125.222)
		(size 0.508)
		(drill 0.254)
		(layers "F.Cu" "B.Cu")
		(net "FLA0_WP_N")
	)
	(segment
		(start 25.8572 -125.222)
		(end 25.2476 -124.6124)
		(width 0.127)
		(layer "In2.Cu")
		(net "FLA0_WP_N")
	)
	(segment
		(start 19.169634 -126.7206)
		(end 14.8336 -126.7206)
		(width 0.127)
		(layer "In2.Cu")
		(net "FLA0_WP_N")
	)
	(segment
		(start 11.10615 -143.133064)
		(end 12.0142 -144.041114)
		(width 0.127)
		(layer "In2.Cu")
		(net "FLA0_WP_N")
	)
	(segment
		(start 12.99845 -128.55575)
		(end 12.99845 -129.965704)
		(width 0.127)
		(layer "In2.Cu")
		(net "FLA0_WP_N")
	)
	(segment
		(start 12.0142 -148.8059)
		(end 19.9009 -156.6926)
		(width 0.127)
		(layer "In2.Cu")
		(net "FLA0_WP_N")
	)
	(segment
		(start 12.99845 -129.965704)
		(end 11.10615 -131.858004)
		(width 0.127)
		(layer "In2.Cu")
		(net "FLA0_WP_N")
	)
	(segment
		(start 19.9009 -156.6926)
		(end 24.9428 -156.6926)
		(width 0.127)
		(layer "In2.Cu")
		(net "FLA0_WP_N")
	)
	(segment
		(start 12.0142 -144.041114)
		(end 12.0142 -148.8059)
		(width 0.127)
		(layer "In2.Cu")
		(net "FLA0_WP_N")
	)
	(segment
		(start 11.10615 -131.858004)
		(end 11.10615 -143.133064)
		(width 0.127)
		(layer "In2.Cu")
		(net "FLA0_WP_N")
	)
	(segment
		(start 14.8336 -126.7206)
		(end 12.99845 -128.55575)
		(width 0.127)
		(layer "In2.Cu")
		(net "FLA0_WP_N")
	)
	(segment
		(start 21.277834 -124.6124)
		(end 19.169634 -126.7206)
		(width 0.127)
		(layer "In2.Cu")
		(net "FLA0_WP_N")
	)
	(segment
		(start 25.2476 -124.6124)
		(end 21.277834 -124.6124)
		(width 0.127)
		(layer "In2.Cu")
		(net "FLA0_WP_N")
	)
	(segment
		(start 43.824906 -119.346218)
		(end 45.591476 -119.346218)
		(width 0.127)
		(layer "F.Cu")
		(net "FLA0_SPI_RST")
	)
	(segment
		(start 43.715178 -119.455946)
		(end 43.824906 -119.346218)
		(width 0.127)
		(layer "F.Cu")
		(net "FLA0_SPI_RST")
	)
	(segment
		(start 41.665906 -119.455946)
		(end 43.715178 -119.455946)
		(width 0.127)
		(layer "F.Cu")
		(net "FLA0_SPI_RST")
	)
	(segment
		(start 45.591476 -119.346218)
		(end 45.591476 -120.389396)
		(width 0.127)
		(layer "F.Cu")
		(net "FLA0_SPI_RST")
	)
	(segment
		(start 45.591476 -120.389396)
		(end 45.58538 -120.395492)
		(width 0.127)
		(layer "F.Cu")
		(net "FLA0_SPI_RST")
	)
	(segment
		(start 41.665906 -116.915946)
		(end 42.63898 -116.915946)
		(width 0.0889)
		(layer "F.Cu")
		(net "FLA0_SPI_HOLD_N")
	)
	(segment
		(start 43.241722 -116.313204)
		(end 45.123862 -116.313204)
		(width 0.0889)
		(layer "F.Cu")
		(net "FLA0_SPI_HOLD_N")
	)
	(segment
		(start 42.63898 -116.915946)
		(end 43.241722 -116.313204)
		(width 0.0889)
		(layer "F.Cu")
		(net "FLA0_SPI_HOLD_N")
	)
	(segment
		(start 45.123862 -116.313204)
		(end 45.591476 -116.780818)
		(width 0.0889)
		(layer "F.Cu")
		(net "FLA0_SPI_HOLD_N")
	)
	(segment
		(start 157.8864 -38.5064)
		(end 157.8864 -34.7472)
		(width 0.127)
		(layer "F.Cu")
		(net "ZDEF_EXTB_TP_D2")
	)
	(segment
		(start 156.44114 -30.268418)
		(end 157.60954 -29.100018)
		(width 0.127)
		(layer "F.Cu")
		(net "ZDEF_EXTB_TP_D2")
	)
	(segment
		(start 157.8864 -34.7472)
		(end 156.44114 -33.30194)
		(width 0.127)
		(layer "F.Cu")
		(net "ZDEF_EXTB_TP_D2")
	)
	(segment
		(start 156.44114 -33.30194)
		(end 156.44114 -30.268418)
		(width 0.127)
		(layer "F.Cu")
		(net "ZDEF_EXTB_TP_D2")
	)
	(segment
		(start 157.60954 -29.100018)
		(end 157.750002 -29.100018)
		(width 0.127)
		(layer "F.Cu")
		(net "ZDEF_EXTB_TP_D2")
	)
	(segment
		(start 158.84906 -34.51606)
		(end 158.84906 -39.21506)
		(width 0.127)
		(layer "F.Cu")
		(net "ZDEF_EXTB_TP_D1")
	)
	(segment
		(start 158.84906 -39.21506)
		(end 158.06674 -39.99738)
		(width 0.127)
		(layer "F.Cu")
		(net "ZDEF_EXTB_TP_D1")
	)
	(segment
		(start 156.99994 -32.66694)
		(end 158.84906 -34.51606)
		(width 0.127)
		(layer "F.Cu")
		(net "ZDEF_EXTB_TP_D1")
	)
	(segment
		(start 156.99994 -30.500066)
		(end 156.99994 -32.66694)
		(width 0.127)
		(layer "F.Cu")
		(net "ZDEF_EXTB_TP_D1")
	)
	(segment
		(start 157.60954 -25.299924)
		(end 157.750002 -25.299924)
		(width 0.127)
		(layer "F.Cu")
		(net "ZDEF_EXTB_TP_C2")
	)
	(segment
		(start 155.1686 -38.481)
		(end 155.1686 -27.740864)
		(width 0.127)
		(layer "F.Cu")
		(net "ZDEF_EXTB_TP_C2")
	)
	(segment
		(start 155.1686 -27.740864)
		(end 157.60954 -25.299924)
		(width 0.127)
		(layer "F.Cu")
		(net "ZDEF_EXTB_TP_C2")
	)
	(segment
		(start 156.5402 -34.7345)
		(end 155.829 -34.0233)
		(width 0.127)
		(layer "F.Cu")
		(net "ZDEF_EXTB_TP_C1")
	)
	(segment
		(start 155.829 -27.870912)
		(end 156.99994 -26.699972)
		(width 0.127)
		(layer "F.Cu")
		(net "ZDEF_EXTB_TP_C1")
	)
	(segment
		(start 156.5402 -38.4556)
		(end 156.5402 -34.7345)
		(width 0.127)
		(layer "F.Cu")
		(net "ZDEF_EXTB_TP_C1")
	)
	(segment
		(start 155.829 -34.0233)
		(end 155.829 -27.870912)
		(width 0.127)
		(layer "F.Cu")
		(net "ZDEF_EXTB_TP_C1")
	)
	(segment
		(start 157.45968 -21.500084)
		(end 157.750002 -21.500084)
		(width 0.127)
		(layer "F.Cu")
		(net "ZDEF_EXTB_TP_B2")
	)
	(segment
		(start 152.4 -38.481)
		(end 152.4 -28.676346)
		(width 0.127)
		(layer "F.Cu")
		(net "ZDEF_EXTB_TP_B2")
	)
	(segment
		(start 156.2227 -24.853646)
		(end 156.2227 -22.737064)
		(width 0.127)
		(layer "F.Cu")
		(net "ZDEF_EXTB_TP_B2")
	)
	(segment
		(start 152.4 -28.676346)
		(end 156.2227 -24.853646)
		(width 0.127)
		(layer "F.Cu")
		(net "ZDEF_EXTB_TP_B2")
	)
	(segment
		(start 156.2227 -22.737064)
		(end 157.45968 -21.500084)
		(width 0.127)
		(layer "F.Cu")
		(net "ZDEF_EXTB_TP_B2")
	)
	(segment
		(start 156.99994 -24.915114)
		(end 153.7716 -28.143454)
		(width 0.127)
		(layer "F.Cu")
		(net "ZDEF_EXTB_TP_B1")
	)
	(segment
		(start 153.7716 -28.143454)
		(end 153.7716 -38.4556)
		(width 0.127)
		(layer "F.Cu")
		(net "ZDEF_EXTB_TP_B1")
	)
	(segment
		(start 156.99994 -22.899878)
		(end 156.99994 -24.915114)
		(width 0.127)
		(layer "F.Cu")
		(net "ZDEF_EXTB_TP_B1")
	)
	(segment
		(start 155.8417 -21.6281)
		(end 157.750002 -19.719798)
		(width 0.127)
		(layer "F.Cu")
		(net "ZDEF_EXTB_TP_A2")
	)
	(segment
		(start 150.876 -29.413454)
		(end 155.8417 -24.447754)
		(width 0.127)
		(layer "F.Cu")
		(net "ZDEF_EXTB_TP_A2")
	)
	(segment
		(start 155.8417 -24.447754)
		(end 155.8417 -21.6281)
		(width 0.127)
		(layer "F.Cu")
		(net "ZDEF_EXTB_TP_A2")
	)
	(segment
		(start 150.876 -38.481)
		(end 150.876 -29.413454)
		(width 0.127)
		(layer "F.Cu")
		(net "ZDEF_EXTB_TP_A2")
	)
	(segment
		(start 157.750002 -19.719798)
		(end 157.750002 -17.69999)
		(width 0.127)
		(layer "F.Cu")
		(net "ZDEF_EXTB_TP_A2")
	)
	(segment
		(start 149.1742 -30.447234)
		(end 155.327858 -24.293576)
		(width 0.127)
		(layer "F.Cu")
		(net "ZDEF_EXTB_TP_A1")
	)
	(segment
		(start 149.1742 -38.4556)
		(end 149.1742 -30.447234)
		(width 0.127)
		(layer "F.Cu")
		(net "ZDEF_EXTB_TP_A1")
	)
	(segment
		(start 155.327858 -20.77212)
		(end 156.99994 -19.100038)
		(width 0.127)
		(layer "F.Cu")
		(net "ZDEF_EXTB_TP_A1")
	)
	(segment
		(start 155.327858 -24.293576)
		(end 155.327858 -20.77212)
		(width 0.127)
		(layer "F.Cu")
		(net "ZDEF_EXTB_TP_A1")
	)
	(segment
		(start 59.184286 -145.742914)
		(end 56.07177 -145.742914)
		(width 0.127)
		(layer "F.Cu")
		(net "DB_PRSNT_BMC_N")
	)
	(segment
		(start 56.07177 -145.742914)
		(end 55.614824 -146.19986)
		(width 0.127)
		(layer "F.Cu")
		(net "DB_PRSNT_BMC_N")
	)
	(segment
		(start 59.6392 -145.288)
		(end 59.184286 -145.742914)
		(width 0.127)
		(layer "F.Cu")
		(net "DB_PRSNT_BMC_N")
	)
	(segment
		(start 55.614824 -146.19986)
		(end 55.299864 -146.19986)
		(width 0.127)
		(layer "F.Cu")
		(net "DB_PRSNT_BMC_N")
	)
	(via
		(at 93.03258 -143.1036)
		(size 0.508)
		(drill 0.254)
		(layers "F.Cu" "B.Cu")
		(net "DB_PRSNT_BMC_N")
	)
	(via
		(at 91.567 -143.8148)
		(size 0.6096)
		(drill 0.3048)
		(layers "F.Cu" "B.Cu")
		(net "DB_PRSNT_BMC_N")
	)
	(via
		(at 59.6392 -145.288)
		(size 0.508)
		(drill 0.254)
		(layers "F.Cu" "B.Cu")
		(net "DB_PRSNT_BMC_N")
	)
	(segment
		(start 92.917264 -143.218916)
		(end 92.563442 -143.218916)
		(width 0.127)
		(layer "B.Cu")
		(net "DB_PRSNT_BMC_N")
	)
	(segment
		(start 93.048328 -143.087852)
		(end 93.03258 -143.1036)
		(width 0.127)
		(layer "B.Cu")
		(net "DB_PRSNT_BMC_N")
	)
	(segment
		(start 91.5162 -142.7099)
		(end 91.5162 -143.764)
		(width 0.127)
		(layer "B.Cu")
		(net "DB_PRSNT_BMC_N")
	)
	(segment
		(start 91.967558 -143.8148)
		(end 91.567 -143.8148)
		(width 0.127)
		(layer "B.Cu")
		(net "DB_PRSNT_BMC_N")
	)
	(segment
		(start 94.9579 -143.087852)
		(end 93.048328 -143.087852)
		(width 0.127)
		(layer "B.Cu")
		(net "DB_PRSNT_BMC_N")
	)
	(segment
		(start 91.5162 -143.764)
		(end 91.567 -143.8148)
		(width 0.127)
		(layer "B.Cu")
		(net "DB_PRSNT_BMC_N")
	)
	(segment
		(start 92.563442 -143.218916)
		(end 91.967558 -143.8148)
		(width 0.127)
		(layer "B.Cu")
		(net "DB_PRSNT_BMC_N")
	)
	(segment
		(start 93.03258 -143.1036)
		(end 92.917264 -143.218916)
		(width 0.127)
		(layer "B.Cu")
		(net "DB_PRSNT_BMC_N")
	)
	(segment
		(start 60.292234 -145.14068)
		(end 60.144914 -145.288)
		(width 0.127)
		(layer "In5.Cu")
		(net "DB_PRSNT_BMC_N")
	)
	(segment
		(start 89.33815 -142.6337)
		(end 87.127334 -142.6337)
		(width 0.127)
		(layer "In5.Cu")
		(net "DB_PRSNT_BMC_N")
	)
	(segment
		(start 87.127334 -142.6337)
		(end 86.080854 -143.68018)
		(width 0.127)
		(layer "In5.Cu")
		(net "DB_PRSNT_BMC_N")
	)
	(segment
		(start 92.956634 -143.027654)
		(end 89.732104 -143.027654)
		(width 0.127)
		(layer "In5.Cu")
		(net "DB_PRSNT_BMC_N")
	)
	(segment
		(start 74.972418 -143.931386)
		(end 74.070972 -143.931386)
		(width 0.127)
		(layer "In5.Cu")
		(net "DB_PRSNT_BMC_N")
	)
	(segment
		(start 82.36585 -144.36344)
		(end 75.404472 -144.36344)
		(width 0.127)
		(layer "In5.Cu")
		(net "DB_PRSNT_BMC_N")
	)
	(segment
		(start 82.92084 -143.85036)
		(end 82.87893 -143.85036)
		(width 0.127)
		(layer "In5.Cu")
		(net "DB_PRSNT_BMC_N")
	)
	(segment
		(start 93.03258 -143.1036)
		(end 92.956634 -143.027654)
		(width 0.127)
		(layer "In5.Cu")
		(net "DB_PRSNT_BMC_N")
	)
	(segment
		(start 83.09102 -143.68018)
		(end 82.92084 -143.85036)
		(width 0.127)
		(layer "In5.Cu")
		(net "DB_PRSNT_BMC_N")
	)
	(segment
		(start 60.144914 -145.288)
		(end 59.6392 -145.288)
		(width 0.127)
		(layer "In5.Cu")
		(net "DB_PRSNT_BMC_N")
	)
	(segment
		(start 64.442086 -145.14068)
		(end 60.292234 -145.14068)
		(width 0.127)
		(layer "In5.Cu")
		(net "DB_PRSNT_BMC_N")
	)
	(segment
		(start 75.404472 -144.36344)
		(end 74.972418 -143.931386)
		(width 0.127)
		(layer "In5.Cu")
		(net "DB_PRSNT_BMC_N")
	)
	(segment
		(start 82.87893 -143.85036)
		(end 82.36585 -144.36344)
		(width 0.127)
		(layer "In5.Cu")
		(net "DB_PRSNT_BMC_N")
	)
	(segment
		(start 65.624456 -143.665702)
		(end 65.3034 -143.986758)
		(width 0.127)
		(layer "In5.Cu")
		(net "DB_PRSNT_BMC_N")
	)
	(segment
		(start 66.290698 -143.665702)
		(end 65.624456 -143.665702)
		(width 0.127)
		(layer "In5.Cu")
		(net "DB_PRSNT_BMC_N")
	)
	(segment
		(start 66.543682 -143.412718)
		(end 66.290698 -143.665702)
		(width 0.127)
		(layer "In5.Cu")
		(net "DB_PRSNT_BMC_N")
	)
	(segment
		(start 86.080854 -143.68018)
		(end 83.09102 -143.68018)
		(width 0.127)
		(layer "In5.Cu")
		(net "DB_PRSNT_BMC_N")
	)
	(segment
		(start 74.070972 -143.931386)
		(end 73.552304 -143.412718)
		(width 0.127)
		(layer "In5.Cu")
		(net "DB_PRSNT_BMC_N")
	)
	(segment
		(start 73.552304 -143.412718)
		(end 66.543682 -143.412718)
		(width 0.127)
		(layer "In5.Cu")
		(net "DB_PRSNT_BMC_N")
	)
	(segment
		(start 65.3034 -144.279366)
		(end 64.442086 -145.14068)
		(width 0.127)
		(layer "In5.Cu")
		(net "DB_PRSNT_BMC_N")
	)
	(segment
		(start 65.3034 -143.986758)
		(end 65.3034 -144.279366)
		(width 0.127)
		(layer "In5.Cu")
		(net "DB_PRSNT_BMC_N")
	)
	(segment
		(start 89.732104 -143.027654)
		(end 89.33815 -142.6337)
		(width 0.127)
		(layer "In5.Cu")
		(net "DB_PRSNT_BMC_N")
	)
	(segment
		(start 27.99588 -124.365512)
		(end 27.99588 -123.303792)
		(width 0.127)
		(layer "F.Cu")
		(net "WP_ENABLE")
	)
	(segment
		(start 37.907468 -134.89432)
		(end 38.982904 -134.89432)
		(width 0.127)
		(layer "F.Cu")
		(net "TPM_PRSNT_N_R")
	)
	(segment
		(start 38.982904 -134.89432)
		(end 40.099996 -136.011412)
		(width 0.127)
		(layer "F.Cu")
		(net "TPM_PRSNT_N_R")
	)
	(segment
		(start 40.099996 -136.011412)
		(end 40.099996 -136.59993)
		(width 0.127)
		(layer "F.Cu")
		(net "TPM_PRSNT_N_R")
	)
	(via
		(at 37.907468 -134.89432)
		(size 0.508)
		(drill 0.254)
		(layers "F.Cu" "B.Cu")
		(net "TPM_PRSNT_N_R")
	)
	(via
		(at 39.50716 -128.65354)
		(size 0.508)
		(drill 0.254)
		(layers "F.Cu" "B.Cu")
		(net "TPM_PRSNT_N_R")
	)
	(via
		(at 39.28364 -129.5654)
		(size 0.6096)
		(drill 0.3048)
		(layers "F.Cu" "B.Cu")
		(net "TPM_PRSNT_N_R")
	)
	(segment
		(start 39.2938 -129.57556)
		(end 39.28364 -129.5654)
		(width 0.127)
		(layer "B.Cu")
		(net "TPM_PRSNT_N_R")
	)
	(segment
		(start 40.25392 -129.57556)
		(end 39.2938 -129.57556)
		(width 0.127)
		(layer "B.Cu")
		(net "TPM_PRSNT_N_R")
	)
	(segment
		(start 39.1033 -129.38506)
		(end 39.28364 -129.5654)
		(width 0.127)
		(layer "B.Cu")
		(net "TPM_PRSNT_N_R")
	)
	(segment
		(start 39.1033 -129.0574)
		(end 39.1033 -129.38506)
		(width 0.127)
		(layer "B.Cu")
		(net "TPM_PRSNT_N_R")
	)
	(segment
		(start 39.50716 -128.65354)
		(end 39.1033 -129.0574)
		(width 0.127)
		(layer "B.Cu")
		(net "TPM_PRSNT_N_R")
	)
	(segment
		(start 38.937438 -134.89432)
		(end 39.394638 -135.35152)
		(width 0.127)
		(layer "In2.Cu")
		(net "TPM_PRSNT_N_R")
	)
	(segment
		(start 39.394638 -135.35152)
		(end 39.81958 -135.35152)
		(width 0.127)
		(layer "In2.Cu")
		(net "TPM_PRSNT_N_R")
	)
	(segment
		(start 40.02532 -131.81203)
		(end 38.900354 -130.687064)
		(width 0.127)
		(layer "In2.Cu")
		(net "TPM_PRSNT_N_R")
	)
	(segment
		(start 40.02532 -135.14578)
		(end 40.02532 -131.81203)
		(width 0.127)
		(layer "In2.Cu")
		(net "TPM_PRSNT_N_R")
	)
	(segment
		(start 38.900354 -130.687064)
		(end 38.900354 -129.260346)
		(width 0.127)
		(layer "In2.Cu")
		(net "TPM_PRSNT_N_R")
	)
	(segment
		(start 38.900354 -129.260346)
		(end 39.50716 -128.65354)
		(width 0.127)
		(layer "In2.Cu")
		(net "TPM_PRSNT_N_R")
	)
	(segment
		(start 39.81958 -135.35152)
		(end 40.02532 -135.14578)
		(width 0.127)
		(layer "In2.Cu")
		(net "TPM_PRSNT_N_R")
	)
	(segment
		(start 37.907468 -134.89432)
		(end 38.937438 -134.89432)
		(width 0.127)
		(layer "In2.Cu")
		(net "TPM_PRSNT_N_R")
	)
	(segment
		(start 57.3024 -131.78282)
		(end 57.250584 -131.78282)
		(width 0.127)
		(layer "F.Cu")
		(net "RSTBTN_OUT_N_R")
	)
	(segment
		(start 55.7276 -133.6294)
		(end 55.7276 -135.4074)
		(width 0.127)
		(layer "F.Cu")
		(net "RSTBTN_OUT_N_R")
	)
	(segment
		(start 54.117748 -136.9822)
		(end 53.699918 -137.40003)
		(width 0.127)
		(layer "F.Cu")
		(net "RSTBTN_OUT_N_R")
	)
	(segment
		(start 55.7276 -135.4074)
		(end 54.931564 -136.203436)
		(width 0.127)
		(layer "F.Cu")
		(net "RSTBTN_OUT_N_R")
	)
	(segment
		(start 54.931564 -136.203436)
		(end 54.931564 -136.689338)
		(width 0.127)
		(layer "F.Cu")
		(net "RSTBTN_OUT_N_R")
	)
	(segment
		(start 54.638702 -136.9822)
		(end 54.117748 -136.9822)
		(width 0.127)
		(layer "F.Cu")
		(net "RSTBTN_OUT_N_R")
	)
	(segment
		(start 57.250584 -131.78282)
		(end 56.3372 -132.696204)
		(width 0.127)
		(layer "F.Cu")
		(net "RSTBTN_OUT_N_R")
	)
	(segment
		(start 54.931564 -136.689338)
		(end 54.638702 -136.9822)
		(width 0.127)
		(layer "F.Cu")
		(net "RSTBTN_OUT_N_R")
	)
	(segment
		(start 56.3372 -132.696204)
		(end 56.3372 -133.0198)
		(width 0.127)
		(layer "F.Cu")
		(net "RSTBTN_OUT_N_R")
	)
	(segment
		(start 56.3372 -133.0198)
		(end 55.7276 -133.6294)
		(width 0.127)
		(layer "F.Cu")
		(net "RSTBTN_OUT_N_R")
	)
	(via
		(at 56.3372 -133.0198)
		(size 0.6604)
		(drill 0.3302)
		(layers "F.Cu" "B.Cu")
		(net "RSTBTN_OUT_N_R")
	)
	(segment
		(start 81.53654 -63.35014)
		(end 81.6864 -63.5)
		(width 0.127)
		(layer "F.Cu")
		(net "I2C_MEZZ_OOB_SDA")
	)
	(segment
		(start 79.925164 -63.35014)
		(end 81.53654 -63.35014)
		(width 0.127)
		(layer "F.Cu")
		(net "I2C_MEZZ_OOB_SDA")
	)
	(via
		(at 81.6864 -63.5)
		(size 0.508)
		(drill 0.254)
		(layers "F.Cu" "B.Cu")
		(net "I2C_MEZZ_OOB_SDA")
	)
	(via
		(at 73.8886 -160.2486)
		(size 0.508)
		(drill 0.254)
		(layers "F.Cu" "B.Cu")
		(net "I2C_MEZZ_OOB_SDA")
	)
	(via
		(at 86.174326 -103.564182)
		(size 0.6096)
		(drill 0.3048)
		(layers "F.Cu" "B.Cu")
		(net "I2C_MEZZ_OOB_SDA")
	)
	(via
		(at 83.098386 -110.541054)
		(size 0.508)
		(drill 0.254)
		(layers "F.Cu" "B.Cu")
		(net "I2C_MEZZ_OOB_SDA")
	)
	(via
		(at 51.979068 -157.76956)
		(size 0.508)
		(drill 0.254)
		(layers "F.Cu" "B.Cu")
		(net "I2C_MEZZ_OOB_SDA")
	)
	(via
		(at 81.198466 -98.328734)
		(size 0.508)
		(drill 0.254)
		(layers "F.Cu" "B.Cu")
		(net "I2C_MEZZ_OOB_SDA")
	)
	(segment
		(start 83.0961 -110.541054)
		(end 83.0961 -110.5408)
		(width 0.127)
		(layer "B.Cu")
		(net "I2C_MEZZ_OOB_SDA")
	)
	(segment
		(start 51.146964 -158.535624)
		(end 51.30546 -158.69412)
		(width 0.127)
		(layer "B.Cu")
		(net "I2C_MEZZ_OOB_SDA")
	)
	(segment
		(start 81.198466 -98.328734)
		(end 81.198466 -98.394266)
		(width 0.127)
		(layer "B.Cu")
		(net "I2C_MEZZ_OOB_SDA")
	)
	(segment
		(start 86.174326 -103.370126)
		(end 86.174326 -103.564182)
		(width 0.127)
		(layer "B.Cu")
		(net "I2C_MEZZ_OOB_SDA")
	)
	(segment
		(start 51.146964 -157.62986)
		(end 51.839368 -157.62986)
		(width 0.127)
		(layer "B.Cu")
		(net "I2C_MEZZ_OOB_SDA")
	)
	(segment
		(start 51.146964 -157.62986)
		(end 51.146964 -158.535624)
		(width 0.127)
		(layer "B.Cu")
		(net "I2C_MEZZ_OOB_SDA")
	)
	(segment
		(start 83.1596 -110.5408)
		(end 86.174326 -107.526074)
		(width 0.127)
		(layer "B.Cu")
		(net "I2C_MEZZ_OOB_SDA")
	)
	(segment
		(start 81.198466 -98.394266)
		(end 86.174326 -103.370126)
		(width 0.127)
		(layer "B.Cu")
		(net "I2C_MEZZ_OOB_SDA")
	)
	(segment
		(start 83.0961 -110.5408)
		(end 83.1596 -110.5408)
		(width 0.127)
		(layer "B.Cu")
		(net "I2C_MEZZ_OOB_SDA")
	)
	(segment
		(start 51.839368 -157.62986)
		(end 51.979068 -157.76956)
		(width 0.127)
		(layer "B.Cu")
		(net "I2C_MEZZ_OOB_SDA")
	)
	(segment
		(start 83.098386 -110.541054)
		(end 83.0961 -110.541054)
		(width 0.127)
		(layer "B.Cu")
		(net "I2C_MEZZ_OOB_SDA")
	)
	(segment
		(start 86.174326 -107.526074)
		(end 86.174326 -103.564182)
		(width 0.127)
		(layer "B.Cu")
		(net "I2C_MEZZ_OOB_SDA")
	)
	(segment
		(start 82.05724 -111.5822)
		(end 78.712568 -111.5822)
		(width 0.127)
		(layer "In2.Cu")
		(net "I2C_MEZZ_OOB_SDA")
	)
	(segment
		(start 74.670666 -115.6208)
		(end 72.5932 -115.6208)
		(width 0.127)
		(layer "In2.Cu")
		(net "I2C_MEZZ_OOB_SDA")
	)
	(segment
		(start 72.676258 -130.688334)
		(end 72.636126 -130.688334)
		(width 0.127)
		(layer "In2.Cu")
		(net "I2C_MEZZ_OOB_SDA")
	)
	(segment
		(start 75.47102 -154.361896)
		(end 75.47102 -158.606236)
		(width 0.127)
		(layer "In2.Cu")
		(net "I2C_MEZZ_OOB_SDA")
	)
	(segment
		(start 72.5932 -115.6208)
		(end 72.3138 -115.9002)
		(width 0.127)
		(layer "In2.Cu")
		(net "I2C_MEZZ_OOB_SDA")
	)
	(segment
		(start 73.54062 -152.431242)
		(end 74.59599 -153.486612)
		(width 0.127)
		(layer "In2.Cu")
		(net "I2C_MEZZ_OOB_SDA")
	)
	(segment
		(start 78.607666 -111.6838)
		(end 74.670666 -115.6208)
		(width 0.127)
		(layer "In2.Cu")
		(net "I2C_MEZZ_OOB_SDA")
	)
	(segment
		(start 73.374504 -139.20978)
		(end 73.374504 -143.058896)
		(width 0.127)
		(layer "In2.Cu")
		(net "I2C_MEZZ_OOB_SDA")
	)
	(segment
		(start 74.3839 -144.068292)
		(end 74.3839 -145.180558)
		(width 0.127)
		(layer "In2.Cu")
		(net "I2C_MEZZ_OOB_SDA")
	)
	(segment
		(start 83.098386 -110.541054)
		(end 82.05724 -111.5822)
		(width 0.127)
		(layer "In2.Cu")
		(net "I2C_MEZZ_OOB_SDA")
	)
	(segment
		(start 74.3839 -145.180558)
		(end 73.54062 -146.023838)
		(width 0.127)
		(layer "In2.Cu")
		(net "I2C_MEZZ_OOB_SDA")
	)
	(segment
		(start 78.610968 -111.6838)
		(end 78.607666 -111.6838)
		(width 0.127)
		(layer "In2.Cu")
		(net "I2C_MEZZ_OOB_SDA")
	)
	(segment
		(start 72.147938 -137.983214)
		(end 73.374504 -139.20978)
		(width 0.127)
		(layer "In2.Cu")
		(net "I2C_MEZZ_OOB_SDA")
	)
	(segment
		(start 72.3138 -115.9002)
		(end 72.3138 -116.6114)
		(width 0.127)
		(layer "In2.Cu")
		(net "I2C_MEZZ_OOB_SDA")
	)
	(segment
		(start 72.711056 -117.008656)
		(end 72.711056 -125.179074)
		(width 0.127)
		(layer "In2.Cu")
		(net "I2C_MEZZ_OOB_SDA")
	)
	(segment
		(start 72.636126 -130.688334)
		(end 72.147938 -131.176522)
		(width 0.127)
		(layer "In2.Cu")
		(net "I2C_MEZZ_OOB_SDA")
	)
	(segment
		(start 73.54062 -146.023838)
		(end 73.54062 -152.431242)
		(width 0.127)
		(layer "In2.Cu")
		(net "I2C_MEZZ_OOB_SDA")
	)
	(segment
		(start 72.147938 -131.176522)
		(end 72.147938 -137.983214)
		(width 0.127)
		(layer "In2.Cu")
		(net "I2C_MEZZ_OOB_SDA")
	)
	(segment
		(start 73.370948 -129.993644)
		(end 72.676258 -130.688334)
		(width 0.127)
		(layer "In2.Cu")
		(net "I2C_MEZZ_OOB_SDA")
	)
	(segment
		(start 72.711056 -125.179074)
		(end 73.370948 -125.838966)
		(width 0.127)
		(layer "In2.Cu")
		(net "I2C_MEZZ_OOB_SDA")
	)
	(segment
		(start 73.370948 -125.838966)
		(end 73.370948 -129.993644)
		(width 0.127)
		(layer "In2.Cu")
		(net "I2C_MEZZ_OOB_SDA")
	)
	(segment
		(start 72.3138 -116.6114)
		(end 72.711056 -117.008656)
		(width 0.127)
		(layer "In2.Cu")
		(net "I2C_MEZZ_OOB_SDA")
	)
	(segment
		(start 74.59599 -153.486612)
		(end 74.59599 -153.486866)
		(width 0.127)
		(layer "In2.Cu")
		(net "I2C_MEZZ_OOB_SDA")
	)
	(segment
		(start 78.712568 -111.5822)
		(end 78.610968 -111.6838)
		(width 0.127)
		(layer "In2.Cu")
		(net "I2C_MEZZ_OOB_SDA")
	)
	(segment
		(start 74.59599 -153.486866)
		(end 75.47102 -154.361896)
		(width 0.127)
		(layer "In2.Cu")
		(net "I2C_MEZZ_OOB_SDA")
	)
	(segment
		(start 73.374504 -143.058896)
		(end 74.3839 -144.068292)
		(width 0.127)
		(layer "In2.Cu")
		(net "I2C_MEZZ_OOB_SDA")
	)
	(segment
		(start 75.47102 -158.606236)
		(end 73.8886 -160.188656)
		(width 0.127)
		(layer "In2.Cu")
		(net "I2C_MEZZ_OOB_SDA")
	)
	(segment
		(start 73.8886 -160.188656)
		(end 73.8886 -160.2486)
		(width 0.127)
		(layer "In2.Cu")
		(net "I2C_MEZZ_OOB_SDA")
	)
	(segment
		(start 81.1784 -98.308668)
		(end 81.1784 -97.409254)
		(width 0.127)
		(layer "In5.Cu")
		(net "I2C_MEZZ_OOB_SDA")
	)
	(segment
		(start 53.627528 -157.4927)
		(end 52.255928 -157.4927)
		(width 0.127)
		(layer "In5.Cu")
		(net "I2C_MEZZ_OOB_SDA")
	)
	(segment
		(start 54.229508 -157.746954)
		(end 53.881782 -157.746954)
		(width 0.127)
		(layer "In5.Cu")
		(net "I2C_MEZZ_OOB_SDA")
	)
	(segment
		(start 81.198466 -98.328734)
		(end 81.1784 -98.308668)
		(width 0.127)
		(layer "In5.Cu")
		(net "I2C_MEZZ_OOB_SDA")
	)
	(segment
		(start 53.881782 -157.746954)
		(end 53.627528 -157.4927)
		(width 0.127)
		(layer "In5.Cu")
		(net "I2C_MEZZ_OOB_SDA")
	)
	(segment
		(start 73.1266 -161.3662)
		(end 72.3011 -161.3662)
		(width 0.127)
		(layer "In5.Cu")
		(net "I2C_MEZZ_OOB_SDA")
	)
	(segment
		(start 73.6854 -160.8074)
		(end 73.1266 -161.3662)
		(width 0.127)
		(layer "In5.Cu")
		(net "I2C_MEZZ_OOB_SDA")
	)
	(segment
		(start 72.3011 -161.3662)
		(end 71.00824 -162.65906)
		(width 0.127)
		(layer "In5.Cu")
		(net "I2C_MEZZ_OOB_SDA")
	)
	(segment
		(start 67.65798 -162.65906)
		(end 66.5734 -161.57448)
		(width 0.127)
		(layer "In5.Cu")
		(net "I2C_MEZZ_OOB_SDA")
	)
	(segment
		(start 61.81852 -158.87192)
		(end 55.354474 -158.87192)
		(width 0.127)
		(layer "In5.Cu")
		(net "I2C_MEZZ_OOB_SDA")
	)
	(segment
		(start 52.255928 -157.4927)
		(end 51.979068 -157.76956)
		(width 0.127)
		(layer "In5.Cu")
		(net "I2C_MEZZ_OOB_SDA")
	)
	(segment
		(start 73.8886 -160.2486)
		(end 73.6854 -160.4518)
		(width 0.127)
		(layer "In5.Cu")
		(net "I2C_MEZZ_OOB_SDA")
	)
	(segment
		(start 80.606138 -64.580262)
		(end 81.6864 -63.5)
		(width 0.127)
		(layer "In5.Cu")
		(net "I2C_MEZZ_OOB_SDA")
	)
	(segment
		(start 73.6854 -160.4518)
		(end 73.6854 -160.8074)
		(width 0.127)
		(layer "In5.Cu")
		(net "I2C_MEZZ_OOB_SDA")
	)
	(segment
		(start 71.00824 -162.65906)
		(end 67.65798 -162.65906)
		(width 0.127)
		(layer "In5.Cu")
		(net "I2C_MEZZ_OOB_SDA")
	)
	(segment
		(start 66.5734 -161.57448)
		(end 64.942212 -161.57448)
		(width 0.127)
		(layer "In5.Cu")
		(net "I2C_MEZZ_OOB_SDA")
	)
	(segment
		(start 64.521334 -161.574734)
		(end 61.81852 -158.87192)
		(width 0.127)
		(layer "In5.Cu")
		(net "I2C_MEZZ_OOB_SDA")
	)
	(segment
		(start 80.606138 -96.836992)
		(end 80.606138 -64.580262)
		(width 0.127)
		(layer "In5.Cu")
		(net "I2C_MEZZ_OOB_SDA")
	)
	(segment
		(start 55.354474 -158.87192)
		(end 54.229508 -157.746954)
		(width 0.127)
		(layer "In5.Cu")
		(net "I2C_MEZZ_OOB_SDA")
	)
	(segment
		(start 64.942212 -161.57448)
		(end 64.521334 -161.574734)
		(width 0.127)
		(layer "In5.Cu")
		(net "I2C_MEZZ_OOB_SDA")
	)
	(segment
		(start 81.1784 -97.409254)
		(end 80.606138 -96.836992)
		(width 0.127)
		(layer "In5.Cu")
		(net "I2C_MEZZ_OOB_SDA")
	)
	(segment
		(start 81.64576 -62.55004)
		(end 81.7118 -62.484)
		(width 0.127)
		(layer "F.Cu")
		(net "I2C_MEZZ_OOB_SCL")
	)
	(segment
		(start 79.925164 -62.55004)
		(end 81.64576 -62.55004)
		(width 0.127)
		(layer "F.Cu")
		(net "I2C_MEZZ_OOB_SCL")
	)
	(via
		(at 72.9488 -160.6804)
		(size 0.508)
		(drill 0.254)
		(layers "F.Cu" "B.Cu")
		(net "I2C_MEZZ_OOB_SCL")
	)
	(via
		(at 81.7118 -62.484)
		(size 0.508)
		(drill 0.254)
		(layers "F.Cu" "B.Cu")
		(net "I2C_MEZZ_OOB_SCL")
	)
	(via
		(at 82.234786 -110.52683)
		(size 0.508)
		(drill 0.254)
		(layers "F.Cu" "B.Cu")
		(net "I2C_MEZZ_OOB_SCL")
	)
	(via
		(at 80.4926 -97.5614)
		(size 0.508)
		(drill 0.254)
		(layers "F.Cu" "B.Cu")
		(net "I2C_MEZZ_OOB_SCL")
	)
	(via
		(at 52.0192 -156.82976)
		(size 0.508)
		(drill 0.254)
		(layers "F.Cu" "B.Cu")
		(net "I2C_MEZZ_OOB_SCL")
	)
	(via
		(at 84.535264 -108.123228)
		(size 0.6096)
		(drill 0.3048)
		(layers "F.Cu" "B.Cu")
		(net "I2C_MEZZ_OOB_SCL")
	)
	(segment
		(start 52.0192 -156.35224)
		(end 52.0192 -156.82976)
		(width 0.127)
		(layer "B.Cu")
		(net "I2C_MEZZ_OOB_SCL")
	)
	(segment
		(start 82.250534 -110.52683)
		(end 82.250534 -110.5281)
		(width 0.127)
		(layer "B.Cu")
		(net "I2C_MEZZ_OOB_SCL")
	)
	(segment
		(start 51.03876 -155.3718)
		(end 52.0192 -156.35224)
		(width 0.127)
		(layer "B.Cu")
		(net "I2C_MEZZ_OOB_SCL")
	)
	(segment
		(start 85.598 -103.5304)
		(end 85.598 -107.060492)
		(width 0.127)
		(layer "B.Cu")
		(net "I2C_MEZZ_OOB_SCL")
	)
	(segment
		(start 50.038 -154.3304)
		(end 50.74793 -155.04033)
		(width 0.127)
		(layer "B.Cu")
		(net "I2C_MEZZ_OOB_SCL")
	)
	(segment
		(start 82.250534 -110.5281)
		(end 82.2706 -110.508034)
		(width 0.127)
		(layer "B.Cu")
		(net "I2C_MEZZ_OOB_SCL")
	)
	(segment
		(start 80.4926 -97.5614)
		(end 80.4926 -98.425)
		(width 0.127)
		(layer "B.Cu")
		(net "I2C_MEZZ_OOB_SCL")
	)
	(segment
		(start 50.74793 -155.08097)
		(end 51.03876 -155.3718)
		(width 0.127)
		(layer "B.Cu")
		(net "I2C_MEZZ_OOB_SCL")
	)
	(segment
		(start 85.598 -107.060492)
		(end 84.535264 -108.123228)
		(width 0.127)
		(layer "B.Cu")
		(net "I2C_MEZZ_OOB_SCL")
	)
	(segment
		(start 80.4926 -98.425)
		(end 85.598 -103.5304)
		(width 0.127)
		(layer "B.Cu")
		(net "I2C_MEZZ_OOB_SCL")
	)
	(segment
		(start 84.484464 -108.123228)
		(end 84.535264 -108.123228)
		(width 0.127)
		(layer "B.Cu")
		(net "I2C_MEZZ_OOB_SCL")
	)
	(segment
		(start 50.74793 -155.04033)
		(end 50.74793 -155.08097)
		(width 0.127)
		(layer "B.Cu")
		(net "I2C_MEZZ_OOB_SCL")
	)
	(segment
		(start 82.234786 -110.52683)
		(end 82.250534 -110.52683)
		(width 0.127)
		(layer "B.Cu")
		(net "I2C_MEZZ_OOB_SCL")
	)
	(segment
		(start 82.2706 -110.508034)
		(end 82.2706 -110.337092)
		(width 0.127)
		(layer "B.Cu")
		(net "I2C_MEZZ_OOB_SCL")
	)
	(segment
		(start 82.2706 -110.337092)
		(end 84.484464 -108.123228)
		(width 0.127)
		(layer "B.Cu")
		(net "I2C_MEZZ_OOB_SCL")
	)
	(segment
		(start 72.30618 -141.149324)
		(end 72.30618 -142.709138)
		(width 0.127)
		(layer "In2.Cu")
		(net "I2C_MEZZ_OOB_SCL")
	)
	(segment
		(start 74.96302 -154.572462)
		(end 74.96302 -158.39567)
		(width 0.127)
		(layer "In2.Cu")
		(net "I2C_MEZZ_OOB_SCL")
	)
	(segment
		(start 72.30618 -142.709138)
		(end 72.69861 -143.101568)
		(width 0.127)
		(layer "In2.Cu")
		(net "I2C_MEZZ_OOB_SCL")
	)
	(segment
		(start 73.02754 -145.202402)
		(end 73.02754 -152.636728)
		(width 0.127)
		(layer "In2.Cu")
		(net "I2C_MEZZ_OOB_SCL")
	)
	(segment
		(start 73.02754 -152.636728)
		(end 74.08799 -153.697178)
		(width 0.127)
		(layer "In2.Cu")
		(net "I2C_MEZZ_OOB_SCL")
	)
	(segment
		(start 72.862948 -129.783078)
		(end 72.465692 -130.180334)
		(width 0.127)
		(layer "In2.Cu")
		(net "I2C_MEZZ_OOB_SCL")
	)
	(segment
		(start 71.8058 -116.110766)
		(end 71.8058 -116.967)
		(width 0.127)
		(layer "In2.Cu")
		(net "I2C_MEZZ_OOB_SCL")
	)
	(segment
		(start 72.69861 -143.101568)
		(end 72.69861 -144.873472)
		(width 0.127)
		(layer "In2.Cu")
		(net "I2C_MEZZ_OOB_SCL")
	)
	(segment
		(start 72.203056 -125.38964)
		(end 72.862948 -126.049532)
		(width 0.127)
		(layer "In2.Cu")
		(net "I2C_MEZZ_OOB_SCL")
	)
	(segment
		(start 71.639938 -140.482828)
		(end 72.046846 -140.889736)
		(width 0.127)
		(layer "In2.Cu")
		(net "I2C_MEZZ_OOB_SCL")
	)
	(segment
		(start 78.4352 -110.998)
		(end 74.3204 -115.1128)
		(width 0.127)
		(layer "In2.Cu")
		(net "I2C_MEZZ_OOB_SCL")
	)
	(segment
		(start 72.046846 -140.889736)
		(end 72.046846 -140.88999)
		(width 0.127)
		(layer "In2.Cu")
		(net "I2C_MEZZ_OOB_SCL")
	)
	(segment
		(start 72.862948 -126.049532)
		(end 72.862948 -129.783078)
		(width 0.127)
		(layer "In2.Cu")
		(net "I2C_MEZZ_OOB_SCL")
	)
	(segment
		(start 72.42556 -130.180334)
		(end 71.639938 -130.965956)
		(width 0.127)
		(layer "In2.Cu")
		(net "I2C_MEZZ_OOB_SCL")
	)
	(segment
		(start 72.046846 -140.88999)
		(end 72.30618 -141.149324)
		(width 0.127)
		(layer "In2.Cu")
		(net "I2C_MEZZ_OOB_SCL")
	)
	(segment
		(start 81.763616 -110.998)
		(end 78.4352 -110.998)
		(width 0.127)
		(layer "In2.Cu")
		(net "I2C_MEZZ_OOB_SCL")
	)
	(segment
		(start 74.3204 -115.1128)
		(end 72.382634 -115.1128)
		(width 0.127)
		(layer "In2.Cu")
		(net "I2C_MEZZ_OOB_SCL")
	)
	(segment
		(start 71.805546 -115.689888)
		(end 71.805546 -116.110512)
		(width 0.127)
		(layer "In2.Cu")
		(net "I2C_MEZZ_OOB_SCL")
	)
	(segment
		(start 72.465692 -130.180334)
		(end 72.42556 -130.180334)
		(width 0.127)
		(layer "In2.Cu")
		(net "I2C_MEZZ_OOB_SCL")
	)
	(segment
		(start 72.382634 -115.1128)
		(end 71.805546 -115.689888)
		(width 0.127)
		(layer "In2.Cu")
		(net "I2C_MEZZ_OOB_SCL")
	)
	(segment
		(start 74.08799 -153.697432)
		(end 74.96302 -154.572462)
		(width 0.127)
		(layer "In2.Cu")
		(net "I2C_MEZZ_OOB_SCL")
	)
	(segment
		(start 72.69861 -144.873472)
		(end 73.02754 -145.202402)
		(width 0.127)
		(layer "In2.Cu")
		(net "I2C_MEZZ_OOB_SCL")
	)
	(segment
		(start 82.234786 -110.52683)
		(end 81.763616 -110.998)
		(width 0.127)
		(layer "In2.Cu")
		(net "I2C_MEZZ_OOB_SCL")
	)
	(segment
		(start 71.805546 -116.110512)
		(end 71.8058 -116.110766)
		(width 0.127)
		(layer "In2.Cu")
		(net "I2C_MEZZ_OOB_SCL")
	)
	(segment
		(start 72.203056 -117.364256)
		(end 72.203056 -125.38964)
		(width 0.127)
		(layer "In2.Cu")
		(net "I2C_MEZZ_OOB_SCL")
	)
	(segment
		(start 72.9488 -160.40989)
		(end 72.9488 -160.6804)
		(width 0.127)
		(layer "In2.Cu")
		(net "I2C_MEZZ_OOB_SCL")
	)
	(segment
		(start 71.8058 -116.967)
		(end 72.203056 -117.364256)
		(width 0.127)
		(layer "In2.Cu")
		(net "I2C_MEZZ_OOB_SCL")
	)
	(segment
		(start 71.639938 -130.965956)
		(end 71.639938 -140.482828)
		(width 0.127)
		(layer "In2.Cu")
		(net "I2C_MEZZ_OOB_SCL")
	)
	(segment
		(start 74.96302 -158.39567)
		(end 72.9488 -160.40989)
		(width 0.127)
		(layer "In2.Cu")
		(net "I2C_MEZZ_OOB_SCL")
	)
	(segment
		(start 74.08799 -153.697178)
		(end 74.08799 -153.697432)
		(width 0.127)
		(layer "In2.Cu")
		(net "I2C_MEZZ_OOB_SCL")
	)
	(segment
		(start 67.868546 -162.15106)
		(end 66.783712 -161.066226)
		(width 0.127)
		(layer "In5.Cu")
		(net "I2C_MEZZ_OOB_SCL")
	)
	(segment
		(start 72.9488 -160.6804)
		(end 72.136 -160.6804)
		(width 0.127)
		(layer "In5.Cu")
		(net "I2C_MEZZ_OOB_SCL")
	)
	(segment
		(start 80.098138 -97.166938)
		(end 80.098138 -64.097662)
		(width 0.127)
		(layer "In5.Cu")
		(net "I2C_MEZZ_OOB_SCL")
	)
	(segment
		(start 72.136 -160.6804)
		(end 70.66534 -162.15106)
		(width 0.127)
		(layer "In5.Cu")
		(net "I2C_MEZZ_OOB_SCL")
	)
	(segment
		(start 80.4926 -97.5614)
		(end 80.098138 -97.166938)
		(width 0.127)
		(layer "In5.Cu")
		(net "I2C_MEZZ_OOB_SCL")
	)
	(segment
		(start 80.098138 -64.097662)
		(end 81.7118 -62.484)
		(width 0.127)
		(layer "In5.Cu")
		(net "I2C_MEZZ_OOB_SCL")
	)
	(segment
		(start 62.029086 -158.36392)
		(end 56.09082 -158.36392)
		(width 0.127)
		(layer "In5.Cu")
		(net "I2C_MEZZ_OOB_SCL")
	)
	(segment
		(start 52.9209 -156.82976)
		(end 52.0192 -156.82976)
		(width 0.127)
		(layer "In5.Cu")
		(net "I2C_MEZZ_OOB_SCL")
	)
	(segment
		(start 52.935886 -156.844746)
		(end 52.9209 -156.82976)
		(width 0.127)
		(layer "In5.Cu")
		(net "I2C_MEZZ_OOB_SCL")
	)
	(segment
		(start 64.731646 -161.06648)
		(end 62.029086 -158.36392)
		(width 0.127)
		(layer "In5.Cu")
		(net "I2C_MEZZ_OOB_SCL")
	)
	(segment
		(start 53.84419 -156.844746)
		(end 52.935886 -156.844746)
		(width 0.127)
		(layer "In5.Cu")
		(net "I2C_MEZZ_OOB_SCL")
	)
	(segment
		(start 66.363088 -161.066226)
		(end 66.362834 -161.06648)
		(width 0.127)
		(layer "In5.Cu")
		(net "I2C_MEZZ_OOB_SCL")
	)
	(segment
		(start 66.783712 -161.066226)
		(end 66.363088 -161.066226)
		(width 0.127)
		(layer "In5.Cu")
		(net "I2C_MEZZ_OOB_SCL")
	)
	(segment
		(start 56.09082 -158.36392)
		(end 54.534054 -156.807154)
		(width 0.127)
		(layer "In5.Cu")
		(net "I2C_MEZZ_OOB_SCL")
	)
	(segment
		(start 70.66534 -162.15106)
		(end 67.868546 -162.15106)
		(width 0.127)
		(layer "In5.Cu")
		(net "I2C_MEZZ_OOB_SCL")
	)
	(segment
		(start 53.881782 -156.807154)
		(end 53.84419 -156.844746)
		(width 0.127)
		(layer "In5.Cu")
		(net "I2C_MEZZ_OOB_SCL")
	)
	(segment
		(start 54.534054 -156.807154)
		(end 53.881782 -156.807154)
		(width 0.127)
		(layer "In5.Cu")
		(net "I2C_MEZZ_OOB_SCL")
	)
	(segment
		(start 66.362834 -161.06648)
		(end 64.731646 -161.06648)
		(width 0.127)
		(layer "In5.Cu")
		(net "I2C_MEZZ_OOB_SCL")
	)
	(segment
		(start 75.475084 -60.950094)
		(end 77.110336 -60.950094)
		(width 0.127)
		(layer "F.Cu")
		(net "I2C_MEZZ_FRU_SENSOR_SDA")
	)
	(segment
		(start 77.666088 -60.394342)
		(end 77.666088 -60.368942)
		(width 0.127)
		(layer "F.Cu")
		(net "I2C_MEZZ_FRU_SENSOR_SDA")
	)
	(segment
		(start 77.110336 -60.950094)
		(end 77.666088 -60.394342)
		(width 0.127)
		(layer "F.Cu")
		(net "I2C_MEZZ_FRU_SENSOR_SDA")
	)
	(via
		(at 88.970612 -145.365724)
		(size 0.508)
		(drill 0.254)
		(layers "F.Cu" "B.Cu")
		(net "I2C_MEZZ_FRU_SENSOR_SDA")
	)
	(via
		(at 66.3194 -145.1864)
		(size 0.508)
		(drill 0.254)
		(layers "F.Cu" "B.Cu")
		(net "I2C_MEZZ_FRU_SENSOR_SDA")
	)
	(via
		(at 64.3636 -145.1356)
		(size 0.6096)
		(drill 0.3048)
		(layers "F.Cu" "B.Cu")
		(net "I2C_MEZZ_FRU_SENSOR_SDA")
	)
	(via
		(at 77.666088 -60.368942)
		(size 0.508)
		(drill 0.254)
		(layers "F.Cu" "B.Cu")
		(net "I2C_MEZZ_FRU_SENSOR_SDA")
	)
	(via
		(at 90.9066 -114.5032)
		(size 0.508)
		(drill 0.254)
		(layers "F.Cu" "B.Cu")
		(net "I2C_MEZZ_FRU_SENSOR_SDA")
	)
	(segment
		(start 64.73571 -145.441924)
		(end 64.669924 -145.441924)
		(width 0.127)
		(layer "B.Cu")
		(net "I2C_MEZZ_FRU_SENSOR_SDA")
	)
	(segment
		(start 64.669924 -145.441924)
		(end 64.3636 -145.1356)
		(width 0.127)
		(layer "B.Cu")
		(net "I2C_MEZZ_FRU_SENSOR_SDA")
	)
	(segment
		(start 64.3636 -145.1356)
		(end 64.1604 -145.3388)
		(width 0.127)
		(layer "B.Cu")
		(net "I2C_MEZZ_FRU_SENSOR_SDA")
	)
	(segment
		(start 65.73012 -145.77568)
		(end 65.069466 -145.77568)
		(width 0.127)
		(layer "B.Cu")
		(net "I2C_MEZZ_FRU_SENSOR_SDA")
	)
	(segment
		(start 62.286896 -145.034)
		(end 62.551818 -144.769078)
		(width 0.127)
		(layer "B.Cu")
		(net "I2C_MEZZ_FRU_SENSOR_SDA")
	)
	(segment
		(start 66.3194 -145.1864)
		(end 65.73012 -145.77568)
		(width 0.127)
		(layer "B.Cu")
		(net "I2C_MEZZ_FRU_SENSOR_SDA")
	)
	(segment
		(start 61.4807 -145.034)
		(end 62.286896 -145.034)
		(width 0.127)
		(layer "B.Cu")
		(net "I2C_MEZZ_FRU_SENSOR_SDA")
	)
	(segment
		(start 65.069466 -145.77568)
		(end 64.73571 -145.441924)
		(width 0.127)
		(layer "B.Cu")
		(net "I2C_MEZZ_FRU_SENSOR_SDA")
	)
	(segment
		(start 63.12154 -145.3388)
		(end 62.551818 -144.769078)
		(width 0.127)
		(layer "B.Cu")
		(net "I2C_MEZZ_FRU_SENSOR_SDA")
	)
	(segment
		(start 64.1604 -145.3388)
		(end 63.12154 -145.3388)
		(width 0.127)
		(layer "B.Cu")
		(net "I2C_MEZZ_FRU_SENSOR_SDA")
	)
	(segment
		(start 89.989406 -140.290804)
		(end 89.989406 -142.918942)
		(width 0.127)
		(layer "In2.Cu")
		(net "I2C_MEZZ_FRU_SENSOR_SDA")
	)
	(segment
		(start 89.98966 -142.919196)
		(end 89.98966 -143.473424)
		(width 0.127)
		(layer "In2.Cu")
		(net "I2C_MEZZ_FRU_SENSOR_SDA")
	)
	(segment
		(start 90.327226 -138.393424)
		(end 90.327226 -139.952984)
		(width 0.127)
		(layer "In2.Cu")
		(net "I2C_MEZZ_FRU_SENSOR_SDA")
	)
	(segment
		(start 90.2843 -124.392182)
		(end 90.2843 -127.059182)
		(width 0.127)
		(layer "In2.Cu")
		(net "I2C_MEZZ_FRU_SENSOR_SDA")
	)
	(segment
		(start 89.243662 -145.092674)
		(end 88.970612 -145.365724)
		(width 0.127)
		(layer "In2.Cu")
		(net "I2C_MEZZ_FRU_SENSOR_SDA")
	)
	(segment
		(start 90.7923 -137.92835)
		(end 90.327226 -138.393424)
		(width 0.127)
		(layer "In2.Cu")
		(net "I2C_MEZZ_FRU_SENSOR_SDA")
	)
	(segment
		(start 90.551 -116.0526)
		(end 90.551 -124.125482)
		(width 0.127)
		(layer "In2.Cu")
		(net "I2C_MEZZ_FRU_SENSOR_SDA")
	)
	(segment
		(start 89.243662 -144.219422)
		(end 89.243662 -145.092674)
		(width 0.127)
		(layer "In2.Cu")
		(net "I2C_MEZZ_FRU_SENSOR_SDA")
	)
	(segment
		(start 90.2843 -127.059182)
		(end 90.7415 -127.516382)
		(width 0.127)
		(layer "In2.Cu")
		(net "I2C_MEZZ_FRU_SENSOR_SDA")
	)
	(segment
		(start 90.7923 -135.977884)
		(end 90.7923 -137.92835)
		(width 0.127)
		(layer "In2.Cu")
		(net "I2C_MEZZ_FRU_SENSOR_SDA")
	)
	(segment
		(start 90.551 -124.125482)
		(end 90.2843 -124.392182)
		(width 0.127)
		(layer "In2.Cu")
		(net "I2C_MEZZ_FRU_SENSOR_SDA")
	)
	(segment
		(start 90.7415 -127.516382)
		(end 90.7415 -135.927084)
		(width 0.127)
		(layer "In2.Cu")
		(net "I2C_MEZZ_FRU_SENSOR_SDA")
	)
	(segment
		(start 90.9066 -114.5032)
		(end 90.9066 -115.697)
		(width 0.127)
		(layer "In2.Cu")
		(net "I2C_MEZZ_FRU_SENSOR_SDA")
	)
	(segment
		(start 89.989406 -142.918942)
		(end 89.98966 -142.919196)
		(width 0.127)
		(layer "In2.Cu")
		(net "I2C_MEZZ_FRU_SENSOR_SDA")
	)
	(segment
		(start 90.327226 -139.952984)
		(end 89.989406 -140.290804)
		(width 0.127)
		(layer "In2.Cu")
		(net "I2C_MEZZ_FRU_SENSOR_SDA")
	)
	(segment
		(start 90.7415 -135.927084)
		(end 90.7923 -135.977884)
		(width 0.127)
		(layer "In2.Cu")
		(net "I2C_MEZZ_FRU_SENSOR_SDA")
	)
	(segment
		(start 89.98966 -143.473424)
		(end 89.243662 -144.219422)
		(width 0.127)
		(layer "In2.Cu")
		(net "I2C_MEZZ_FRU_SENSOR_SDA")
	)
	(segment
		(start 90.9066 -115.697)
		(end 90.551 -116.0526)
		(width 0.127)
		(layer "In2.Cu")
		(net "I2C_MEZZ_FRU_SENSOR_SDA")
	)
	(segment
		(start 67.18681 -145.788126)
		(end 66.62039 -145.221706)
		(width 0.127)
		(layer "In5.Cu")
		(net "I2C_MEZZ_FRU_SENSOR_SDA")
	)
	(segment
		(start 87.525606 -145.348452)
		(end 86.876128 -145.99793)
		(width 0.127)
		(layer "In5.Cu")
		(net "I2C_MEZZ_FRU_SENSOR_SDA")
	)
	(segment
		(start 86.876128 -145.99793)
		(end 73.12406 -145.99793)
		(width 0.127)
		(layer "In5.Cu")
		(net "I2C_MEZZ_FRU_SENSOR_SDA")
	)
	(segment
		(start 87.52586 -145.154142)
		(end 87.525606 -145.348452)
		(width 0.127)
		(layer "In5.Cu")
		(net "I2C_MEZZ_FRU_SENSOR_SDA")
	)
	(segment
		(start 76.525628 -99.216464)
		(end 76.525628 -61.509402)
		(width 0.127)
		(layer "In5.Cu")
		(net "I2C_MEZZ_FRU_SENSOR_SDA")
	)
	(segment
		(start 88.970612 -145.365724)
		(end 88.445848 -144.84096)
		(width 0.127)
		(layer "In5.Cu")
		(net "I2C_MEZZ_FRU_SENSOR_SDA")
	)
	(segment
		(start 90.9066 -109.420914)
		(end 81.977738 -100.492052)
		(width 0.127)
		(layer "In5.Cu")
		(net "I2C_MEZZ_FRU_SENSOR_SDA")
	)
	(segment
		(start 88.445848 -144.84096)
		(end 87.839042 -144.84096)
		(width 0.127)
		(layer "In5.Cu")
		(net "I2C_MEZZ_FRU_SENSOR_SDA")
	)
	(segment
		(start 87.839042 -144.84096)
		(end 87.52586 -145.154142)
		(width 0.127)
		(layer "In5.Cu")
		(net "I2C_MEZZ_FRU_SENSOR_SDA")
	)
	(segment
		(start 77.801216 -100.492052)
		(end 76.525628 -99.216464)
		(width 0.127)
		(layer "In5.Cu")
		(net "I2C_MEZZ_FRU_SENSOR_SDA")
	)
	(segment
		(start 73.12406 -145.99793)
		(end 72.914256 -145.788126)
		(width 0.127)
		(layer "In5.Cu")
		(net "I2C_MEZZ_FRU_SENSOR_SDA")
	)
	(segment
		(start 81.977738 -100.492052)
		(end 77.801216 -100.492052)
		(width 0.127)
		(layer "In5.Cu")
		(net "I2C_MEZZ_FRU_SENSOR_SDA")
	)
	(segment
		(start 90.9066 -114.5032)
		(end 90.9066 -109.420914)
		(width 0.127)
		(layer "In5.Cu")
		(net "I2C_MEZZ_FRU_SENSOR_SDA")
	)
	(segment
		(start 66.354706 -145.221706)
		(end 66.3194 -145.1864)
		(width 0.127)
		(layer "In5.Cu")
		(net "I2C_MEZZ_FRU_SENSOR_SDA")
	)
	(segment
		(start 66.62039 -145.221706)
		(end 66.354706 -145.221706)
		(width 0.127)
		(layer "In5.Cu")
		(net "I2C_MEZZ_FRU_SENSOR_SDA")
	)
	(segment
		(start 76.525628 -61.509402)
		(end 77.666088 -60.368942)
		(width 0.127)
		(layer "In5.Cu")
		(net "I2C_MEZZ_FRU_SENSOR_SDA")
	)
	(segment
		(start 72.914256 -145.788126)
		(end 67.18681 -145.788126)
		(width 0.127)
		(layer "In5.Cu")
		(net "I2C_MEZZ_FRU_SENSOR_SDA")
	)
	(segment
		(start 75.475084 -60.149994)
		(end 77.04963 -60.149994)
		(width 0.127)
		(layer "F.Cu")
		(net "I2C_MEZZ_FRU_SENSOR_SCL")
	)
	(segment
		(start 77.04963 -60.149994)
		(end 77.694028 -59.505596)
		(width 0.127)
		(layer "F.Cu")
		(net "I2C_MEZZ_FRU_SENSOR_SCL")
	)
	(via
		(at 62.738 -145.940018)
		(size 0.6096)
		(drill 0.3048)
		(layers "F.Cu" "B.Cu")
		(net "I2C_MEZZ_FRU_SENSOR_SCL")
	)
	(via
		(at 88.03386 -145.31086)
		(size 0.508)
		(drill 0.254)
		(layers "F.Cu" "B.Cu")
		(net "I2C_MEZZ_FRU_SENSOR_SCL")
	)
	(via
		(at 90.2716 -115.2652)
		(size 0.508)
		(drill 0.254)
		(layers "F.Cu" "B.Cu")
		(net "I2C_MEZZ_FRU_SENSOR_SCL")
	)
	(via
		(at 77.694028 -59.505596)
		(size 0.508)
		(drill 0.254)
		(layers "F.Cu" "B.Cu")
		(net "I2C_MEZZ_FRU_SENSOR_SCL")
	)
	(via
		(at 64.643 -146.06778)
		(size 0.508)
		(drill 0.254)
		(layers "F.Cu" "B.Cu")
		(net "I2C_MEZZ_FRU_SENSOR_SCL")
	)
	(segment
		(start 61.916818 -147.083018)
		(end 62.555628 -147.083018)
		(width 0.127)
		(layer "B.Cu")
		(net "I2C_MEZZ_FRU_SENSOR_SCL")
	)
	(segment
		(start 62.738 -145.940018)
		(end 62.738 -146.900646)
		(width 0.127)
		(layer "B.Cu")
		(net "I2C_MEZZ_FRU_SENSOR_SCL")
	)
	(segment
		(start 61.4807 -146.0754)
		(end 61.4807 -146.6469)
		(width 0.127)
		(layer "B.Cu")
		(net "I2C_MEZZ_FRU_SENSOR_SCL")
	)
	(segment
		(start 64.643 -146.06778)
		(end 64.515238 -145.940018)
		(width 0.127)
		(layer "B.Cu")
		(net "I2C_MEZZ_FRU_SENSOR_SCL")
	)
	(segment
		(start 62.738 -146.900646)
		(end 62.555628 -147.083018)
		(width 0.127)
		(layer "B.Cu")
		(net "I2C_MEZZ_FRU_SENSOR_SCL")
	)
	(segment
		(start 61.4807 -146.6469)
		(end 61.916818 -147.083018)
		(width 0.127)
		(layer "B.Cu")
		(net "I2C_MEZZ_FRU_SENSOR_SCL")
	)
	(segment
		(start 64.515238 -145.940018)
		(end 62.738 -145.940018)
		(width 0.127)
		(layer "B.Cu")
		(net "I2C_MEZZ_FRU_SENSOR_SCL")
	)
	(segment
		(start 90.2843 -136.18845)
		(end 90.2843 -137.717784)
		(width 0.127)
		(layer "In2.Cu")
		(net "I2C_MEZZ_FRU_SENSOR_SCL")
	)
	(segment
		(start 89.481406 -143.263112)
		(end 88.626188 -144.11833)
		(width 0.127)
		(layer "In2.Cu")
		(net "I2C_MEZZ_FRU_SENSOR_SCL")
	)
	(segment
		(start 89.819226 -138.182858)
		(end 89.819226 -139.742418)
		(width 0.127)
		(layer "In2.Cu")
		(net "I2C_MEZZ_FRU_SENSOR_SCL")
	)
	(segment
		(start 90.043 -115.4684)
		(end 90.043 -123.914916)
		(width 0.127)
		(layer "In2.Cu")
		(net "I2C_MEZZ_FRU_SENSOR_SCL")
	)
	(segment
		(start 90.2081 -136.11225)
		(end 90.2843 -136.18845)
		(width 0.127)
		(layer "In2.Cu")
		(net "I2C_MEZZ_FRU_SENSOR_SCL")
	)
	(segment
		(start 90.043 -123.914916)
		(end 89.7763 -124.181616)
		(width 0.127)
		(layer "In2.Cu")
		(net "I2C_MEZZ_FRU_SENSOR_SCL")
	)
	(segment
		(start 88.626188 -144.718532)
		(end 88.03386 -145.31086)
		(width 0.127)
		(layer "In2.Cu")
		(net "I2C_MEZZ_FRU_SENSOR_SCL")
	)
	(segment
		(start 90.2081 -131.78282)
		(end 90.2081 -136.11225)
		(width 0.127)
		(layer "In2.Cu")
		(net "I2C_MEZZ_FRU_SENSOR_SCL")
	)
	(segment
		(start 90.2716 -115.2652)
		(end 90.2716 -115.2398)
		(width 0.127)
		(layer "In2.Cu")
		(net "I2C_MEZZ_FRU_SENSOR_SCL")
	)
	(segment
		(start 90.2843 -137.717784)
		(end 89.819226 -138.182858)
		(width 0.127)
		(layer "In2.Cu")
		(net "I2C_MEZZ_FRU_SENSOR_SCL")
	)
	(segment
		(start 90.2716 -115.2398)
		(end 90.043 -115.4684)
		(width 0.127)
		(layer "In2.Cu")
		(net "I2C_MEZZ_FRU_SENSOR_SCL")
	)
	(segment
		(start 89.819226 -139.742418)
		(end 89.481406 -140.080238)
		(width 0.127)
		(layer "In2.Cu")
		(net "I2C_MEZZ_FRU_SENSOR_SCL")
	)
	(segment
		(start 89.7763 -124.181616)
		(end 89.7763 -131.35102)
		(width 0.127)
		(layer "In2.Cu")
		(net "I2C_MEZZ_FRU_SENSOR_SCL")
	)
	(segment
		(start 88.626188 -144.11833)
		(end 88.626188 -144.718532)
		(width 0.127)
		(layer "In2.Cu")
		(net "I2C_MEZZ_FRU_SENSOR_SCL")
	)
	(segment
		(start 89.7763 -131.35102)
		(end 90.2081 -131.78282)
		(width 0.127)
		(layer "In2.Cu")
		(net "I2C_MEZZ_FRU_SENSOR_SCL")
	)
	(segment
		(start 89.481406 -140.080238)
		(end 89.481406 -143.263112)
		(width 0.127)
		(layer "In2.Cu")
		(net "I2C_MEZZ_FRU_SENSOR_SCL")
	)
	(segment
		(start 72.70369 -146.296126)
		(end 73.789794 -147.38223)
		(width 0.127)
		(layer "In5.Cu")
		(net "I2C_MEZZ_FRU_SENSOR_SCL")
	)
	(segment
		(start 81.767172 -101.000052)
		(end 77.59065 -101.000052)
		(width 0.127)
		(layer "In5.Cu")
		(net "I2C_MEZZ_FRU_SENSOR_SCL")
	)
	(segment
		(start 66.976244 -146.296126)
		(end 72.70369 -146.296126)
		(width 0.127)
		(layer "In5.Cu")
		(net "I2C_MEZZ_FRU_SENSOR_SCL")
	)
	(segment
		(start 88.03386 -145.558764)
		(end 88.03386 -145.31086)
		(width 0.127)
		(layer "In5.Cu")
		(net "I2C_MEZZ_FRU_SENSOR_SCL")
	)
	(segment
		(start 64.77508 -145.9357)
		(end 66.615818 -145.9357)
		(width 0.127)
		(layer "In5.Cu")
		(net "I2C_MEZZ_FRU_SENSOR_SCL")
	)
	(segment
		(start 76.017628 -61.181996)
		(end 77.694028 -59.505596)
		(width 0.127)
		(layer "In5.Cu")
		(net "I2C_MEZZ_FRU_SENSOR_SCL")
	)
	(segment
		(start 90.2716 -115.2652)
		(end 90.2716 -109.50448)
		(width 0.127)
		(layer "In5.Cu")
		(net "I2C_MEZZ_FRU_SENSOR_SCL")
	)
	(segment
		(start 76.017628 -99.42703)
		(end 76.017628 -61.181996)
		(width 0.127)
		(layer "In5.Cu")
		(net "I2C_MEZZ_FRU_SENSOR_SCL")
	)
	(segment
		(start 90.2716 -109.50448)
		(end 81.767172 -101.000052)
		(width 0.127)
		(layer "In5.Cu")
		(net "I2C_MEZZ_FRU_SENSOR_SCL")
	)
	(segment
		(start 64.643 -146.06778)
		(end 64.77508 -145.9357)
		(width 0.127)
		(layer "In5.Cu")
		(net "I2C_MEZZ_FRU_SENSOR_SCL")
	)
	(segment
		(start 75.557634 -147.38223)
		(end 76.433934 -146.50593)
		(width 0.127)
		(layer "In5.Cu")
		(net "I2C_MEZZ_FRU_SENSOR_SCL")
	)
	(segment
		(start 66.615818 -145.9357)
		(end 66.976244 -146.296126)
		(width 0.127)
		(layer "In5.Cu")
		(net "I2C_MEZZ_FRU_SENSOR_SCL")
	)
	(segment
		(start 87.086694 -146.50593)
		(end 88.03386 -145.558764)
		(width 0.127)
		(layer "In5.Cu")
		(net "I2C_MEZZ_FRU_SENSOR_SCL")
	)
	(segment
		(start 76.433934 -146.50593)
		(end 87.086694 -146.50593)
		(width 0.127)
		(layer "In5.Cu")
		(net "I2C_MEZZ_FRU_SENSOR_SCL")
	)
	(segment
		(start 73.789794 -147.38223)
		(end 75.557634 -147.38223)
		(width 0.127)
		(layer "In5.Cu")
		(net "I2C_MEZZ_FRU_SENSOR_SCL")
	)
	(segment
		(start 77.59065 -101.000052)
		(end 76.017628 -99.42703)
		(width 0.127)
		(layer "In5.Cu")
		(net "I2C_MEZZ_FRU_SENSOR_SCL")
	)
	(segment
		(start 64.0715 -163.488624)
		(end 64.132968 -163.427156)
		(width 0.127)
		(layer "F.Cu")
		(net "FM_TPM_PRSNT_RST_N_R")
	)
	(segment
		(start 64.238124 -163.322)
		(end 64.132968 -163.427156)
		(width 0.127)
		(layer "F.Cu")
		(net "FM_TPM_PRSNT_RST_N_R")
	)
	(segment
		(start 64.0715 -164.75075)
		(end 64.0715 -163.488624)
		(width 0.127)
		(layer "F.Cu")
		(net "FM_TPM_PRSNT_RST_N_R")
	)
	(segment
		(start 65.5955 -163.322)
		(end 64.238124 -163.322)
		(width 0.127)
		(layer "F.Cu")
		(net "FM_TPM_PRSNT_RST_N_R")
	)
	(via
		(at 64.132968 -163.427156)
		(size 0.6604)
		(drill 0.3302)
		(layers "F.Cu" "B.Cu")
		(net "FM_TPM_PRSNT_RST_N_R")
	)
	(segment
		(start 63.8302 -172.5041)
		(end 63.9826 -172.6565)
		(width 0.127)
		(layer "F.Cu")
		(net "FM_TPM_PRSNT_RST_N_C")
	)
	(segment
		(start 62.724538 -173.361096)
		(end 62.476634 -173.609)
		(width 0.127)
		(layer "F.Cu")
		(net "FM_TPM_PRSNT_RST_N_C")
	)
	(segment
		(start 63.9826 -173.131988)
		(end 63.753492 -173.361096)
		(width 0.127)
		(layer "F.Cu")
		(net "FM_TPM_PRSNT_RST_N_C")
	)
	(segment
		(start 61.6966 -172.5041)
		(end 62.8396 -172.5041)
		(width 0.127)
		(layer "F.Cu")
		(net "FM_TPM_PRSNT_RST_N_C")
	)
	(segment
		(start 63.753492 -173.361096)
		(end 62.724538 -173.361096)
		(width 0.127)
		(layer "F.Cu")
		(net "FM_TPM_PRSNT_RST_N_C")
	)
	(segment
		(start 63.9826 -172.6565)
		(end 63.9826 -173.131988)
		(width 0.127)
		(layer "F.Cu")
		(net "FM_TPM_PRSNT_RST_N_C")
	)
	(segment
		(start 62.476634 -173.609)
		(end 62.476634 -174.313596)
		(width 0.127)
		(layer "F.Cu")
		(net "FM_TPM_PRSNT_RST_N_C")
	)
	(segment
		(start 62.8396 -172.5041)
		(end 63.8302 -172.5041)
		(width 0.127)
		(layer "F.Cu")
		(net "FM_TPM_PRSNT_RST_N_C")
	)
	(via
		(at 62.8396 -172.5041)
		(size 0.6604)
		(drill 0.3302)
		(layers "F.Cu" "B.Cu")
		(net "FM_TPM_PRSNT_RST_N_C")
	)
	(segment
		(start 66.82486 -182.566818)
		(end 64.918844 -182.566818)
		(width 0.127)
		(layer "F.Cu")
		(net "FM_TPM_PRSNT_RST_N")
	)
	(segment
		(start 61.3791 -171.6151)
		(end 60.8076 -172.1866)
		(width 0.127)
		(layer "F.Cu")
		(net "FM_TPM_PRSNT_RST_N")
	)
	(segment
		(start 67.410584 -178.664616)
		(end 67.410584 -179.90058)
		(width 0.127)
		(layer "F.Cu")
		(net "FM_TPM_PRSNT_RST_N")
	)
	(segment
		(start 67.6402 -175.913796)
		(end 66.926714 -175.913796)
		(width 0.127)
		(layer "F.Cu")
		(net "FM_TPM_PRSNT_RST_N")
	)
	(segment
		(start 58.187844 -177.1777)
		(end 54.2163 -177.1777)
		(width 0.127)
		(layer "F.Cu")
		(net "FM_TPM_PRSNT_RST_N")
	)
	(segment
		(start 61.468 -166.7256)
		(end 61.3791 -166.7256)
		(width 0.127)
		(layer "F.Cu")
		(net "FM_TPM_PRSNT_RST_N")
	)
	(segment
		(start 67.9069 -181.484778)
		(end 66.82486 -182.566818)
		(width 0.127)
		(layer "F.Cu")
		(net "FM_TPM_PRSNT_RST_N")
	)
	(segment
		(start 60.66536 -167.7289)
		(end 60.66536 -167.43934)
		(width 0.127)
		(layer "F.Cu")
		(net "FM_TPM_PRSNT_RST_N")
	)
	(segment
		(start 60.689744 -169.397426)
		(end 60.258706 -169.397426)
		(width 0.127)
		(layer "F.Cu")
		(net "FM_TPM_PRSNT_RST_N")
	)
	(segment
		(start 66.4845 -163.322)
		(end 66.4845 -162.9283)
		(width 0.127)
		(layer "F.Cu")
		(net "FM_TPM_PRSNT_RST_N")
	)
	(segment
		(start 59.97194 -168.42232)
		(end 60.66536 -167.7289)
		(width 0.127)
		(layer "F.Cu")
		(net "FM_TPM_PRSNT_RST_N")
	)
	(segment
		(start 67.410584 -179.90058)
		(end 67.9069 -180.396896)
		(width 0.127)
		(layer "F.Cu")
		(net "FM_TPM_PRSNT_RST_N")
	)
	(segment
		(start 66.926714 -176.730914)
		(end 67.728846 -177.533046)
		(width 0.127)
		(layer "F.Cu")
		(net "FM_TPM_PRSNT_RST_N")
	)
	(segment
		(start 63.635128 -181.283102)
		(end 62.293246 -181.283102)
		(width 0.127)
		(layer "F.Cu")
		(net "FM_TPM_PRSNT_RST_N")
	)
	(segment
		(start 61.3791 -166.7256)
		(end 60.6933 -167.4114)
		(width 0.127)
		(layer "F.Cu")
		(net "FM_TPM_PRSNT_RST_N")
	)
	(segment
		(start 66.926714 -175.913796)
		(end 66.926714 -176.730914)
		(width 0.127)
		(layer "F.Cu")
		(net "FM_TPM_PRSNT_RST_N")
	)
	(segment
		(start 60.66536 -167.43934)
		(end 60.6933 -167.4114)
		(width 0.127)
		(layer "F.Cu")
		(net "FM_TPM_PRSNT_RST_N")
	)
	(segment
		(start 64.918844 -182.566818)
		(end 63.635128 -181.283102)
		(width 0.127)
		(layer "F.Cu")
		(net "FM_TPM_PRSNT_RST_N")
	)
	(segment
		(start 67.728846 -178.346354)
		(end 67.410584 -178.664616)
		(width 0.127)
		(layer "F.Cu")
		(net "FM_TPM_PRSNT_RST_N")
	)
	(segment
		(start 59.97194 -169.11066)
		(end 59.97194 -168.42232)
		(width 0.127)
		(layer "F.Cu")
		(net "FM_TPM_PRSNT_RST_N")
	)
	(segment
		(start 67.9069 -180.396896)
		(end 67.9069 -181.484778)
		(width 0.127)
		(layer "F.Cu")
		(net "FM_TPM_PRSNT_RST_N")
	)
	(segment
		(start 60.258706 -169.397426)
		(end 59.97194 -169.11066)
		(width 0.127)
		(layer "F.Cu")
		(net "FM_TPM_PRSNT_RST_N")
	)
	(segment
		(start 62.1665 -169.291)
		(end 62.1665 -171.1452)
		(width 0.127)
		(layer "F.Cu")
		(net "FM_TPM_PRSNT_RST_N")
	)
	(segment
		(start 67.728846 -177.533046)
		(end 67.728846 -178.346354)
		(width 0.127)
		(layer "F.Cu")
		(net "FM_TPM_PRSNT_RST_N")
	)
	(segment
		(start 62.1665 -169.291)
		(end 60.79617 -169.291)
		(width 0.127)
		(layer "F.Cu")
		(net "FM_TPM_PRSNT_RST_N")
	)
	(segment
		(start 65.983358 -162.427158)
		(end 65.983358 -162.273742)
		(width 0.127)
		(layer "F.Cu")
		(net "FM_TPM_PRSNT_RST_N")
	)
	(segment
		(start 61.6966 -171.6151)
		(end 61.3791 -171.6151)
		(width 0.127)
		(layer "F.Cu")
		(net "FM_TPM_PRSNT_RST_N")
	)
	(segment
		(start 62.1665 -171.1452)
		(end 61.6966 -171.6151)
		(width 0.127)
		(layer "F.Cu")
		(net "FM_TPM_PRSNT_RST_N")
	)
	(segment
		(start 60.79617 -169.291)
		(end 60.689744 -169.397426)
		(width 0.127)
		(layer "F.Cu")
		(net "FM_TPM_PRSNT_RST_N")
	)
	(segment
		(start 53.280056 -176.241456)
		(end 53.280056 -174.994824)
		(width 0.127)
		(layer "F.Cu")
		(net "FM_TPM_PRSNT_RST_N")
	)
	(segment
		(start 54.2163 -177.1777)
		(end 53.280056 -176.241456)
		(width 0.127)
		(layer "F.Cu")
		(net "FM_TPM_PRSNT_RST_N")
	)
	(segment
		(start 66.4845 -162.9283)
		(end 65.983358 -162.427158)
		(width 0.127)
		(layer "F.Cu")
		(net "FM_TPM_PRSNT_RST_N")
	)
	(segment
		(start 62.293246 -181.283102)
		(end 58.187844 -177.1777)
		(width 0.127)
		(layer "F.Cu")
		(net "FM_TPM_PRSNT_RST_N")
	)
	(via
		(at 60.8076 -172.1866)
		(size 0.508)
		(drill 0.254)
		(layers "F.Cu" "B.Cu")
		(net "FM_TPM_PRSNT_RST_N")
	)
	(via
		(at 65.983358 -162.273742)
		(size 0.508)
		(drill 0.254)
		(layers "F.Cu" "B.Cu")
		(net "FM_TPM_PRSNT_RST_N")
	)
	(via
		(at 61.468 -166.7256)
		(size 0.508)
		(drill 0.254)
		(layers "F.Cu" "B.Cu")
		(net "FM_TPM_PRSNT_RST_N")
	)
	(via
		(at 67.9069 -180.396896)
		(size 0.6604)
		(drill 0.3302)
		(layers "F.Cu" "B.Cu")
		(net "FM_TPM_PRSNT_RST_N")
	)
	(via
		(at 67.6402 -175.913796)
		(size 0.508)
		(drill 0.254)
		(layers "F.Cu" "B.Cu")
		(net "FM_TPM_PRSNT_RST_N")
	)
	(segment
		(start 61.468 -166.7256)
		(end 65.821052 -162.372548)
		(width 0.127)
		(layer "B.Cu")
		(net "FM_TPM_PRSNT_RST_N")
	)
	(segment
		(start 65.821052 -162.372548)
		(end 65.884552 -162.372548)
		(width 0.127)
		(layer "B.Cu")
		(net "FM_TPM_PRSNT_RST_N")
	)
	(segment
		(start 65.884552 -162.372548)
		(end 65.983358 -162.273742)
		(width 0.127)
		(layer "B.Cu")
		(net "FM_TPM_PRSNT_RST_N")
	)
	(segment
		(start 60.8076 -172.1866)
		(end 62.1665 -173.5455)
		(width 0.127)
		(layer "In2.Cu")
		(net "FM_TPM_PRSNT_RST_N")
	)
	(segment
		(start 62.1665 -173.5455)
		(end 65.271904 -173.5455)
		(width 0.127)
		(layer "In2.Cu")
		(net "FM_TPM_PRSNT_RST_N")
	)
	(segment
		(start 65.271904 -173.5455)
		(end 67.6402 -175.913796)
		(width 0.127)
		(layer "In2.Cu")
		(net "FM_TPM_PRSNT_RST_N")
	)
	(segment
		(start 64.365378 -166.14775)
		(end 64.721994 -166.14775)
		(width 0.127)
		(layer "F.Cu")
		(net "FM_TPM_PRSNT_RST")
	)
	(segment
		(start 65.293494 -166.71925)
		(end 65.9765 -166.71925)
		(width 0.127)
		(layer "F.Cu")
		(net "FM_TPM_PRSNT_RST")
	)
	(segment
		(start 64.721994 -166.14775)
		(end 65.293494 -166.71925)
		(width 0.127)
		(layer "F.Cu")
		(net "FM_TPM_PRSNT_RST")
	)
	(segment
		(start 61.8236 -163.3093)
		(end 62.8396 -163.3093)
		(width 0.127)
		(layer "F.Cu")
		(net "FM_TPM_PRSNT_RST")
	)
	(segment
		(start 61.2902 -163.3093)
		(end 61.8236 -163.3093)
		(width 0.127)
		(layer "F.Cu")
		(net "FM_TPM_PRSNT_RST")
	)
	(segment
		(start 63.104014 -164.886386)
		(end 64.365378 -166.14775)
		(width 0.127)
		(layer "F.Cu")
		(net "FM_TPM_PRSNT_RST")
	)
	(segment
		(start 62.1665 -165.735)
		(end 61.9633 -165.9382)
		(width 0.127)
		(layer "F.Cu")
		(net "FM_TPM_PRSNT_RST")
	)
	(segment
		(start 63.104014 -163.573714)
		(end 63.104014 -164.886386)
		(width 0.127)
		(layer "F.Cu")
		(net "FM_TPM_PRSNT_RST")
	)
	(segment
		(start 61.1251 -165.9382)
		(end 60.6933 -165.5064)
		(width 0.127)
		(layer "F.Cu")
		(net "FM_TPM_PRSNT_RST")
	)
	(segment
		(start 60.6933 -165.5064)
		(end 60.6552 -165.4683)
		(width 0.127)
		(layer "F.Cu")
		(net "FM_TPM_PRSNT_RST")
	)
	(segment
		(start 60.6552 -165.4683)
		(end 60.6552 -163.9443)
		(width 0.127)
		(layer "F.Cu")
		(net "FM_TPM_PRSNT_RST")
	)
	(segment
		(start 60.6552 -163.9443)
		(end 61.2902 -163.3093)
		(width 0.127)
		(layer "F.Cu")
		(net "FM_TPM_PRSNT_RST")
	)
	(segment
		(start 62.8396 -163.3093)
		(end 63.104014 -163.573714)
		(width 0.127)
		(layer "F.Cu")
		(net "FM_TPM_PRSNT_RST")
	)
	(segment
		(start 61.9633 -165.9382)
		(end 61.1251 -165.9382)
		(width 0.127)
		(layer "F.Cu")
		(net "FM_TPM_PRSNT_RST")
	)
	(via
		(at 60.6933 -165.5064)
		(size 0.6604)
		(drill 0.3302)
		(layers "F.Cu" "B.Cu")
		(net "FM_TPM_PRSNT_RST")
	)
	(segment
		(start 65.659 -174.23003)
		(end 65.626234 -174.262796)
		(width 0.127)
		(layer "F.Cu")
		(net "FM_TPM_PRSNT_N")
	)
	(segment
		(start 65.659 -172.5295)
		(end 65.659 -174.23003)
		(width 0.127)
		(layer "F.Cu")
		(net "FM_TPM_PRSNT_N")
	)
	(segment
		(start 65.2526 -172.5295)
		(end 65.659 -172.5295)
		(width 0.127)
		(layer "F.Cu")
		(net "FM_TPM_PRSNT_N")
	)
	(segment
		(start 64.8208 -172.9613)
		(end 65.2526 -172.5295)
		(width 0.127)
		(layer "F.Cu")
		(net "FM_TPM_PRSNT_N")
	)
	(via
		(at 64.8208 -172.9613)
		(size 0.508)
		(drill 0.254)
		(layers "F.Cu" "B.Cu")
		(net "FM_TPM_PRSNT_N")
	)
	(via
		(at 9.7917 -156.9593)
		(size 0.508)
		(drill 0.254)
		(layers "F.Cu" "B.Cu")
		(net "FM_TPM_PRSNT_N")
	)
	(via
		(at 40.50792 -128.67386)
		(size 0.508)
		(drill 0.254)
		(layers "F.Cu" "B.Cu")
		(net "FM_TPM_PRSNT_N")
	)
	(via
		(at 46.0502 -172.4914)
		(size 0.508)
		(drill 0.254)
		(layers "F.Cu" "B.Cu")
		(net "FM_TPM_PRSNT_N")
	)
	(via
		(at 12.5984 -125.9967)
		(size 0.508)
		(drill 0.254)
		(layers "F.Cu" "B.Cu")
		(net "FM_TPM_PRSNT_N")
	)
	(via
		(at 63.26886 -171.859194)
		(size 0.6096)
		(drill 0.3048)
		(layers "F.Cu" "B.Cu")
		(net "FM_TPM_PRSNT_N")
	)
	(segment
		(start 63.718694 -171.859194)
		(end 63.26886 -171.859194)
		(width 0.127)
		(layer "B.Cu")
		(net "FM_TPM_PRSNT_N")
	)
	(segment
		(start 46.6344 -172.0088)
		(end 46.1518 -172.4914)
		(width 0.127)
		(layer "B.Cu")
		(net "FM_TPM_PRSNT_N")
	)
	(segment
		(start 58.438288 -172.0088)
		(end 46.6344 -172.0088)
		(width 0.127)
		(layer "B.Cu")
		(net "FM_TPM_PRSNT_N")
	)
	(segment
		(start 41.14292 -129.57556)
		(end 41.14292 -129.30886)
		(width 0.127)
		(layer "B.Cu")
		(net "FM_TPM_PRSNT_N")
	)
	(segment
		(start 46.1518 -172.4914)
		(end 46.0502 -172.4914)
		(width 0.127)
		(layer "B.Cu")
		(net "FM_TPM_PRSNT_N")
	)
	(segment
		(start 61.336428 -170.72991)
		(end 59.717178 -170.72991)
		(width 0.127)
		(layer "B.Cu")
		(net "FM_TPM_PRSNT_N")
	)
	(segment
		(start 62.465712 -171.859194)
		(end 61.336428 -170.72991)
		(width 0.127)
		(layer "B.Cu")
		(net "FM_TPM_PRSNT_N")
	)
	(segment
		(start 41.14292 -129.30886)
		(end 40.50792 -128.67386)
		(width 0.127)
		(layer "B.Cu")
		(net "FM_TPM_PRSNT_N")
	)
	(segment
		(start 64.8208 -172.9613)
		(end 63.718694 -171.859194)
		(width 0.127)
		(layer "B.Cu")
		(net "FM_TPM_PRSNT_N")
	)
	(segment
		(start 59.717178 -170.72991)
		(end 58.438288 -172.0088)
		(width 0.127)
		(layer "B.Cu")
		(net "FM_TPM_PRSNT_N")
	)
	(segment
		(start 63.26886 -171.859194)
		(end 62.465712 -171.859194)
		(width 0.127)
		(layer "B.Cu")
		(net "FM_TPM_PRSNT_N")
	)
	(segment
		(start 9.5631 -156.7307)
		(end 9.5631 -145.4277)
		(width 0.127)
		(layer "In2.Cu")
		(net "FM_TPM_PRSNT_N")
	)
	(segment
		(start 9.5631 -145.4277)
		(end 10.21715 -144.77365)
		(width 0.127)
		(layer "In2.Cu")
		(net "FM_TPM_PRSNT_N")
	)
	(segment
		(start 11.1887 -127.4064)
		(end 12.5984 -125.9967)
		(width 0.127)
		(layer "In2.Cu")
		(net "FM_TPM_PRSNT_N")
	)
	(segment
		(start 9.7917 -156.9593)
		(end 9.5631 -156.7307)
		(width 0.127)
		(layer "In2.Cu")
		(net "FM_TPM_PRSNT_N")
	)
	(segment
		(start 10.21715 -131.48945)
		(end 11.1887 -130.5179)
		(width 0.127)
		(layer "In2.Cu")
		(net "FM_TPM_PRSNT_N")
	)
	(segment
		(start 10.21715 -144.77365)
		(end 10.21715 -131.48945)
		(width 0.127)
		(layer "In2.Cu")
		(net "FM_TPM_PRSNT_N")
	)
	(segment
		(start 11.1887 -130.5179)
		(end 11.1887 -127.4064)
		(width 0.127)
		(layer "In2.Cu")
		(net "FM_TPM_PRSNT_N")
	)
	(segment
		(start 9.7917 -156.9593)
		(end 15.5321 -162.6997)
		(width 0.127)
		(layer "In5.Cu")
		(net "FM_TPM_PRSNT_N")
	)
	(segment
		(start 28.6893 -123.952)
		(end 30.6832 -123.952)
		(width 0.127)
		(layer "In5.Cu")
		(net "FM_TPM_PRSNT_N")
	)
	(segment
		(start 39.677086 -173.827186)
		(end 43.215814 -173.827186)
		(width 0.127)
		(layer "In5.Cu")
		(net "FM_TPM_PRSNT_N")
	)
	(segment
		(start 30.5435 -164.6936)
		(end 39.677086 -173.827186)
		(width 0.127)
		(layer "In5.Cu")
		(net "FM_TPM_PRSNT_N")
	)
	(segment
		(start 26.0604 -126.5809)
		(end 28.6893 -123.952)
		(width 0.127)
		(layer "In5.Cu")
		(net "FM_TPM_PRSNT_N")
	)
	(segment
		(start 15.5321 -162.6997)
		(end 28.03144 -162.6997)
		(width 0.127)
		(layer "In5.Cu")
		(net "FM_TPM_PRSNT_N")
	)
	(segment
		(start 40.192198 -128.67386)
		(end 40.50792 -128.67386)
		(width 0.127)
		(layer "In5.Cu")
		(net "FM_TPM_PRSNT_N")
	)
	(segment
		(start 13.1826 -126.5809)
		(end 26.0604 -126.5809)
		(width 0.127)
		(layer "In5.Cu")
		(net "FM_TPM_PRSNT_N")
	)
	(segment
		(start 28.03144 -162.6997)
		(end 30.02534 -164.6936)
		(width 0.127)
		(layer "In5.Cu")
		(net "FM_TPM_PRSNT_N")
	)
	(segment
		(start 12.5984 -125.9967)
		(end 13.1826 -126.5809)
		(width 0.127)
		(layer "In5.Cu")
		(net "FM_TPM_PRSNT_N")
	)
	(segment
		(start 30.6832 -123.952)
		(end 33.89376 -127.16256)
		(width 0.127)
		(layer "In5.Cu")
		(net "FM_TPM_PRSNT_N")
	)
	(segment
		(start 43.215814 -173.827186)
		(end 44.5516 -172.4914)
		(width 0.127)
		(layer "In5.Cu")
		(net "FM_TPM_PRSNT_N")
	)
	(segment
		(start 44.5516 -172.4914)
		(end 46.0502 -172.4914)
		(width 0.127)
		(layer "In5.Cu")
		(net "FM_TPM_PRSNT_N")
	)
	(segment
		(start 33.89376 -127.16256)
		(end 38.680898 -127.16256)
		(width 0.127)
		(layer "In5.Cu")
		(net "FM_TPM_PRSNT_N")
	)
	(segment
		(start 38.680898 -127.16256)
		(end 40.192198 -128.67386)
		(width 0.127)
		(layer "In5.Cu")
		(net "FM_TPM_PRSNT_N")
	)
	(segment
		(start 30.02534 -164.6936)
		(end 30.5435 -164.6936)
		(width 0.127)
		(layer "In5.Cu")
		(net "FM_TPM_PRSNT_N")
	)
	(segment
		(start 68.89496 -174.3329)
		(end 68.89496 -172.744638)
		(width 0.127)
		(layer "F.Cu")
		(net "COMP_TO_BMC_RESET_N_OUT")
	)
	(segment
		(start 68.8086 -172.658278)
		(end 68.89496 -172.744638)
		(width 0.127)
		(layer "F.Cu")
		(net "COMP_TO_BMC_RESET_N_OUT")
	)
	(segment
		(start 70.1294 -171.6786)
		(end 70.1294 -172.1358)
		(width 0.127)
		(layer "F.Cu")
		(net "COMP_TO_BMC_RESET_N_OUT")
	)
	(segment
		(start 68.8086 -171.2087)
		(end 69.6595 -171.2087)
		(width 0.127)
		(layer "F.Cu")
		(net "COMP_TO_BMC_RESET_N_OUT")
	)
	(segment
		(start 82.51317 -149.08276)
		(end 82.298286 -149.297644)
		(width 0.127)
		(layer "F.Cu")
		(net "COMP_TO_BMC_RESET_N_OUT")
	)
	(segment
		(start 69.6595 -171.2087)
		(end 70.1294 -171.6786)
		(width 0.127)
		(layer "F.Cu")
		(net "COMP_TO_BMC_RESET_N_OUT")
	)
	(segment
		(start 82.298286 -149.297644)
		(end 82.298286 -150.752302)
		(width 0.127)
		(layer "F.Cu")
		(net "COMP_TO_BMC_RESET_N_OUT")
	)
	(segment
		(start 82.298286 -150.752302)
		(end 80.693006 -152.357582)
		(width 0.127)
		(layer "F.Cu")
		(net "COMP_TO_BMC_RESET_N_OUT")
	)
	(segment
		(start 83.1215 -149.08276)
		(end 82.51317 -149.08276)
		(width 0.127)
		(layer "F.Cu")
		(net "COMP_TO_BMC_RESET_N_OUT")
	)
	(segment
		(start 68.8086 -171.2087)
		(end 68.8086 -172.658278)
		(width 0.127)
		(layer "F.Cu")
		(net "COMP_TO_BMC_RESET_N_OUT")
	)
	(via
		(at 70.1294 -172.1358)
		(size 0.508)
		(drill 0.254)
		(layers "F.Cu" "B.Cu")
		(net "COMP_TO_BMC_RESET_N_OUT")
	)
	(via
		(at 83.5914 -165.2778)
		(size 0.508)
		(drill 0.254)
		(layers "F.Cu" "B.Cu")
		(net "COMP_TO_BMC_RESET_N_OUT")
	)
	(via
		(at 68.89496 -172.744638)
		(size 0.6604)
		(drill 0.3302)
		(layers "F.Cu" "B.Cu")
		(net "COMP_TO_BMC_RESET_N_OUT")
	)
	(via
		(at 80.693006 -152.357582)
		(size 0.508)
		(drill 0.254)
		(layers "F.Cu" "B.Cu")
		(net "COMP_TO_BMC_RESET_N_OUT")
	)
	(segment
		(start 85.308948 -167.291258)
		(end 86.381336 -168.363646)
		(width 0.127)
		(layer "B.Cu")
		(net "COMP_TO_BMC_RESET_N_OUT")
	)
	(segment
		(start 83.5914 -165.2778)
		(end 84.403946 -165.2778)
		(width 0.127)
		(layer "B.Cu")
		(net "COMP_TO_BMC_RESET_N_OUT")
	)
	(segment
		(start 86.381336 -168.544494)
		(end 86.3854 -168.548558)
		(width 0.127)
		(layer "B.Cu")
		(net "COMP_TO_BMC_RESET_N_OUT")
	)
	(segment
		(start 86.381336 -168.363646)
		(end 86.381336 -168.544494)
		(width 0.127)
		(layer "B.Cu")
		(net "COMP_TO_BMC_RESET_N_OUT")
	)
	(segment
		(start 84.403946 -165.2778)
		(end 85.308948 -166.182802)
		(width 0.127)
		(layer "B.Cu")
		(net "COMP_TO_BMC_RESET_N_OUT")
	)
	(segment
		(start 86.3854 -168.548558)
		(end 86.3854 -171.70908)
		(width 0.127)
		(layer "B.Cu")
		(net "COMP_TO_BMC_RESET_N_OUT")
	)
	(segment
		(start 85.308948 -166.182802)
		(end 85.308948 -167.291258)
		(width 0.127)
		(layer "B.Cu")
		(net "COMP_TO_BMC_RESET_N_OUT")
	)
	(segment
		(start 86.3854 -171.70908)
		(end 83.50758 -174.5869)
		(width 0.127)
		(layer "B.Cu")
		(net "COMP_TO_BMC_RESET_N_OUT")
	)
	(segment
		(start 72.5805 -174.5869)
		(end 70.1294 -172.1358)
		(width 0.127)
		(layer "B.Cu")
		(net "COMP_TO_BMC_RESET_N_OUT")
	)
	(segment
		(start 83.50758 -174.5869)
		(end 72.5805 -174.5869)
		(width 0.127)
		(layer "B.Cu")
		(net "COMP_TO_BMC_RESET_N_OUT")
	)
	(segment
		(start 83.211162 -164.643562)
		(end 83.211162 -164.948362)
		(width 0.127)
		(layer "In2.Cu")
		(net "COMP_TO_BMC_RESET_N_OUT")
	)
	(segment
		(start 80.2005 -158.553404)
		(end 81.4959 -159.848804)
		(width 0.127)
		(layer "In2.Cu")
		(net "COMP_TO_BMC_RESET_N_OUT")
	)
	(segment
		(start 80.2005 -152.850088)
		(end 80.2005 -158.553404)
		(width 0.127)
		(layer "In2.Cu")
		(net "COMP_TO_BMC_RESET_N_OUT")
	)
	(segment
		(start 83.211162 -164.948362)
		(end 83.5406 -165.2778)
		(width 0.127)
		(layer "In2.Cu")
		(net "COMP_TO_BMC_RESET_N_OUT")
	)
	(segment
		(start 82.110326 -163.997894)
		(end 82.565494 -163.997894)
		(width 0.127)
		(layer "In2.Cu")
		(net "COMP_TO_BMC_RESET_N_OUT")
	)
	(segment
		(start 81.4959 -163.383468)
		(end 82.110326 -163.997894)
		(width 0.127)
		(layer "In2.Cu")
		(net "COMP_TO_BMC_RESET_N_OUT")
	)
	(segment
		(start 81.4959 -159.848804)
		(end 81.4959 -163.383468)
		(width 0.127)
		(layer "In2.Cu")
		(net "COMP_TO_BMC_RESET_N_OUT")
	)
	(segment
		(start 80.693006 -152.357582)
		(end 80.2005 -152.850088)
		(width 0.127)
		(layer "In2.Cu")
		(net "COMP_TO_BMC_RESET_N_OUT")
	)
	(segment
		(start 83.5406 -165.2778)
		(end 83.5914 -165.2778)
		(width 0.127)
		(layer "In2.Cu")
		(net "COMP_TO_BMC_RESET_N_OUT")
	)
	(segment
		(start 82.565494 -163.997894)
		(end 83.211162 -164.643562)
		(width 0.127)
		(layer "In2.Cu")
		(net "COMP_TO_BMC_RESET_N_OUT")
	)
	(segment
		(start 9.85012 -12.19454)
		(end 11.02868 -12.19454)
		(width 0.127)
		(layer "F.Cu")
		(net "SYS_RST_BTN_IN_N")
	)
	(segment
		(start 75.121516 -140.0302)
		(end 75.226418 -139.925298)
		(width 0.127)
		(layer "F.Cu")
		(net "SYS_RST_BTN_IN_N")
	)
	(segment
		(start 75.226418 -139.925298)
		(end 75.643994 -139.925298)
		(width 0.127)
		(layer "F.Cu")
		(net "SYS_RST_BTN_IN_N")
	)
	(segment
		(start 7.68858 -12.27582)
		(end 7.75462 -12.20978)
		(width 0.127)
		(layer "F.Cu")
		(net "SYS_RST_BTN_IN_N")
	)
	(segment
		(start 8.65378 -12.20978)
		(end 8.66902 -12.19454)
		(width 0.127)
		(layer "F.Cu")
		(net "SYS_RST_BTN_IN_N")
	)
	(segment
		(start 74.9173 -140.0302)
		(end 75.121516 -140.0302)
		(width 0.127)
		(layer "F.Cu")
		(net "SYS_RST_BTN_IN_N")
	)
	(segment
		(start 11.02868 -12.19454)
		(end 11.04392 -12.1793)
		(width 0.127)
		(layer "F.Cu")
		(net "SYS_RST_BTN_IN_N")
	)
	(segment
		(start 7.75462 -12.20978)
		(end 8.65378 -12.20978)
		(width 0.127)
		(layer "F.Cu")
		(net "SYS_RST_BTN_IN_N")
	)
	(segment
		(start 11.04392 -12.1793)
		(end 11.04392 -7.5438)
		(width 0.127)
		(layer "F.Cu")
		(net "SYS_RST_BTN_IN_N")
	)
	(segment
		(start 75.643994 -139.925298)
		(end 75.822556 -139.746736)
		(width 0.127)
		(layer "F.Cu")
		(net "SYS_RST_BTN_IN_N")
	)
	(segment
		(start 8.66902 -12.19454)
		(end 9.85012 -12.19454)
		(width 0.127)
		(layer "F.Cu")
		(net "SYS_RST_BTN_IN_N")
	)
	(segment
		(start 11.04392 -7.5438)
		(end 9.750044 -6.249924)
		(width 0.127)
		(layer "F.Cu")
		(net "SYS_RST_BTN_IN_N")
	)
	(via
		(at 7.68858 -12.27582)
		(size 0.508)
		(drill 0.254)
		(layers "F.Cu" "B.Cu")
		(net "SYS_RST_BTN_IN_N")
	)
	(via
		(at 57.023 -113.1824)
		(size 0.508)
		(drill 0.254)
		(layers "F.Cu" "B.Cu")
		(net "SYS_RST_BTN_IN_N")
	)
	(via
		(at 72.8218 -116.205)
		(size 0.508)
		(drill 0.254)
		(layers "F.Cu" "B.Cu")
		(net "SYS_RST_BTN_IN_N")
	)
	(via
		(at 58.0898 -114.4524)
		(size 0.6096)
		(drill 0.3048)
		(layers "F.Cu" "B.Cu")
		(net "SYS_RST_BTN_IN_N")
	)
	(via
		(at 27.5082 -110.7186)
		(size 0.508)
		(drill 0.254)
		(layers "F.Cu" "B.Cu")
		(net "SYS_RST_BTN_IN_N")
	)
	(via
		(at 75.822556 -139.746736)
		(size 0.508)
		(drill 0.254)
		(layers "F.Cu" "B.Cu")
		(net "SYS_RST_BTN_IN_N")
	)
	(segment
		(start 62.611 -118.9736)
		(end 70.187566 -118.9736)
		(width 0.127)
		(layer "B.Cu")
		(net "SYS_RST_BTN_IN_N")
	)
	(segment
		(start 57.023 -113.3856)
		(end 57.023 -113.1824)
		(width 0.127)
		(layer "B.Cu")
		(net "SYS_RST_BTN_IN_N")
	)
	(segment
		(start 58.0898 -114.4524)
		(end 62.611 -118.9736)
		(width 0.127)
		(layer "B.Cu")
		(net "SYS_RST_BTN_IN_N")
	)
	(segment
		(start 72.678036 -116.48313)
		(end 72.678036 -116.348764)
		(width 0.127)
		(layer "B.Cu")
		(net "SYS_RST_BTN_IN_N")
	)
	(segment
		(start 58.0898 -114.4524)
		(end 57.023 -113.3856)
		(width 0.127)
		(layer "B.Cu")
		(net "SYS_RST_BTN_IN_N")
	)
	(segment
		(start 72.678036 -116.348764)
		(end 72.8218 -116.205)
		(width 0.127)
		(layer "B.Cu")
		(net "SYS_RST_BTN_IN_N")
	)
	(segment
		(start 70.187566 -118.9736)
		(end 72.678036 -116.48313)
		(width 0.127)
		(layer "B.Cu")
		(net "SYS_RST_BTN_IN_N")
	)
	(segment
		(start 72.8218 -116.205)
		(end 73.219056 -116.602256)
		(width 0.127)
		(layer "In2.Cu")
		(net "SYS_RST_BTN_IN_N")
	)
	(segment
		(start 24.978614 -12.3825)
		(end 27.1145 -14.518386)
		(width 0.127)
		(layer "In2.Cu")
		(net "SYS_RST_BTN_IN_N")
	)
	(segment
		(start 7.68858 -12.27582)
		(end 7.79526 -12.3825)
		(width 0.127)
		(layer "In2.Cu")
		(net "SYS_RST_BTN_IN_N")
	)
	(segment
		(start 73.219056 -124.968508)
		(end 73.879202 -125.628654)
		(width 0.127)
		(layer "In2.Cu")
		(net "SYS_RST_BTN_IN_N")
	)
	(segment
		(start 27.413204 -110.623604)
		(end 27.5082 -110.7186)
		(width 0.127)
		(layer "In2.Cu")
		(net "SYS_RST_BTN_IN_N")
	)
	(segment
		(start 27.1145 -14.518386)
		(end 27.1145 -42.5069)
		(width 0.127)
		(layer "In2.Cu")
		(net "SYS_RST_BTN_IN_N")
	)
	(segment
		(start 73.219056 -116.602256)
		(end 73.219056 -124.968508)
		(width 0.127)
		(layer "In2.Cu")
		(net "SYS_RST_BTN_IN_N")
	)
	(segment
		(start 7.79526 -12.3825)
		(end 24.978614 -12.3825)
		(width 0.127)
		(layer "In2.Cu")
		(net "SYS_RST_BTN_IN_N")
	)
	(segment
		(start 73.879202 -125.628654)
		(end 73.879202 -129.073402)
		(width 0.127)
		(layer "In2.Cu")
		(net "SYS_RST_BTN_IN_N")
	)
	(segment
		(start 75.822556 -133.653022)
		(end 75.822556 -139.746736)
		(width 0.127)
		(layer "In2.Cu")
		(net "SYS_RST_BTN_IN_N")
	)
	(segment
		(start 27.1145 -42.5069)
		(end 27.413204 -42.805604)
		(width 0.127)
		(layer "In2.Cu")
		(net "SYS_RST_BTN_IN_N")
	)
	(segment
		(start 27.413204 -42.805604)
		(end 27.413204 -110.623604)
		(width 0.127)
		(layer "In2.Cu")
		(net "SYS_RST_BTN_IN_N")
	)
	(segment
		(start 76.24699 -131.44119)
		(end 76.24699 -133.228588)
		(width 0.127)
		(layer "In2.Cu")
		(net "SYS_RST_BTN_IN_N")
	)
	(segment
		(start 73.879202 -129.073402)
		(end 76.24699 -131.44119)
		(width 0.127)
		(layer "In2.Cu")
		(net "SYS_RST_BTN_IN_N")
	)
	(segment
		(start 76.24699 -133.228588)
		(end 75.822556 -133.653022)
		(width 0.127)
		(layer "In2.Cu")
		(net "SYS_RST_BTN_IN_N")
	)
	(segment
		(start 33.8074 -113.0808)
		(end 53.2892 -113.0808)
		(width 0.127)
		(layer "In5.Cu")
		(net "SYS_RST_BTN_IN_N")
	)
	(segment
		(start 32.4866 -111.76)
		(end 33.8074 -113.0808)
		(width 0.127)
		(layer "In5.Cu")
		(net "SYS_RST_BTN_IN_N")
	)
	(segment
		(start 27.5082 -110.7186)
		(end 27.5844 -110.6424)
		(width 0.127)
		(layer "In5.Cu")
		(net "SYS_RST_BTN_IN_N")
	)
	(segment
		(start 53.7718 -112.5982)
		(end 56.4388 -112.5982)
		(width 0.127)
		(layer "In5.Cu")
		(net "SYS_RST_BTN_IN_N")
	)
	(segment
		(start 56.4388 -112.5982)
		(end 57.023 -113.1824)
		(width 0.127)
		(layer "In5.Cu")
		(net "SYS_RST_BTN_IN_N")
	)
	(segment
		(start 30.0736 -111.76)
		(end 32.4866 -111.76)
		(width 0.127)
		(layer "In5.Cu")
		(net "SYS_RST_BTN_IN_N")
	)
	(segment
		(start 53.2892 -113.0808)
		(end 53.7718 -112.5982)
		(width 0.127)
		(layer "In5.Cu")
		(net "SYS_RST_BTN_IN_N")
	)
	(segment
		(start 27.5844 -110.6424)
		(end 28.956 -110.6424)
		(width 0.127)
		(layer "In5.Cu")
		(net "SYS_RST_BTN_IN_N")
	)
	(segment
		(start 28.956 -110.6424)
		(end 30.0736 -111.76)
		(width 0.127)
		(layer "In5.Cu")
		(net "SYS_RST_BTN_IN_N")
	)
	(segment
		(start 52.899818 -138.200384)
		(end 52.899818 -138.199876)
		(width 0.127)
		(layer "F.Cu")
		(net "SYS_RESET_N_OUT_R")
	)
	(segment
		(start 52.499768 -138.600434)
		(end 52.899818 -138.200384)
		(width 0.127)
		(layer "F.Cu")
		(net "SYS_RESET_N_OUT_R")
	)
	(via
		(at 52.499768 -138.600434)
		(size 0.4572)
		(drill 0.2032)
		(layers "F.Cu" "B.Cu")
		(net "SYS_RESET_N_OUT_R")
	)
	(via
		(at 52.5018 -137.0584)
		(size 0.6096)
		(drill 0.3048)
		(layers "F.Cu" "B.Cu")
		(net "SYS_RESET_N_OUT_R")
	)
	(segment
		(start 52.5272 -136.15162)
		(end 52.5272 -137.033)
		(width 0.127)
		(layer "B.Cu")
		(net "SYS_RESET_N_OUT_R")
	)
	(segment
		(start 53.050186 -138.050016)
		(end 53.050186 -137.606786)
		(width 0.127)
		(layer "B.Cu")
		(net "SYS_RESET_N_OUT_R")
	)
	(segment
		(start 52.5272 -137.033)
		(end 52.5018 -137.0584)
		(width 0.127)
		(layer "B.Cu")
		(net "SYS_RESET_N_OUT_R")
	)
	(segment
		(start 53.050186 -137.606786)
		(end 52.5018 -137.0584)
		(width 0.127)
		(layer "B.Cu")
		(net "SYS_RESET_N_OUT_R")
	)
	(segment
		(start 52.499768 -138.600434)
		(end 53.050186 -138.050016)
		(width 0.127)
		(layer "B.Cu")
		(net "SYS_RESET_N_OUT_R")
	)
	(via
		(at 52.832 -134.4422)
		(size 0.508)
		(drill 0.254)
		(layers "F.Cu" "B.Cu")
		(net "SYS_RESET_N_OUT")
	)
	(via
		(at 33.756346 -124.234194)
		(size 0.6096)
		(drill 0.3048)
		(layers "F.Cu" "B.Cu")
		(net "SYS_RESET_N_OUT")
	)
	(via
		(at 37.138864 -123.45543)
		(size 0.508)
		(drill 0.254)
		(layers "F.Cu" "B.Cu")
		(net "SYS_RESET_N_OUT")
	)
	(via
		(at 49.845722 -123.642628)
		(size 0.508)
		(drill 0.254)
		(layers "F.Cu" "B.Cu")
		(net "SYS_RESET_N_OUT")
	)
	(segment
		(start 36.517072 -123.45543)
		(end 37.138864 -123.45543)
		(width 0.127)
		(layer "B.Cu")
		(net "SYS_RESET_N_OUT")
	)
	(segment
		(start 52.705 -134.5692)
		(end 52.832 -134.4422)
		(width 0.127)
		(layer "B.Cu")
		(net "SYS_RESET_N_OUT")
	)
	(segment
		(start 35.738308 -124.234194)
		(end 34.722308 -124.234194)
		(width 0.127)
		(layer "B.Cu")
		(net "SYS_RESET_N_OUT")
	)
	(segment
		(start 32.808672 -123.8631)
		(end 32.2199 -123.8631)
		(width 0.127)
		(layer "B.Cu")
		(net "SYS_RESET_N_OUT")
	)
	(segment
		(start 52.705 -134.6454)
		(end 52.705 -134.5692)
		(width 0.127)
		(layer "B.Cu")
		(net "SYS_RESET_N_OUT")
	)
	(segment
		(start 52.5272 -134.8232)
		(end 52.705 -134.6454)
		(width 0.127)
		(layer "B.Cu")
		(net "SYS_RESET_N_OUT")
	)
	(segment
		(start 35.738308 -124.234194)
		(end 36.517072 -123.45543)
		(width 0.127)
		(layer "B.Cu")
		(net "SYS_RESET_N_OUT")
	)
	(segment
		(start 33.756346 -124.234194)
		(end 33.179766 -124.234194)
		(width 0.127)
		(layer "B.Cu")
		(net "SYS_RESET_N_OUT")
	)
	(segment
		(start 33.179766 -124.234194)
		(end 32.808672 -123.8631)
		(width 0.127)
		(layer "B.Cu")
		(net "SYS_RESET_N_OUT")
	)
	(segment
		(start 34.722308 -124.234194)
		(end 33.756346 -124.234194)
		(width 0.127)
		(layer "B.Cu")
		(net "SYS_RESET_N_OUT")
	)
	(segment
		(start 52.5272 -135.26262)
		(end 52.5272 -134.8232)
		(width 0.127)
		(layer "B.Cu")
		(net "SYS_RESET_N_OUT")
	)
	(segment
		(start 49.845722 -123.642628)
		(end 51.163728 -123.642628)
		(width 0.127)
		(layer "In2.Cu")
		(net "SYS_RESET_N_OUT")
	)
	(segment
		(start 51.2953 -123.7742)
		(end 51.2953 -127.1397)
		(width 0.127)
		(layer "In2.Cu")
		(net "SYS_RESET_N_OUT")
	)
	(segment
		(start 51.2953 -127.1397)
		(end 52.83962 -128.68402)
		(width 0.127)
		(layer "In2.Cu")
		(net "SYS_RESET_N_OUT")
	)
	(segment
		(start 52.832 -129.621534)
		(end 52.832 -134.4422)
		(width 0.127)
		(layer "In2.Cu")
		(net "SYS_RESET_N_OUT")
	)
	(segment
		(start 52.83962 -129.613914)
		(end 52.832 -129.621534)
		(width 0.127)
		(layer "In2.Cu")
		(net "SYS_RESET_N_OUT")
	)
	(segment
		(start 52.83962 -128.68402)
		(end 52.83962 -129.613914)
		(width 0.127)
		(layer "In2.Cu")
		(net "SYS_RESET_N_OUT")
	)
	(segment
		(start 51.163728 -123.642628)
		(end 51.2953 -123.7742)
		(width 0.127)
		(layer "In2.Cu")
		(net "SYS_RESET_N_OUT")
	)
	(segment
		(start 38.016434 -124.333)
		(end 37.138864 -123.45543)
		(width 0.127)
		(layer "In5.Cu")
		(net "SYS_RESET_N_OUT")
	)
	(segment
		(start 39.778432 -124.333)
		(end 38.016434 -124.333)
		(width 0.127)
		(layer "In5.Cu")
		(net "SYS_RESET_N_OUT")
	)
	(segment
		(start 49.0855 -123.7869)
		(end 40.324532 -123.7869)
		(width 0.127)
		(layer "In5.Cu")
		(net "SYS_RESET_N_OUT")
	)
	(segment
		(start 49.229772 -123.642628)
		(end 49.0855 -123.7869)
		(width 0.127)
		(layer "In5.Cu")
		(net "SYS_RESET_N_OUT")
	)
	(segment
		(start 40.324532 -123.7869)
		(end 39.778432 -124.333)
		(width 0.127)
		(layer "In5.Cu")
		(net "SYS_RESET_N_OUT")
	)
	(segment
		(start 49.845722 -123.642628)
		(end 49.229772 -123.642628)
		(width 0.127)
		(layer "In5.Cu")
		(net "SYS_RESET_N_OUT")
	)
	(segment
		(start 183.418988 -155.40736)
		(end 183.418988 -155.836366)
		(width 0.127)
		(layer "F.Cu")
		(net "P12V_IOM_PGOOD")
	)
	(segment
		(start 182.499 -156.2862)
		(end 182.9562 -156.2862)
		(width 0.127)
		(layer "F.Cu")
		(net "P12V_IOM_PGOOD")
	)
	(segment
		(start 181.95163 -155.40736)
		(end 181.95163 -155.73883)
		(width 0.127)
		(layer "F.Cu")
		(net "P12V_IOM_PGOOD")
	)
	(segment
		(start 124.3965 -8.636)
		(end 123.502166 -7.741666)
		(width 0.127)
		(layer "F.Cu")
		(net "P12V_IOM_PGOOD")
	)
	(segment
		(start 123.502166 -7.741666)
		(end 121.3485 -7.741666)
		(width 0.127)
		(layer "F.Cu")
		(net "P12V_IOM_PGOOD")
	)
	(segment
		(start 183.418988 -155.836366)
		(end 182.969154 -156.2862)
		(width 0.127)
		(layer "F.Cu")
		(net "P12V_IOM_PGOOD")
	)
	(segment
		(start 123.361196 -8.362696)
		(end 123.6345 -8.636)
		(width 0.127)
		(layer "F.Cu")
		(net "P12V_IOM_PGOOD")
	)
	(segment
		(start 123.6345 -8.636)
		(end 124.3965 -8.636)
		(width 0.127)
		(layer "F.Cu")
		(net "P12V_IOM_PGOOD")
	)
	(segment
		(start 182.969154 -156.2862)
		(end 182.9562 -156.2862)
		(width 0.127)
		(layer "F.Cu")
		(net "P12V_IOM_PGOOD")
	)
	(segment
		(start 181.95163 -155.73883)
		(end 182.499 -156.2862)
		(width 0.127)
		(layer "F.Cu")
		(net "P12V_IOM_PGOOD")
	)
	(via
		(at 152.732994 -3.434334)
		(size 0.508)
		(drill 0.254)
		(layers "F.Cu" "B.Cu")
		(net "P12V_IOM_PGOOD")
	)
	(via
		(at 123.361196 -8.362696)
		(size 0.508)
		(drill 0.254)
		(layers "F.Cu" "B.Cu")
		(net "P12V_IOM_PGOOD")
	)
	(via
		(at 183.418988 -155.40736)
		(size 0.508)
		(drill 0.254)
		(layers "F.Cu" "B.Cu")
		(net "P12V_IOM_PGOOD")
	)
	(via
		(at 182.9562 -156.2862)
		(size 0.6604)
		(drill 0.3302)
		(layers "F.Cu" "B.Cu")
		(net "P12V_IOM_PGOOD")
	)
	(via
		(at 189.7888 -155.4226)
		(size 0.508)
		(drill 0.254)
		(layers "F.Cu" "B.Cu")
		(net "P12V_IOM_PGOOD")
	)
	(segment
		(start 121.397522 -8.67791)
		(end 123.045982 -8.67791)
		(width 0.127)
		(layer "B.Cu")
		(net "P12V_IOM_PGOOD")
	)
	(segment
		(start 189.7888 -155.4226)
		(end 189.77356 -155.40736)
		(width 0.127)
		(layer "B.Cu")
		(net "P12V_IOM_PGOOD")
	)
	(segment
		(start 123.3424 -8.362696)
		(end 123.3424 -8.3439)
		(width 0.127)
		(layer "B.Cu")
		(net "P12V_IOM_PGOOD")
	)
	(segment
		(start 189.77356 -155.40736)
		(end 183.418988 -155.40736)
		(width 0.127)
		(layer "B.Cu")
		(net "P12V_IOM_PGOOD")
	)
	(segment
		(start 123.045982 -8.67791)
		(end 123.361196 -8.362696)
		(width 0.127)
		(layer "B.Cu")
		(net "P12V_IOM_PGOOD")
	)
	(segment
		(start 123.3424 -8.3439)
		(end 123.952508 -7.733792)
		(width 0.127)
		(layer "B.Cu")
		(net "P12V_IOM_PGOOD")
	)
	(segment
		(start 123.952508 -7.733792)
		(end 124.391166 -7.733792)
		(width 0.127)
		(layer "B.Cu")
		(net "P12V_IOM_PGOOD")
	)
	(segment
		(start 123.361196 -8.362696)
		(end 123.3424 -8.362696)
		(width 0.127)
		(layer "B.Cu")
		(net "P12V_IOM_PGOOD")
	)
	(segment
		(start 228.4349 -116.7765)
		(end 189.7888 -155.4226)
		(width 0.127)
		(layer "In2.Cu")
		(net "P12V_IOM_PGOOD")
	)
	(segment
		(start 187.846462 -21.806662)
		(end 193.789046 -27.749246)
		(width 0.127)
		(layer "In2.Cu")
		(net "P12V_IOM_PGOOD")
	)
	(segment
		(start 223.7105 -98.400108)
		(end 228.4349 -103.124508)
		(width 0.127)
		(layer "In2.Cu")
		(net "P12V_IOM_PGOOD")
	)
	(segment
		(start 228.4349 -103.124508)
		(end 228.4349 -116.7765)
		(width 0.127)
		(layer "In2.Cu")
		(net "P12V_IOM_PGOOD")
	)
	(segment
		(start 187.846462 -4.560062)
		(end 187.846462 -21.806662)
		(width 0.127)
		(layer "In2.Cu")
		(net "P12V_IOM_PGOOD")
	)
	(segment
		(start 193.942462 -27.749246)
		(end 194.500754 -28.307538)
		(width 0.127)
		(layer "In2.Cu")
		(net "P12V_IOM_PGOOD")
	)
	(segment
		(start 221.85376 -55.07736)
		(end 221.85376 -80.710532)
		(width 0.127)
		(layer "In2.Cu")
		(net "P12V_IOM_PGOOD")
	)
	(segment
		(start 153.388568 -2.77876)
		(end 186.06516 -2.77876)
		(width 0.127)
		(layer "In2.Cu")
		(net "P12V_IOM_PGOOD")
	)
	(segment
		(start 193.789046 -27.749246)
		(end 193.942462 -27.749246)
		(width 0.127)
		(layer "In2.Cu")
		(net "P12V_IOM_PGOOD")
	)
	(segment
		(start 186.06516 -2.77876)
		(end 187.846462 -4.560062)
		(width 0.127)
		(layer "In2.Cu")
		(net "P12V_IOM_PGOOD")
	)
	(segment
		(start 198.53021 -31.75381)
		(end 221.85376 -55.07736)
		(width 0.127)
		(layer "In2.Cu")
		(net "P12V_IOM_PGOOD")
	)
	(segment
		(start 194.500754 -28.307538)
		(end 194.500754 -28.460954)
		(width 0.127)
		(layer "In2.Cu")
		(net "P12V_IOM_PGOOD")
	)
	(segment
		(start 152.732994 -3.434334)
		(end 153.388568 -2.77876)
		(width 0.127)
		(layer "In2.Cu")
		(net "P12V_IOM_PGOOD")
	)
	(segment
		(start 197.79361 -31.75381)
		(end 198.53021 -31.75381)
		(width 0.127)
		(layer "In2.Cu")
		(net "P12V_IOM_PGOOD")
	)
	(segment
		(start 223.7105 -82.567272)
		(end 223.7105 -98.400108)
		(width 0.127)
		(layer "In2.Cu")
		(net "P12V_IOM_PGOOD")
	)
	(segment
		(start 221.85376 -80.710532)
		(end 223.7105 -82.567272)
		(width 0.127)
		(layer "In2.Cu")
		(net "P12V_IOM_PGOOD")
	)
	(segment
		(start 194.500754 -28.460954)
		(end 197.79361 -31.75381)
		(width 0.127)
		(layer "In2.Cu")
		(net "P12V_IOM_PGOOD")
	)
	(segment
		(start 126.2888 -6.5532)
		(end 132.989828 -6.5532)
		(width 0.127)
		(layer "In5.Cu")
		(net "P12V_IOM_PGOOD")
	)
	(segment
		(start 134.898638 -4.64439)
		(end 151.522938 -4.64439)
		(width 0.127)
		(layer "In5.Cu")
		(net "P12V_IOM_PGOOD")
	)
	(segment
		(start 124.479304 -8.362696)
		(end 126.2888 -6.5532)
		(width 0.127)
		(layer "In5.Cu")
		(net "P12V_IOM_PGOOD")
	)
	(segment
		(start 151.522938 -4.64439)
		(end 152.732994 -3.434334)
		(width 0.127)
		(layer "In5.Cu")
		(net "P12V_IOM_PGOOD")
	)
	(segment
		(start 123.361196 -8.362696)
		(end 124.479304 -8.362696)
		(width 0.127)
		(layer "In5.Cu")
		(net "P12V_IOM_PGOOD")
	)
	(segment
		(start 132.989828 -6.5532)
		(end 134.898638 -4.64439)
		(width 0.127)
		(layer "In5.Cu")
		(net "P12V_IOM_PGOOD")
	)
	(segment
		(start 63.805054 -180.53304)
		(end 65.193164 -181.92115)
		(width 0.127)
		(layer "F.Cu")
		(net "IOM_STBY_PGOOD")
	)
	(segment
		(start 83.596226 -170.1419)
		(end 83.312 -170.1419)
		(width 0.127)
		(layer "F.Cu")
		(net "IOM_STBY_PGOOD")
	)
	(segment
		(start 96.175576 -88.406224)
		(end 96.175576 -85.134958)
		(width 0.127)
		(layer "F.Cu")
		(net "IOM_STBY_PGOOD")
	)
	(segment
		(start 97.28962 -89.520268)
		(end 96.175576 -88.406224)
		(width 0.127)
		(layer "F.Cu")
		(net "IOM_STBY_PGOOD")
	)
	(segment
		(start 94.361 -54.5084)
		(end 93.2688 -54.5084)
		(width 0.127)
		(layer "F.Cu")
		(net "IOM_STBY_PGOOD")
	)
	(segment
		(start 84.22132 -170.7007)
		(end 84.155026 -170.7007)
		(width 0.127)
		(layer "F.Cu")
		(net "IOM_STBY_PGOOD")
	)
	(segment
		(start 95.533972 -84.493354)
		(end 95.533972 -55.681372)
		(width 0.127)
		(layer "F.Cu")
		(net "IOM_STBY_PGOOD")
	)
	(segment
		(start 65.368932 -182.096918)
		(end 65.193164 -181.92115)
		(width 0.127)
		(layer "F.Cu")
		(net "IOM_STBY_PGOOD")
	)
	(segment
		(start 85.3948 -171.958)
		(end 85.3948 -171.87418)
		(width 0.127)
		(layer "F.Cu")
		(net "IOM_STBY_PGOOD")
	)
	(segment
		(start 63.459868 -180.53304)
		(end 63.805054 -180.53304)
		(width 0.127)
		(layer "F.Cu")
		(net "IOM_STBY_PGOOD")
	)
	(segment
		(start 83.312 -170.1419)
		(end 83.312 -169.523664)
		(width 0.127)
		(layer "F.Cu")
		(net "IOM_STBY_PGOOD")
	)
	(segment
		(start 95.533972 -55.681372)
		(end 94.361 -54.5084)
		(width 0.127)
		(layer "F.Cu")
		(net "IOM_STBY_PGOOD")
	)
	(segment
		(start 85.3948 -171.87418)
		(end 84.22132 -170.7007)
		(width 0.127)
		(layer "F.Cu")
		(net "IOM_STBY_PGOOD")
	)
	(segment
		(start 66.630042 -182.096918)
		(end 65.368932 -182.096918)
		(width 0.127)
		(layer "F.Cu")
		(net "IOM_STBY_PGOOD")
	)
	(segment
		(start 83.312 -169.523664)
		(end 84.184744 -168.65092)
		(width 0.127)
		(layer "F.Cu")
		(net "IOM_STBY_PGOOD")
	)
	(segment
		(start 84.155026 -170.7007)
		(end 83.596226 -170.1419)
		(width 0.127)
		(layer "F.Cu")
		(net "IOM_STBY_PGOOD")
	)
	(segment
		(start 96.175576 -85.134958)
		(end 95.533972 -84.493354)
		(width 0.127)
		(layer "F.Cu")
		(net "IOM_STBY_PGOOD")
	)
	(segment
		(start 93.09989 -54.67731)
		(end 93.09989 -55.352442)
		(width 0.127)
		(layer "F.Cu")
		(net "IOM_STBY_PGOOD")
	)
	(segment
		(start 93.2688 -54.5084)
		(end 93.09989 -54.67731)
		(width 0.127)
		(layer "F.Cu")
		(net "IOM_STBY_PGOOD")
	)
	(via
		(at 85.3948 -171.958)
		(size 0.508)
		(drill 0.254)
		(layers "F.Cu" "B.Cu")
		(net "IOM_STBY_PGOOD")
	)
	(via
		(at 66.630042 -182.096918)
		(size 0.508)
		(drill 0.254)
		(layers "F.Cu" "B.Cu")
		(net "IOM_STBY_PGOOD")
	)
	(via
		(at 65.193164 -181.92115)
		(size 0.6604)
		(drill 0.3302)
		(layers "F.Cu" "B.Cu")
		(net "IOM_STBY_PGOOD")
	)
	(via
		(at 99.7712 -172.1104)
		(size 0.508)
		(drill 0.254)
		(layers "F.Cu" "B.Cu")
		(net "IOM_STBY_PGOOD")
	)
	(via
		(at 73.5838 -172.42282)
		(size 0.508)
		(drill 0.254)
		(layers "F.Cu" "B.Cu")
		(net "IOM_STBY_PGOOD")
	)
	(via
		(at 97.28962 -89.520268)
		(size 0.508)
		(drill 0.254)
		(layers "F.Cu" "B.Cu")
		(net "IOM_STBY_PGOOD")
	)
	(via
		(at 71.284084 -182.25516)
		(size 0.508)
		(drill 0.254)
		(layers "F.Cu" "B.Cu")
		(net "IOM_STBY_PGOOD")
	)
	(segment
		(start 100.663502 -143.96085)
		(end 100.4443 -143.741648)
		(width 0.127)
		(layer "B.Cu")
		(net "IOM_STBY_PGOOD")
	)
	(segment
		(start 100.4443 -143.741648)
		(end 100.4443 -140.650976)
		(width 0.127)
		(layer "B.Cu")
		(net "IOM_STBY_PGOOD")
	)
	(segment
		(start 101.295454 -169.59961)
		(end 101.295454 -167.1701)
		(width 0.127)
		(layer "B.Cu")
		(net "IOM_STBY_PGOOD")
	)
	(segment
		(start 100.684584 -172.1104)
		(end 100.915724 -171.87926)
		(width 0.127)
		(layer "B.Cu")
		(net "IOM_STBY_PGOOD")
	)
	(segment
		(start 100.663502 -166.538148)
		(end 100.663502 -143.96085)
		(width 0.127)
		(layer "B.Cu")
		(net "IOM_STBY_PGOOD")
	)
	(segment
		(start 101.076252 -140.019024)
		(end 101.076252 -128.469136)
		(width 0.127)
		(layer "B.Cu")
		(net "IOM_STBY_PGOOD")
	)
	(segment
		(start 100.915724 -169.97934)
		(end 101.295454 -169.59961)
		(width 0.127)
		(layer "B.Cu")
		(net "IOM_STBY_PGOOD")
	)
	(segment
		(start 100.917248 -128.310132)
		(end 100.917248 -93.147896)
		(width 0.127)
		(layer "B.Cu")
		(net "IOM_STBY_PGOOD")
	)
	(segment
		(start 101.295454 -167.1701)
		(end 100.663502 -166.538148)
		(width 0.127)
		(layer "B.Cu")
		(net "IOM_STBY_PGOOD")
	)
	(segment
		(start 99.7712 -172.1104)
		(end 100.684584 -172.1104)
		(width 0.127)
		(layer "B.Cu")
		(net "IOM_STBY_PGOOD")
	)
	(segment
		(start 100.915724 -171.87926)
		(end 100.915724 -169.97934)
		(width 0.127)
		(layer "B.Cu")
		(net "IOM_STBY_PGOOD")
	)
	(segment
		(start 100.917248 -93.147896)
		(end 97.28962 -89.520268)
		(width 0.127)
		(layer "B.Cu")
		(net "IOM_STBY_PGOOD")
	)
	(segment
		(start 100.4443 -140.650976)
		(end 101.076252 -140.019024)
		(width 0.127)
		(layer "B.Cu")
		(net "IOM_STBY_PGOOD")
	)
	(segment
		(start 101.076252 -128.469136)
		(end 100.917248 -128.310132)
		(width 0.127)
		(layer "B.Cu")
		(net "IOM_STBY_PGOOD")
	)
	(segment
		(start 72.40778 -181.131464)
		(end 71.284084 -182.25516)
		(width 0.127)
		(layer "In2.Cu")
		(net "IOM_STBY_PGOOD")
	)
	(segment
		(start 72.40778 -177.13198)
		(end 72.40778 -181.131464)
		(width 0.127)
		(layer "In2.Cu")
		(net "IOM_STBY_PGOOD")
	)
	(segment
		(start 73.4314 -176.10836)
		(end 72.40778 -177.13198)
		(width 0.127)
		(layer "In2.Cu")
		(net "IOM_STBY_PGOOD")
	)
	(segment
		(start 73.5838 -172.42282)
		(end 73.4314 -172.57522)
		(width 0.127)
		(layer "In2.Cu")
		(net "IOM_STBY_PGOOD")
	)
	(segment
		(start 73.4314 -172.57522)
		(end 73.4314 -176.10836)
		(width 0.127)
		(layer "In2.Cu")
		(net "IOM_STBY_PGOOD")
	)
	(segment
		(start 66.630042 -182.096918)
		(end 68.322698 -182.096918)
		(width 0.127)
		(layer "In5.Cu")
		(net "IOM_STBY_PGOOD")
	)
	(segment
		(start 85.3948 -171.958)
		(end 88.251284 -171.958)
		(width 0.127)
		(layer "In5.Cu")
		(net "IOM_STBY_PGOOD")
	)
	(segment
		(start 68.48094 -182.25516)
		(end 71.284084 -182.25516)
		(width 0.127)
		(layer "In5.Cu")
		(net "IOM_STBY_PGOOD")
	)
	(segment
		(start 74.303382 -173.1137)
		(end 73.612502 -172.42282)
		(width 0.127)
		(layer "In5.Cu")
		(net "IOM_STBY_PGOOD")
	)
	(segment
		(start 90.857324 -172.0342)
		(end 96.200976 -172.0342)
		(width 0.127)
		(layer "In5.Cu")
		(net "IOM_STBY_PGOOD")
	)
	(segment
		(start 90.781124 -172.1104)
		(end 90.857324 -172.0342)
		(width 0.127)
		(layer "In5.Cu")
		(net "IOM_STBY_PGOOD")
	)
	(segment
		(start 96.200976 -172.0342)
		(end 96.277176 -172.1104)
		(width 0.127)
		(layer "In5.Cu")
		(net "IOM_STBY_PGOOD")
	)
	(segment
		(start 88.251284 -171.958)
		(end 88.403684 -172.1104)
		(width 0.127)
		(layer "In5.Cu")
		(net "IOM_STBY_PGOOD")
	)
	(segment
		(start 85.3948 -171.958)
		(end 83.998054 -171.958)
		(width 0.127)
		(layer "In5.Cu")
		(net "IOM_STBY_PGOOD")
	)
	(segment
		(start 82.842354 -173.1137)
		(end 74.303382 -173.1137)
		(width 0.127)
		(layer "In5.Cu")
		(net "IOM_STBY_PGOOD")
	)
	(segment
		(start 73.612502 -172.42282)
		(end 73.5838 -172.42282)
		(width 0.127)
		(layer "In5.Cu")
		(net "IOM_STBY_PGOOD")
	)
	(segment
		(start 88.403684 -172.1104)
		(end 90.781124 -172.1104)
		(width 0.127)
		(layer "In5.Cu")
		(net "IOM_STBY_PGOOD")
	)
	(segment
		(start 83.998054 -171.958)
		(end 82.842354 -173.1137)
		(width 0.127)
		(layer "In5.Cu")
		(net "IOM_STBY_PGOOD")
	)
	(segment
		(start 96.277176 -172.1104)
		(end 99.7712 -172.1104)
		(width 0.127)
		(layer "In5.Cu")
		(net "IOM_STBY_PGOOD")
	)
	(segment
		(start 68.322698 -182.096918)
		(end 68.48094 -182.25516)
		(width 0.127)
		(layer "In5.Cu")
		(net "IOM_STBY_PGOOD")
	)
	(segment
		(start 41.6179 -133.5405)
		(end 41.8719 -133.7945)
		(width 0.127)
		(layer "F.Cu")
		(net "IOM_FULL_PGOOD")
	)
	(segment
		(start 37.92347 -119.237506)
		(end 37.92347 -123.954794)
		(width 0.127)
		(layer "F.Cu")
		(net "IOM_FULL_PGOOD")
	)
	(segment
		(start 41.8719 -133.798818)
		(end 42.328338 -134.255256)
		(width 0.127)
		(layer "F.Cu")
		(net "IOM_FULL_PGOOD")
	)
	(segment
		(start 181.427628 -121.412)
		(end 179.959 -121.412)
		(width 0.127)
		(layer "F.Cu")
		(net "IOM_FULL_PGOOD")
	)
	(segment
		(start 42.328338 -135.328406)
		(end 43.153838 -136.153906)
		(width 0.127)
		(layer "F.Cu")
		(net "IOM_FULL_PGOOD")
	)
	(segment
		(start 179.167536 -120.620536)
		(end 179.167536 -119.61622)
		(width 0.127)
		(layer "F.Cu")
		(net "IOM_FULL_PGOOD")
	)
	(segment
		(start 160.978088 -96.416114)
		(end 161.887662 -96.416114)
		(width 0.127)
		(layer "F.Cu")
		(net "IOM_FULL_PGOOD")
	)
	(segment
		(start 43.153838 -136.153906)
		(end 43.503342 -136.153906)
		(width 0.127)
		(layer "F.Cu")
		(net "IOM_FULL_PGOOD")
	)
	(segment
		(start 187.0964 -127)
		(end 187.551568 -126.544832)
		(width 0.127)
		(layer "F.Cu")
		(net "IOM_FULL_PGOOD")
	)
	(segment
		(start 43.748706 -136.39927)
		(end 43.748706 -137.306812)
		(width 0.127)
		(layer "F.Cu")
		(net "IOM_FULL_PGOOD")
	)
	(segment
		(start 41.6179 -127.649224)
		(end 41.6179 -133.5405)
		(width 0.127)
		(layer "F.Cu")
		(net "IOM_FULL_PGOOD")
	)
	(segment
		(start 40.003984 -117.156992)
		(end 37.92347 -119.237506)
		(width 0.127)
		(layer "F.Cu")
		(net "IOM_FULL_PGOOD")
	)
	(segment
		(start 42.328338 -134.255256)
		(end 42.328338 -135.328406)
		(width 0.127)
		(layer "F.Cu")
		(net "IOM_FULL_PGOOD")
	)
	(segment
		(start 41.8719 -133.7945)
		(end 41.8719 -133.798818)
		(width 0.127)
		(layer "F.Cu")
		(net "IOM_FULL_PGOOD")
	)
	(segment
		(start 43.503342 -136.153906)
		(end 43.748706 -136.39927)
		(width 0.127)
		(layer "F.Cu")
		(net "IOM_FULL_PGOOD")
	)
	(segment
		(start 179.959 -121.412)
		(end 179.167536 -120.620536)
		(width 0.127)
		(layer "F.Cu")
		(net "IOM_FULL_PGOOD")
	)
	(segment
		(start 188.180726 -124.74321)
		(end 188.180726 -124.146564)
		(width 0.127)
		(layer "F.Cu")
		(net "IOM_FULL_PGOOD")
	)
	(segment
		(start 187.551568 -125.372368)
		(end 188.180726 -124.74321)
		(width 0.127)
		(layer "F.Cu")
		(net "IOM_FULL_PGOOD")
	)
	(segment
		(start 43.841924 -137.40003)
		(end 44.099988 -137.40003)
		(width 0.127)
		(layer "F.Cu")
		(net "IOM_FULL_PGOOD")
	)
	(segment
		(start 187.551568 -126.544832)
		(end 187.551568 -125.372368)
		(width 0.127)
		(layer "F.Cu")
		(net "IOM_FULL_PGOOD")
	)
	(segment
		(start 37.92347 -123.954794)
		(end 41.6179 -127.649224)
		(width 0.127)
		(layer "F.Cu")
		(net "IOM_FULL_PGOOD")
	)
	(segment
		(start 181.709314 -121.693686)
		(end 181.427628 -121.412)
		(width 0.127)
		(layer "F.Cu")
		(net "IOM_FULL_PGOOD")
	)
	(segment
		(start 43.748706 -137.306812)
		(end 43.841924 -137.40003)
		(width 0.127)
		(layer "F.Cu")
		(net "IOM_FULL_PGOOD")
	)
	(via
		(at 40.003984 -117.156992)
		(size 0.508)
		(drill 0.254)
		(layers "F.Cu" "B.Cu")
		(net "IOM_FULL_PGOOD")
	)
	(via
		(at 183.1086 -104.8766)
		(size 0.508)
		(drill 0.254)
		(layers "F.Cu" "B.Cu")
		(net "IOM_FULL_PGOOD")
	)
	(via
		(at 225.18116 -98.804984)
		(size 0.508)
		(drill 0.254)
		(layers "F.Cu" "B.Cu")
		(net "IOM_FULL_PGOOD")
	)
	(via
		(at 161.887662 -96.416114)
		(size 0.508)
		(drill 0.254)
		(layers "F.Cu" "B.Cu")
		(net "IOM_FULL_PGOOD")
	)
	(via
		(at 187.0964 -127)
		(size 0.508)
		(drill 0.254)
		(layers "F.Cu" "B.Cu")
		(net "IOM_FULL_PGOOD")
	)
	(via
		(at 181.709314 -121.693686)
		(size 0.508)
		(drill 0.254)
		(layers "F.Cu" "B.Cu")
		(net "IOM_FULL_PGOOD")
	)
	(via
		(at 183.1086 -110.279688)
		(size 0.6096)
		(drill 0.3048)
		(layers "F.Cu" "B.Cu")
		(net "IOM_FULL_PGOOD")
	)
	(segment
		(start 182.6006 -104.3686)
		(end 183.1086 -104.8766)
		(width 0.127)
		(layer "B.Cu")
		(net "IOM_FULL_PGOOD")
	)
	(segment
		(start 180.8988 -98.8568)
		(end 182.6006 -100.5586)
		(width 0.127)
		(layer "B.Cu")
		(net "IOM_FULL_PGOOD")
	)
	(segment
		(start 180.687472 -119.041672)
		(end 181.709314 -120.063514)
		(width 0.127)
		(layer "B.Cu")
		(net "IOM_FULL_PGOOD")
	)
	(segment
		(start 161.887662 -96.416114)
		(end 166.445946 -96.416114)
		(width 0.127)
		(layer "B.Cu")
		(net "IOM_FULL_PGOOD")
	)
	(segment
		(start 182.6006 -100.5586)
		(end 182.6006 -104.3686)
		(width 0.127)
		(layer "B.Cu")
		(net "IOM_FULL_PGOOD")
	)
	(segment
		(start 180.0606 -114.8461)
		(end 179.9082 -114.9985)
		(width 0.127)
		(layer "B.Cu")
		(net "IOM_FULL_PGOOD")
	)
	(segment
		(start 180.15966 -114.8461)
		(end 180.0606 -114.8461)
		(width 0.127)
		(layer "B.Cu")
		(net "IOM_FULL_PGOOD")
	)
	(segment
		(start 180.687472 -116.909596)
		(end 180.687472 -119.041672)
		(width 0.127)
		(layer "B.Cu")
		(net "IOM_FULL_PGOOD")
	)
	(segment
		(start 183.1086 -111.89716)
		(end 180.15966 -114.8461)
		(width 0.127)
		(layer "B.Cu")
		(net "IOM_FULL_PGOOD")
	)
	(segment
		(start 183.1086 -110.279688)
		(end 183.1086 -104.8766)
		(width 0.127)
		(layer "B.Cu")
		(net "IOM_FULL_PGOOD")
	)
	(segment
		(start 179.9082 -114.9985)
		(end 179.9082 -116.130324)
		(width 0.127)
		(layer "B.Cu")
		(net "IOM_FULL_PGOOD")
	)
	(segment
		(start 168.886632 -98.8568)
		(end 180.8988 -98.8568)
		(width 0.127)
		(layer "B.Cu")
		(net "IOM_FULL_PGOOD")
	)
	(segment
		(start 179.9082 -116.130324)
		(end 180.687472 -116.909596)
		(width 0.127)
		(layer "B.Cu")
		(net "IOM_FULL_PGOOD")
	)
	(segment
		(start 166.445946 -96.416114)
		(end 168.886632 -98.8568)
		(width 0.127)
		(layer "B.Cu")
		(net "IOM_FULL_PGOOD")
	)
	(segment
		(start 181.709314 -120.063514)
		(end 181.709314 -121.693686)
		(width 0.127)
		(layer "B.Cu")
		(net "IOM_FULL_PGOOD")
	)
	(segment
		(start 183.1086 -110.279688)
		(end 183.1086 -111.89716)
		(width 0.127)
		(layer "B.Cu")
		(net "IOM_FULL_PGOOD")
	)
	(segment
		(start 222.23476 -54.919372)
		(end 222.23476 -80.552544)
		(width 0.127)
		(layer "In2.Cu")
		(net "IOM_FULL_PGOOD")
	)
	(segment
		(start 81.27492 -107.5944)
		(end 82.867246 -106.002074)
		(width 0.127)
		(layer "In2.Cu")
		(net "IOM_FULL_PGOOD")
	)
	(segment
		(start 188.227462 -21.593048)
		(end 194.00266 -27.368246)
		(width 0.127)
		(layer "In2.Cu")
		(net "IOM_FULL_PGOOD")
	)
	(segment
		(start 76.19238 -7.09422)
		(end 80.1243 -3.1623)
		(width 0.127)
		(layer "In2.Cu")
		(net "IOM_FULL_PGOOD")
	)
	(segment
		(start 132.57403 -1.68148)
		(end 133.030722 -1.681226)
		(width 0.127)
		(layer "In2.Cu")
		(net "IOM_FULL_PGOOD")
	)
	(segment
		(start 194.00266 -27.368246)
		(end 194.10045 -27.368246)
		(width 0.127)
		(layer "In2.Cu")
		(net "IOM_FULL_PGOOD")
	)
	(segment
		(start 82.867246 -106.002074)
		(end 82.867246 -104.069896)
		(width 0.127)
		(layer "In2.Cu")
		(net "IOM_FULL_PGOOD")
	)
	(segment
		(start 76.6318 -49.440084)
		(end 78.862174 -47.20971)
		(width 0.127)
		(layer "In2.Cu")
		(net "IOM_FULL_PGOOD")
	)
	(segment
		(start 73.59269 -111.7092)
		(end 77.70749 -107.5944)
		(width 0.127)
		(layer "In2.Cu")
		(net "IOM_FULL_PGOOD")
	)
	(segment
		(start 168.918382 -2.3876)
		(end 186.212988 -2.3876)
		(width 0.127)
		(layer "In2.Cu")
		(net "IOM_FULL_PGOOD")
	)
	(segment
		(start 168.212008 -1.681226)
		(end 168.918382 -2.3876)
		(width 0.127)
		(layer "In2.Cu")
		(net "IOM_FULL_PGOOD")
	)
	(segment
		(start 40.003984 -117.156992)
		(end 41.209976 -115.951)
		(width 0.127)
		(layer "In2.Cu")
		(net "IOM_FULL_PGOOD")
	)
	(segment
		(start 77.70749 -107.5944)
		(end 81.27492 -107.5944)
		(width 0.127)
		(layer "In2.Cu")
		(net "IOM_FULL_PGOOD")
	)
	(segment
		(start 75.210416 -41.955974)
		(end 75.210416 -9.055608)
		(width 0.127)
		(layer "In2.Cu")
		(net "IOM_FULL_PGOOD")
	)
	(segment
		(start 188.227462 -4.402074)
		(end 188.227462 -21.593048)
		(width 0.127)
		(layer "In2.Cu")
		(net "IOM_FULL_PGOOD")
	)
	(segment
		(start 186.212988 -2.3876)
		(end 188.227462 -4.402074)
		(width 0.127)
		(layer "In2.Cu")
		(net "IOM_FULL_PGOOD")
	)
	(segment
		(start 55.2958 -115.951)
		(end 59.5376 -111.7092)
		(width 0.127)
		(layer "In2.Cu")
		(net "IOM_FULL_PGOOD")
	)
	(segment
		(start 224.0915 -82.409284)
		(end 224.0915 -97.715324)
		(width 0.127)
		(layer "In2.Cu")
		(net "IOM_FULL_PGOOD")
	)
	(segment
		(start 198.688198 -31.37281)
		(end 222.23476 -54.919372)
		(width 0.127)
		(layer "In2.Cu")
		(net "IOM_FULL_PGOOD")
	)
	(segment
		(start 194.881754 -28.24734)
		(end 198.007224 -31.37281)
		(width 0.127)
		(layer "In2.Cu")
		(net "IOM_FULL_PGOOD")
	)
	(segment
		(start 80.1243 -3.1623)
		(end 82.459068 -3.1623)
		(width 0.127)
		(layer "In2.Cu")
		(net "IOM_FULL_PGOOD")
	)
	(segment
		(start 75.210416 -9.055608)
		(end 76.19238 -8.073644)
		(width 0.127)
		(layer "In2.Cu")
		(net "IOM_FULL_PGOOD")
	)
	(segment
		(start 59.5376 -111.7092)
		(end 73.59269 -111.7092)
		(width 0.127)
		(layer "In2.Cu")
		(net "IOM_FULL_PGOOD")
	)
	(segment
		(start 41.209976 -115.951)
		(end 55.2958 -115.951)
		(width 0.127)
		(layer "In2.Cu")
		(net "IOM_FULL_PGOOD")
	)
	(segment
		(start 83.939888 -1.68148)
		(end 132.57403 -1.68148)
		(width 0.127)
		(layer "In2.Cu")
		(net "IOM_FULL_PGOOD")
	)
	(segment
		(start 224.0915 -97.715324)
		(end 225.18116 -98.804984)
		(width 0.127)
		(layer "In2.Cu")
		(net "IOM_FULL_PGOOD")
	)
	(segment
		(start 75.737466 -95.504)
		(end 76.6318 -94.609666)
		(width 0.127)
		(layer "In2.Cu")
		(net "IOM_FULL_PGOOD")
	)
	(segment
		(start 82.867246 -104.069896)
		(end 81.244948 -102.447598)
		(width 0.127)
		(layer "In2.Cu")
		(net "IOM_FULL_PGOOD")
	)
	(segment
		(start 76.19238 -8.073644)
		(end 76.19238 -7.09422)
		(width 0.127)
		(layer "In2.Cu")
		(net "IOM_FULL_PGOOD")
	)
	(segment
		(start 81.244948 -102.447598)
		(end 79.308198 -102.447598)
		(width 0.127)
		(layer "In2.Cu")
		(net "IOM_FULL_PGOOD")
	)
	(segment
		(start 194.10045 -27.368246)
		(end 194.881754 -28.14955)
		(width 0.127)
		(layer "In2.Cu")
		(net "IOM_FULL_PGOOD")
	)
	(segment
		(start 198.007224 -31.37281)
		(end 198.688198 -31.37281)
		(width 0.127)
		(layer "In2.Cu")
		(net "IOM_FULL_PGOOD")
	)
	(segment
		(start 75.737466 -98.876866)
		(end 75.737466 -95.504)
		(width 0.127)
		(layer "In2.Cu")
		(net "IOM_FULL_PGOOD")
	)
	(segment
		(start 78.862174 -45.607732)
		(end 75.210416 -41.955974)
		(width 0.127)
		(layer "In2.Cu")
		(net "IOM_FULL_PGOOD")
	)
	(segment
		(start 76.6318 -94.609666)
		(end 76.6318 -49.440084)
		(width 0.127)
		(layer "In2.Cu")
		(net "IOM_FULL_PGOOD")
	)
	(segment
		(start 79.308198 -102.447598)
		(end 75.737466 -98.876866)
		(width 0.127)
		(layer "In2.Cu")
		(net "IOM_FULL_PGOOD")
	)
	(segment
		(start 222.23476 -80.552544)
		(end 224.0915 -82.409284)
		(width 0.127)
		(layer "In2.Cu")
		(net "IOM_FULL_PGOOD")
	)
	(segment
		(start 82.459068 -3.1623)
		(end 83.939888 -1.68148)
		(width 0.127)
		(layer "In2.Cu")
		(net "IOM_FULL_PGOOD")
	)
	(segment
		(start 78.862174 -47.20971)
		(end 78.862174 -45.607732)
		(width 0.127)
		(layer "In2.Cu")
		(net "IOM_FULL_PGOOD")
	)
	(segment
		(start 133.030722 -1.681226)
		(end 168.212008 -1.681226)
		(width 0.127)
		(layer "In2.Cu")
		(net "IOM_FULL_PGOOD")
	)
	(segment
		(start 194.881754 -28.14955)
		(end 194.881754 -28.24734)
		(width 0.127)
		(layer "In2.Cu")
		(net "IOM_FULL_PGOOD")
	)
	(segment
		(start 181.7116 -122.1486)
		(end 181.7116 -121.695972)
		(width 0.127)
		(layer "In5.Cu")
		(net "IOM_FULL_PGOOD")
	)
	(segment
		(start 204.8764 -105.0036)
		(end 202.2348 -102.362)
		(width 0.127)
		(layer "In5.Cu")
		(net "IOM_FULL_PGOOD")
	)
	(segment
		(start 181.7116 -121.695972)
		(end 181.709314 -121.693686)
		(width 0.127)
		(layer "In5.Cu")
		(net "IOM_FULL_PGOOD")
	)
	(segment
		(start 219.1512 -105.0036)
		(end 204.8764 -105.0036)
		(width 0.127)
		(layer "In5.Cu")
		(net "IOM_FULL_PGOOD")
	)
	(segment
		(start 220.8022 -103.3526)
		(end 219.1512 -105.0036)
		(width 0.127)
		(layer "In5.Cu")
		(net "IOM_FULL_PGOOD")
	)
	(segment
		(start 202.2348 -102.362)
		(end 188.656976 -102.362)
		(width 0.127)
		(layer "In5.Cu")
		(net "IOM_FULL_PGOOD")
	)
	(segment
		(start 183.919876 -104.065324)
		(end 183.1086 -104.8766)
		(width 0.127)
		(layer "In5.Cu")
		(net "IOM_FULL_PGOOD")
	)
	(segment
		(start 186.0804 -126.5174)
		(end 181.7116 -122.1486)
		(width 0.127)
		(layer "In5.Cu")
		(net "IOM_FULL_PGOOD")
	)
	(segment
		(start 187.0964 -127)
		(end 186.6138 -126.5174)
		(width 0.127)
		(layer "In5.Cu")
		(net "IOM_FULL_PGOOD")
	)
	(segment
		(start 225.18116 -98.804984)
		(end 225.18116 -101.121972)
		(width 0.127)
		(layer "In5.Cu")
		(net "IOM_FULL_PGOOD")
	)
	(segment
		(start 225.18116 -101.121972)
		(end 222.950532 -103.3526)
		(width 0.127)
		(layer "In5.Cu")
		(net "IOM_FULL_PGOOD")
	)
	(segment
		(start 186.6138 -126.5174)
		(end 186.0804 -126.5174)
		(width 0.127)
		(layer "In5.Cu")
		(net "IOM_FULL_PGOOD")
	)
	(segment
		(start 186.953652 -104.065324)
		(end 183.919876 -104.065324)
		(width 0.127)
		(layer "In5.Cu")
		(net "IOM_FULL_PGOOD")
	)
	(segment
		(start 222.950532 -103.3526)
		(end 220.8022 -103.3526)
		(width 0.127)
		(layer "In5.Cu")
		(net "IOM_FULL_PGOOD")
	)
	(segment
		(start 188.656976 -102.362)
		(end 186.953652 -104.065324)
		(width 0.127)
		(layer "In5.Cu")
		(net "IOM_FULL_PGOOD")
	)
	(segment
		(start 50.818796 -124.999496)
		(end 50.8381 -125.0188)
		(width 0.127)
		(layer "F.Cu")
		(net "DPB_MISC_ALERT_OUT")
	)
	(segment
		(start 50.8381 -125.0188)
		(end 50.8381 -125.8824)
		(width 0.127)
		(layer "F.Cu")
		(net "DPB_MISC_ALERT_OUT")
	)
	(segment
		(start 50.8254 -124.8918)
		(end 50.818796 -124.898404)
		(width 0.127)
		(layer "F.Cu")
		(net "DPB_MISC_ALERT_OUT")
	)
	(segment
		(start 99.695 -171.069)
		(end 99.2632 -170.6372)
		(width 0.127)
		(layer "F.Cu")
		(net "DPB_MISC_ALERT_OUT")
	)
	(segment
		(start 50.818796 -124.898404)
		(end 50.818796 -124.999496)
		(width 0.127)
		(layer "F.Cu")
		(net "DPB_MISC_ALERT_OUT")
	)
	(segment
		(start 99.2632 -170.6372)
		(end 98.8441 -170.6372)
		(width 0.127)
		(layer "F.Cu")
		(net "DPB_MISC_ALERT_OUT")
	)
	(via
		(at 99.695 -171.069)
		(size 0.508)
		(drill 0.254)
		(layers "F.Cu" "B.Cu")
		(net "DPB_MISC_ALERT_OUT")
	)
	(via
		(at 50.8254 -124.8918)
		(size 0.508)
		(drill 0.254)
		(layers "F.Cu" "B.Cu")
		(net "DPB_MISC_ALERT_OUT")
	)
	(via
		(at 50.6476 -134.4676)
		(size 0.508)
		(drill 0.254)
		(layers "F.Cu" "B.Cu")
		(net "DPB_MISC_ALERT_OUT")
	)
	(via
		(at 98.879152 -122.809)
		(size 0.508)
		(drill 0.254)
		(layers "F.Cu" "B.Cu")
		(net "DPB_MISC_ALERT_OUT")
	)
	(segment
		(start 50.6476 -135.1153)
		(end 50.6476 -134.4676)
		(width 0.127)
		(layer "B.Cu")
		(net "DPB_MISC_ALERT_OUT")
	)
	(segment
		(start 50.4444 -135.3185)
		(end 50.6476 -135.1153)
		(width 0.127)
		(layer "B.Cu")
		(net "DPB_MISC_ALERT_OUT")
	)
	(segment
		(start 98.879152 -122.809)
		(end 98.483166 -123.204986)
		(width 0.127)
		(layer "In2.Cu")
		(net "DPB_MISC_ALERT_OUT")
	)
	(segment
		(start 98.436938 -147.389088)
		(end 98.59137 -147.54352)
		(width 0.127)
		(layer "In2.Cu")
		(net "DPB_MISC_ALERT_OUT")
	)
	(segment
		(start 51.0921 -131.0005)
		(end 50.6476 -131.445)
		(width 0.127)
		(layer "In2.Cu")
		(net "DPB_MISC_ALERT_OUT")
	)
	(segment
		(start 98.59137 -148.338032)
		(end 99.735894 -149.482556)
		(width 0.127)
		(layer "In2.Cu")
		(net "DPB_MISC_ALERT_OUT")
	)
	(segment
		(start 50.8254 -124.8918)
		(end 50.8254 -128.016)
		(width 0.127)
		(layer "In2.Cu")
		(net "DPB_MISC_ALERT_OUT")
	)
	(segment
		(start 98.914458 -142.791688)
		(end 98.436938 -143.269208)
		(width 0.127)
		(layer "In2.Cu")
		(net "DPB_MISC_ALERT_OUT")
	)
	(segment
		(start 99.245166 -140.00353)
		(end 98.914458 -140.334238)
		(width 0.127)
		(layer "In2.Cu")
		(net "DPB_MISC_ALERT_OUT")
	)
	(segment
		(start 51.0921 -128.2827)
		(end 51.0921 -131.0005)
		(width 0.127)
		(layer "In2.Cu")
		(net "DPB_MISC_ALERT_OUT")
	)
	(segment
		(start 98.914458 -140.334238)
		(end 98.914458 -142.791688)
		(width 0.127)
		(layer "In2.Cu")
		(net "DPB_MISC_ALERT_OUT")
	)
	(segment
		(start 99.826318 -164.018976)
		(end 99.321366 -164.523928)
		(width 0.127)
		(layer "In2.Cu")
		(net "DPB_MISC_ALERT_OUT")
	)
	(segment
		(start 99.735894 -149.482556)
		(end 99.735894 -155.530042)
		(width 0.127)
		(layer "In2.Cu")
		(net "DPB_MISC_ALERT_OUT")
	)
	(segment
		(start 99.826318 -155.620466)
		(end 99.826318 -164.018976)
		(width 0.127)
		(layer "In2.Cu")
		(net "DPB_MISC_ALERT_OUT")
	)
	(segment
		(start 99.321366 -167.143684)
		(end 99.821746 -167.644064)
		(width 0.127)
		(layer "In2.Cu")
		(net "DPB_MISC_ALERT_OUT")
	)
	(segment
		(start 99.821746 -170.942254)
		(end 99.695 -171.069)
		(width 0.127)
		(layer "In2.Cu")
		(net "DPB_MISC_ALERT_OUT")
	)
	(segment
		(start 50.6476 -131.445)
		(end 50.6476 -134.4676)
		(width 0.127)
		(layer "In2.Cu")
		(net "DPB_MISC_ALERT_OUT")
	)
	(segment
		(start 98.436938 -143.269208)
		(end 98.436938 -147.389088)
		(width 0.127)
		(layer "In2.Cu")
		(net "DPB_MISC_ALERT_OUT")
	)
	(segment
		(start 98.59137 -147.54352)
		(end 98.59137 -148.338032)
		(width 0.127)
		(layer "In2.Cu")
		(net "DPB_MISC_ALERT_OUT")
	)
	(segment
		(start 99.321366 -164.523928)
		(end 99.321366 -167.143684)
		(width 0.127)
		(layer "In2.Cu")
		(net "DPB_MISC_ALERT_OUT")
	)
	(segment
		(start 99.245166 -129.957576)
		(end 99.245166 -140.00353)
		(width 0.127)
		(layer "In2.Cu")
		(net "DPB_MISC_ALERT_OUT")
	)
	(segment
		(start 50.8254 -128.016)
		(end 51.0921 -128.2827)
		(width 0.127)
		(layer "In2.Cu")
		(net "DPB_MISC_ALERT_OUT")
	)
	(segment
		(start 98.483166 -129.195576)
		(end 99.245166 -129.957576)
		(width 0.127)
		(layer "In2.Cu")
		(net "DPB_MISC_ALERT_OUT")
	)
	(segment
		(start 98.483166 -123.204986)
		(end 98.483166 -129.195576)
		(width 0.127)
		(layer "In2.Cu")
		(net "DPB_MISC_ALERT_OUT")
	)
	(segment
		(start 99.735894 -155.530042)
		(end 99.826318 -155.620466)
		(width 0.127)
		(layer "In2.Cu")
		(net "DPB_MISC_ALERT_OUT")
	)
	(segment
		(start 99.821746 -167.644064)
		(end 99.821746 -170.942254)
		(width 0.127)
		(layer "In2.Cu")
		(net "DPB_MISC_ALERT_OUT")
	)
	(segment
		(start 86.2076 -122.809)
		(end 98.879152 -122.809)
		(width 0.127)
		(layer "In5.Cu")
		(net "DPB_MISC_ALERT_OUT")
	)
	(segment
		(start 52.610512 -122.793252)
		(end 54.841902 -122.793252)
		(width 0.127)
		(layer "In5.Cu")
		(net "DPB_MISC_ALERT_OUT")
	)
	(segment
		(start 55.080154 -122.555)
		(end 71.33971 -122.555)
		(width 0.127)
		(layer "In5.Cu")
		(net "DPB_MISC_ALERT_OUT")
	)
	(segment
		(start 54.841902 -122.793252)
		(end 55.080154 -122.555)
		(width 0.127)
		(layer "In5.Cu")
		(net "DPB_MISC_ALERT_OUT")
	)
	(segment
		(start 74.378058 -125.593348)
		(end 83.423252 -125.593348)
		(width 0.127)
		(layer "In5.Cu")
		(net "DPB_MISC_ALERT_OUT")
	)
	(segment
		(start 50.8254 -124.8918)
		(end 50.8254 -124.578364)
		(width 0.127)
		(layer "In5.Cu")
		(net "DPB_MISC_ALERT_OUT")
	)
	(segment
		(start 83.423252 -125.593348)
		(end 86.2076 -122.809)
		(width 0.127)
		(layer "In5.Cu")
		(net "DPB_MISC_ALERT_OUT")
	)
	(segment
		(start 71.33971 -122.555)
		(end 74.378058 -125.593348)
		(width 0.127)
		(layer "In5.Cu")
		(net "DPB_MISC_ALERT_OUT")
	)
	(segment
		(start 50.8254 -124.578364)
		(end 52.610512 -122.793252)
		(width 0.127)
		(layer "In5.Cu")
		(net "DPB_MISC_ALERT_OUT")
	)
	(segment
		(start 50.899822 -138.599926)
		(end 50.500026 -138.999722)
		(width 0.127)
		(layer "F.Cu")
		(net "DPB_MISC_ALERT_O_R")
	)
	(segment
		(start 50.500026 -138.999722)
		(end 50.500026 -138.999976)
		(width 0.127)
		(layer "F.Cu")
		(net "DPB_MISC_ALERT_O_R")
	)
	(via
		(at 50.7238 -137.4394)
		(size 0.6096)
		(drill 0.3048)
		(layers "F.Cu" "B.Cu")
		(net "DPB_MISC_ALERT_O_R")
	)
	(via
		(at 50.899822 -138.599926)
		(size 0.4572)
		(drill 0.2032)
		(layers "F.Cu" "B.Cu")
		(net "DPB_MISC_ALERT_O_R")
	)
	(segment
		(start 50.7238 -138.423904)
		(end 50.899822 -138.599926)
		(width 0.127)
		(layer "B.Cu")
		(net "DPB_MISC_ALERT_O_R")
	)
	(segment
		(start 50.7238 -136.4869)
		(end 50.4444 -136.2075)
		(width 0.127)
		(layer "B.Cu")
		(net "DPB_MISC_ALERT_O_R")
	)
	(segment
		(start 50.7238 -137.4394)
		(end 50.7238 -138.423904)
		(width 0.127)
		(layer "B.Cu")
		(net "DPB_MISC_ALERT_O_R")
	)
	(segment
		(start 50.7238 -137.4394)
		(end 50.7238 -136.4869)
		(width 0.127)
		(layer "B.Cu")
		(net "DPB_MISC_ALERT_O_R")
	)
	(via
		(at 83.2104 -131.0386)
		(size 0.6096)
		(drill 0.3048)
		(layers "F.Cu" "B.Cu")
		(net "BMC_TO_EXP_RESET_OUT_R")
	)
	(segment
		(start 83.2104 -131.0386)
		(end 82.2198 -130.048)
		(width 0.127)
		(layer "B.Cu")
		(net "BMC_TO_EXP_RESET_OUT_R")
	)
	(segment
		(start 84.1375 -130.048)
		(end 84.1375 -130.4163)
		(width 0.127)
		(layer "B.Cu")
		(net "BMC_TO_EXP_RESET_OUT_R")
	)
	(segment
		(start 83.5152 -131.0386)
		(end 83.2104 -131.0386)
		(width 0.127)
		(layer "B.Cu")
		(net "BMC_TO_EXP_RESET_OUT_R")
	)
	(segment
		(start 82.2198 -130.048)
		(end 81.4451 -130.048)
		(width 0.127)
		(layer "B.Cu")
		(net "BMC_TO_EXP_RESET_OUT_R")
	)
	(segment
		(start 84.1375 -130.4163)
		(end 83.5152 -131.0386)
		(width 0.127)
		(layer "B.Cu")
		(net "BMC_TO_EXP_RESET_OUT_R")
	)
	(segment
		(start 60.812426 -140.402056)
		(end 59.876182 -141.3383)
		(width 0.127)
		(layer "F.Cu")
		(net "BMC_TO_EXP_RESET_OUT")
	)
	(segment
		(start 59.876182 -141.3383)
		(end 59.861704 -141.3383)
		(width 0.127)
		(layer "F.Cu")
		(net "BMC_TO_EXP_RESET_OUT")
	)
	(segment
		(start 84.536534 -130.91541)
		(end 84.489544 -130.9624)
		(width 0.127)
		(layer "F.Cu")
		(net "BMC_TO_EXP_RESET_OUT")
	)
	(segment
		(start 59.861704 -141.3383)
		(end 59.717686 -141.482318)
		(width 0.127)
		(layer "F.Cu")
		(net "BMC_TO_EXP_RESET_OUT")
	)
	(segment
		(start 84.489544 -130.9624)
		(end 76.61148 -130.9624)
		(width 0.127)
		(layer "F.Cu")
		(net "BMC_TO_EXP_RESET_OUT")
	)
	(segment
		(start 76.073 -130.9624)
		(end 74.036682 -128.926082)
		(width 0.127)
		(layer "F.Cu")
		(net "BMC_TO_EXP_RESET_OUT")
	)
	(segment
		(start 76.61148 -130.9624)
		(end 76.073 -130.9624)
		(width 0.127)
		(layer "F.Cu")
		(net "BMC_TO_EXP_RESET_OUT")
	)
	(segment
		(start 65.151 -129.225548)
		(end 65.151 -129.595118)
		(width 0.127)
		(layer "F.Cu")
		(net "BMC_TO_EXP_RESET_OUT")
	)
	(segment
		(start 59.717686 -141.482318)
		(end 59.502294 -141.482318)
		(width 0.127)
		(layer "F.Cu")
		(net "BMC_TO_EXP_RESET_OUT")
	)
	(segment
		(start 60.83808 -140.349732)
		(end 60.812426 -140.349732)
		(width 0.127)
		(layer "F.Cu")
		(net "BMC_TO_EXP_RESET_OUT")
	)
	(segment
		(start 65.450466 -128.926082)
		(end 65.151 -129.225548)
		(width 0.127)
		(layer "F.Cu")
		(net "BMC_TO_EXP_RESET_OUT")
	)
	(segment
		(start 53.699918 -143.800068)
		(end 54.099968 -143.400018)
		(width 0.127)
		(layer "F.Cu")
		(net "BMC_TO_EXP_RESET_OUT")
	)
	(segment
		(start 59.502294 -141.482318)
		(end 59.336178 -141.648434)
		(width 0.127)
		(layer "F.Cu")
		(net "BMC_TO_EXP_RESET_OUT")
	)
	(segment
		(start 64.837818 -129.9083)
		(end 60.5917 -129.9083)
		(width 0.127)
		(layer "F.Cu")
		(net "BMC_TO_EXP_RESET_OUT")
	)
	(segment
		(start 60.5917 -129.9083)
		(end 60.5536 -129.8702)
		(width 0.127)
		(layer "F.Cu")
		(net "BMC_TO_EXP_RESET_OUT")
	)
	(segment
		(start 65.151 -129.595118)
		(end 64.837818 -129.9083)
		(width 0.127)
		(layer "F.Cu")
		(net "BMC_TO_EXP_RESET_OUT")
	)
	(segment
		(start 74.036682 -128.926082)
		(end 65.450466 -128.926082)
		(width 0.127)
		(layer "F.Cu")
		(net "BMC_TO_EXP_RESET_OUT")
	)
	(segment
		(start 60.812426 -140.349732)
		(end 60.812426 -140.402056)
		(width 0.127)
		(layer "F.Cu")
		(net "BMC_TO_EXP_RESET_OUT")
	)
	(via
		(at 54.099968 -143.400018)
		(size 0.4572)
		(drill 0.2032)
		(layers "F.Cu" "B.Cu")
		(net "BMC_TO_EXP_RESET_OUT")
	)
	(via
		(at 76.61148 -130.9624)
		(size 0.6604)
		(drill 0.3302)
		(layers "F.Cu" "B.Cu")
		(net "BMC_TO_EXP_RESET_OUT")
	)
	(via
		(at 60.5536 -129.8702)
		(size 0.508)
		(drill 0.254)
		(layers "F.Cu" "B.Cu")
		(net "BMC_TO_EXP_RESET_OUT")
	)
	(via
		(at 84.536534 -130.91541)
		(size 0.508)
		(drill 0.254)
		(layers "F.Cu" "B.Cu")
		(net "BMC_TO_EXP_RESET_OUT")
	)
	(via
		(at 59.336178 -141.648434)
		(size 0.508)
		(drill 0.254)
		(layers "F.Cu" "B.Cu")
		(net "BMC_TO_EXP_RESET_OUT")
	)
	(segment
		(start 84.57819 -130.91541)
		(end 85.0265 -130.4671)
		(width 0.127)
		(layer "B.Cu")
		(net "BMC_TO_EXP_RESET_OUT")
	)
	(segment
		(start 85.0265 -130.4671)
		(end 85.0265 -130.048)
		(width 0.127)
		(layer "B.Cu")
		(net "BMC_TO_EXP_RESET_OUT")
	)
	(segment
		(start 84.536534 -130.91541)
		(end 84.57819 -130.91541)
		(width 0.127)
		(layer "B.Cu")
		(net "BMC_TO_EXP_RESET_OUT")
	)
	(segment
		(start 58.683906 -139.405868)
		(end 59.408568 -138.681206)
		(width 0.127)
		(layer "In2.Cu")
		(net "BMC_TO_EXP_RESET_OUT")
	)
	(segment
		(start 59.408568 -136.555734)
		(end 60.1091 -135.855202)
		(width 0.127)
		(layer "In2.Cu")
		(net "BMC_TO_EXP_RESET_OUT")
	)
	(segment
		(start 59.336178 -141.648434)
		(end 58.683906 -140.996162)
		(width 0.127)
		(layer "In2.Cu")
		(net "BMC_TO_EXP_RESET_OUT")
	)
	(segment
		(start 60.1091 -130.3147)
		(end 60.5536 -129.8702)
		(width 0.127)
		(layer "In2.Cu")
		(net "BMC_TO_EXP_RESET_OUT")
	)
	(segment
		(start 58.683906 -140.996162)
		(end 58.683906 -139.405868)
		(width 0.127)
		(layer "In2.Cu")
		(net "BMC_TO_EXP_RESET_OUT")
	)
	(segment
		(start 60.1091 -135.855202)
		(end 60.1091 -130.3147)
		(width 0.127)
		(layer "In2.Cu")
		(net "BMC_TO_EXP_RESET_OUT")
	)
	(segment
		(start 59.408568 -138.681206)
		(end 59.408568 -136.555734)
		(width 0.127)
		(layer "In2.Cu")
		(net "BMC_TO_EXP_RESET_OUT")
	)
	(segment
		(start 59.336178 -141.648434)
		(end 58.031126 -141.648434)
		(width 0.127)
		(layer "In5.Cu")
		(net "BMC_TO_EXP_RESET_OUT")
	)
	(segment
		(start 58.031126 -141.648434)
		(end 56.672734 -143.006826)
		(width 0.127)
		(layer "In5.Cu")
		(net "BMC_TO_EXP_RESET_OUT")
	)
	(segment
		(start 54.736492 -143.006826)
		(end 54.564534 -143.178784)
		(width 0.127)
		(layer "In5.Cu")
		(net "BMC_TO_EXP_RESET_OUT")
	)
	(segment
		(start 54.358032 -143.222218)
		(end 54.277768 -143.222218)
		(width 0.127)
		(layer "In5.Cu")
		(net "BMC_TO_EXP_RESET_OUT")
	)
	(segment
		(start 54.401466 -143.178784)
		(end 54.358032 -143.222218)
		(width 0.127)
		(layer "In5.Cu")
		(net "BMC_TO_EXP_RESET_OUT")
	)
	(segment
		(start 54.564534 -143.178784)
		(end 54.401466 -143.178784)
		(width 0.127)
		(layer "In5.Cu")
		(net "BMC_TO_EXP_RESET_OUT")
	)
	(segment
		(start 56.672734 -143.006826)
		(end 54.736492 -143.006826)
		(width 0.127)
		(layer "In5.Cu")
		(net "BMC_TO_EXP_RESET_OUT")
	)
	(segment
		(start 54.277768 -143.222218)
		(end 54.099968 -143.400018)
		(width 0.127)
		(layer "In5.Cu")
		(net "BMC_TO_EXP_RESET_OUT")
	)
	(via
		(at 48.3108 -120.904)
		(size 0.6096)
		(drill 0.3048)
		(layers "F.Cu" "B.Cu")
		(net "TEMP_3_SDA")
	)
	(segment
		(start 48.258222 -120.851422)
		(end 48.3108 -120.904)
		(width 0.127)
		(layer "B.Cu")
		(net "TEMP_3_SDA")
	)
	(segment
		(start 46.116748 -120.851422)
		(end 48.258222 -120.851422)
		(width 0.127)
		(layer "B.Cu")
		(net "TEMP_3_SDA")
	)
	(segment
		(start 48.326548 -120.888252)
		(end 48.3108 -120.904)
		(width 0.127)
		(layer "B.Cu")
		(net "TEMP_3_SDA")
	)
	(segment
		(start 49.36871 -120.888252)
		(end 48.326548 -120.888252)
		(width 0.127)
		(layer "B.Cu")
		(net "TEMP_3_SDA")
	)
	(via
		(at 48.133 -119.8626)
		(size 0.6096)
		(drill 0.3048)
		(layers "F.Cu" "B.Cu")
		(net "TEMP_3_SCL")
	)
	(segment
		(start 46.116748 -120.201182)
		(end 47.794418 -120.201182)
		(width 0.127)
		(layer "B.Cu")
		(net "TEMP_3_SCL")
	)
	(segment
		(start 48.148748 -119.846852)
		(end 48.133 -119.8626)
		(width 0.127)
		(layer "B.Cu")
		(net "TEMP_3_SCL")
	)
	(segment
		(start 47.794418 -120.201182)
		(end 48.133 -119.8626)
		(width 0.127)
		(layer "B.Cu")
		(net "TEMP_3_SCL")
	)
	(segment
		(start 49.34331 -119.846852)
		(end 48.148748 -119.846852)
		(width 0.127)
		(layer "B.Cu")
		(net "TEMP_3_SCL")
	)
	(segment
		(start 47.530258 -119.550942)
		(end 46.116748 -119.550942)
		(width 0.127)
		(layer "B.Cu")
		(net "TEMP_3_ALERT")
	)
	(segment
		(start 48.72101 -118.36019)
		(end 47.530258 -119.550942)
		(width 0.127)
		(layer "B.Cu")
		(net "TEMP_3_ALERT")
	)
	(segment
		(start 49.082452 -118.36019)
		(end 48.72101 -118.36019)
		(width 0.127)
		(layer "B.Cu")
		(net "TEMP_3_ALERT")
	)
	(via
		(at 40.1828 -118.6434)
		(size 0.6096)
		(drill 0.3048)
		(layers "F.Cu" "B.Cu")
		(net "TEMP_3_A2")
	)
	(segment
		(start 39.481252 -117.941852)
		(end 38.90391 -117.941852)
		(width 0.127)
		(layer "B.Cu")
		(net "TEMP_3_A2")
	)
	(segment
		(start 38.9001 -116.8908)
		(end 38.90391 -116.89461)
		(width 0.127)
		(layer "B.Cu")
		(net "TEMP_3_A2")
	)
	(segment
		(start 40.1828 -118.6434)
		(end 39.481252 -117.941852)
		(width 0.127)
		(layer "B.Cu")
		(net "TEMP_3_A2")
	)
	(segment
		(start 40.440102 -118.900702)
		(end 40.1828 -118.6434)
		(width 0.127)
		(layer "B.Cu")
		(net "TEMP_3_A2")
	)
	(segment
		(start 38.90391 -116.89461)
		(end 38.90391 -117.941852)
		(width 0.127)
		(layer "B.Cu")
		(net "TEMP_3_A2")
	)
	(segment
		(start 42.007028 -118.900702)
		(end 40.440102 -118.900702)
		(width 0.127)
		(layer "B.Cu")
		(net "TEMP_3_A2")
	)
	(via
		(at 40.0812 -119.8372)
		(size 0.6096)
		(drill 0.3048)
		(layers "F.Cu" "B.Cu")
		(net "TEMP_3_A1")
	)
	(segment
		(start 38.995858 -120.1674)
		(end 39.751 -120.1674)
		(width 0.127)
		(layer "B.Cu")
		(net "TEMP_3_A1")
	)
	(segment
		(start 39.751 -120.1674)
		(end 40.0812 -119.8372)
		(width 0.127)
		(layer "B.Cu")
		(net "TEMP_3_A1")
	)
	(segment
		(start 40.0812 -119.8372)
		(end 40.367458 -119.550942)
		(width 0.127)
		(layer "B.Cu")
		(net "TEMP_3_A1")
	)
	(segment
		(start 40.367458 -119.550942)
		(end 42.007028 -119.550942)
		(width 0.127)
		(layer "B.Cu")
		(net "TEMP_3_A1")
	)
	(segment
		(start 38.90391 -119.022368)
		(end 38.90391 -120.075452)
		(width 0.127)
		(layer "B.Cu")
		(net "TEMP_3_A1")
	)
	(segment
		(start 38.90391 -120.075452)
		(end 38.995858 -120.1674)
		(width 0.127)
		(layer "B.Cu")
		(net "TEMP_3_A1")
	)
	(segment
		(start 38.89629 -119.014748)
		(end 38.90391 -119.022368)
		(width 0.127)
		(layer "B.Cu")
		(net "TEMP_3_A1")
	)
	(via
		(at 40.132 -121.142252)
		(size 0.6096)
		(drill 0.3048)
		(layers "F.Cu" "B.Cu")
		(net "TEMP_3_A0")
	)
	(segment
		(start 40.274748 -121.142252)
		(end 41.215818 -120.201182)
		(width 0.127)
		(layer "B.Cu")
		(net "TEMP_3_A0")
	)
	(segment
		(start 38.86581 -121.154952)
		(end 38.87851 -121.142252)
		(width 0.127)
		(layer "B.Cu")
		(net "TEMP_3_A0")
	)
	(segment
		(start 40.132 -121.142252)
		(end 40.274748 -121.142252)
		(width 0.127)
		(layer "B.Cu")
		(net "TEMP_3_A0")
	)
	(segment
		(start 38.86581 -122.188478)
		(end 38.86581 -121.154952)
		(width 0.127)
		(layer "B.Cu")
		(net "TEMP_3_A0")
	)
	(segment
		(start 38.87851 -121.142252)
		(end 40.132 -121.142252)
		(width 0.127)
		(layer "B.Cu")
		(net "TEMP_3_A0")
	)
	(segment
		(start 41.215818 -120.201182)
		(end 42.007028 -120.201182)
		(width 0.127)
		(layer "B.Cu")
		(net "TEMP_3_A0")
	)
	(segment
		(start 49.801018 -126.2507)
		(end 49.792382 -126.2507)
		(width 0.127)
		(layer "F.Cu")
		(net "SCC_RMT_FULL_PWR_EN")
	)
	(segment
		(start 50.1269 -127.7112)
		(end 50.0888 -127.7493)
		(width 0.127)
		(layer "F.Cu")
		(net "SCC_RMT_FULL_PWR_EN")
	)
	(segment
		(start 50.1269 -126.576582)
		(end 49.801018 -126.2507)
		(width 0.127)
		(layer "F.Cu")
		(net "SCC_RMT_FULL_PWR_EN")
	)
	(segment
		(start 49.3395 -125.797818)
		(end 49.3395 -123.0757)
		(width 0.127)
		(layer "F.Cu")
		(net "SCC_RMT_FULL_PWR_EN")
	)
	(segment
		(start 50.1269 -127.7112)
		(end 50.1269 -126.576582)
		(width 0.127)
		(layer "F.Cu")
		(net "SCC_RMT_FULL_PWR_EN")
	)
	(segment
		(start 50.0888 -127.7493)
		(end 49.022 -127.7493)
		(width 0.127)
		(layer "F.Cu")
		(net "SCC_RMT_FULL_PWR_EN")
	)
	(segment
		(start 49.3395 -123.0757)
		(end 49.8348 -122.5804)
		(width 0.127)
		(layer "F.Cu")
		(net "SCC_RMT_FULL_PWR_EN")
	)
	(segment
		(start 49.792382 -126.2507)
		(end 49.3395 -125.797818)
		(width 0.127)
		(layer "F.Cu")
		(net "SCC_RMT_FULL_PWR_EN")
	)
	(via
		(at 84.7979 -116.4336)
		(size 0.508)
		(drill 0.254)
		(layers "F.Cu" "B.Cu")
		(net "SCC_RMT_FULL_PWR_EN")
	)
	(via
		(at 49.8348 -122.5804)
		(size 0.508)
		(drill 0.254)
		(layers "F.Cu" "B.Cu")
		(net "SCC_RMT_FULL_PWR_EN")
	)
	(segment
		(start 88.724232 -109.040168)
		(end 87.5411 -110.2233)
		(width 0.127)
		(layer "In2.Cu")
		(net "SCC_RMT_FULL_PWR_EN")
	)
	(segment
		(start 97.822766 -15.00759)
		(end 96.8629 -15.00759)
		(width 0.127)
		(layer "In2.Cu")
		(net "SCC_RMT_FULL_PWR_EN")
	)
	(segment
		(start 87.660734 -63.733934)
		(end 87.660734 -64.876934)
		(width 0.127)
		(layer "In2.Cu")
		(net "SCC_RMT_FULL_PWR_EN")
	)
	(segment
		(start 87.660734 -64.876934)
		(end 88.724232 -65.940432)
		(width 0.127)
		(layer "In2.Cu")
		(net "SCC_RMT_FULL_PWR_EN")
	)
	(segment
		(start 93.256608 -8.67664)
		(end 86.53526 -8.67664)
		(width 0.127)
		(layer "In2.Cu")
		(net "SCC_RMT_FULL_PWR_EN")
	)
	(segment
		(start 131.674362 -27.1272)
		(end 129.745232 -27.1272)
		(width 0.127)
		(layer "In2.Cu")
		(net "SCC_RMT_FULL_PWR_EN")
	)
	(segment
		(start 135.052562 -30.5054)
		(end 131.674362 -27.1272)
		(width 0.127)
		(layer "In2.Cu")
		(net "SCC_RMT_FULL_PWR_EN")
	)
	(segment
		(start 88.61933 -42.787316)
		(end 86.896448 -44.510198)
		(width 0.127)
		(layer "In2.Cu")
		(net "SCC_RMT_FULL_PWR_EN")
	)
	(segment
		(start 84.335874 -8.676386)
		(end 82.16138 -10.85088)
		(width 0.127)
		(layer "In2.Cu")
		(net "SCC_RMT_FULL_PWR_EN")
	)
	(segment
		(start 88.724232 -65.940432)
		(end 88.724232 -109.040168)
		(width 0.127)
		(layer "In2.Cu")
		(net "SCC_RMT_FULL_PWR_EN")
	)
	(segment
		(start 87.5411 -110.2233)
		(end 87.5411 -111.581184)
		(width 0.127)
		(layer "In2.Cu")
		(net "SCC_RMT_FULL_PWR_EN")
	)
	(segment
		(start 119.385842 -20.94357)
		(end 117.958108 -19.515836)
		(width 0.127)
		(layer "In2.Cu")
		(net "SCC_RMT_FULL_PWR_EN")
	)
	(segment
		(start 135.052562 -44.552616)
		(end 135.052562 -30.5054)
		(width 0.127)
		(layer "In2.Cu")
		(net "SCC_RMT_FULL_PWR_EN")
	)
	(segment
		(start 123.382532 -23.312374)
		(end 121.013728 -20.94357)
		(width 0.127)
		(layer "In2.Cu")
		(net "SCC_RMT_FULL_PWR_EN")
	)
	(segment
		(start 95.568262 -10.988294)
		(end 93.256608 -8.67664)
		(width 0.127)
		(layer "In2.Cu")
		(net "SCC_RMT_FULL_PWR_EN")
	)
	(segment
		(start 84.7979 -114.324384)
		(end 84.7979 -116.4336)
		(width 0.127)
		(layer "In2.Cu")
		(net "SCC_RMT_FULL_PWR_EN")
	)
	(segment
		(start 87.5411 -111.581184)
		(end 84.7979 -114.324384)
		(width 0.127)
		(layer "In2.Cu")
		(net "SCC_RMT_FULL_PWR_EN")
	)
	(segment
		(start 95.568262 -13.712952)
		(end 95.568262 -10.988294)
		(width 0.127)
		(layer "In2.Cu")
		(net "SCC_RMT_FULL_PWR_EN")
	)
	(segment
		(start 86.535006 -8.676386)
		(end 84.335874 -8.676386)
		(width 0.127)
		(layer "In2.Cu")
		(net "SCC_RMT_FULL_PWR_EN")
	)
	(segment
		(start 82.16138 -10.85088)
		(end 82.16138 -30.250384)
		(width 0.127)
		(layer "In2.Cu")
		(net "SCC_RMT_FULL_PWR_EN")
	)
	(segment
		(start 86.896448 -44.510198)
		(end 86.896448 -62.969648)
		(width 0.127)
		(layer "In2.Cu")
		(net "SCC_RMT_FULL_PWR_EN")
	)
	(segment
		(start 125.930406 -23.312374)
		(end 123.382532 -23.312374)
		(width 0.127)
		(layer "In2.Cu")
		(net "SCC_RMT_FULL_PWR_EN")
	)
	(segment
		(start 96.8629 -15.00759)
		(end 95.568262 -13.712952)
		(width 0.127)
		(layer "In2.Cu")
		(net "SCC_RMT_FULL_PWR_EN")
	)
	(segment
		(start 88.61933 -36.708334)
		(end 88.61933 -42.787316)
		(width 0.127)
		(layer "In2.Cu")
		(net "SCC_RMT_FULL_PWR_EN")
	)
	(segment
		(start 121.013728 -20.94357)
		(end 119.385842 -20.94357)
		(width 0.127)
		(layer "In2.Cu")
		(net "SCC_RMT_FULL_PWR_EN")
	)
	(segment
		(start 86.53526 -8.67664)
		(end 86.535006 -8.676386)
		(width 0.127)
		(layer "In2.Cu")
		(net "SCC_RMT_FULL_PWR_EN")
	)
	(segment
		(start 86.896448 -62.969648)
		(end 87.660734 -63.733934)
		(width 0.127)
		(layer "In2.Cu")
		(net "SCC_RMT_FULL_PWR_EN")
	)
	(segment
		(start 129.745232 -27.1272)
		(end 125.930406 -23.312374)
		(width 0.127)
		(layer "In2.Cu")
		(net "SCC_RMT_FULL_PWR_EN")
	)
	(segment
		(start 82.16138 -30.250384)
		(end 88.61933 -36.708334)
		(width 0.127)
		(layer "In2.Cu")
		(net "SCC_RMT_FULL_PWR_EN")
	)
	(segment
		(start 135.899906 -45.39996)
		(end 135.052562 -44.552616)
		(width 0.127)
		(layer "In2.Cu")
		(net "SCC_RMT_FULL_PWR_EN")
	)
	(segment
		(start 117.958108 -19.515836)
		(end 102.331012 -19.515836)
		(width 0.127)
		(layer "In2.Cu")
		(net "SCC_RMT_FULL_PWR_EN")
	)
	(segment
		(start 102.331012 -19.515836)
		(end 97.822766 -15.00759)
		(width 0.127)
		(layer "In2.Cu")
		(net "SCC_RMT_FULL_PWR_EN")
	)
	(segment
		(start 49.8348 -121.7168)
		(end 49.8348 -122.5804)
		(width 0.127)
		(layer "In5.Cu")
		(net "SCC_RMT_FULL_PWR_EN")
	)
	(segment
		(start 73.1393 -118.9228)
		(end 54.61 -118.9228)
		(width 0.127)
		(layer "In5.Cu")
		(net "SCC_RMT_FULL_PWR_EN")
	)
	(segment
		(start 78.0161 -114.046)
		(end 73.1393 -118.9228)
		(width 0.127)
		(layer "In5.Cu")
		(net "SCC_RMT_FULL_PWR_EN")
	)
	(segment
		(start 81.9658 -114.046)
		(end 78.0161 -114.046)
		(width 0.127)
		(layer "In5.Cu")
		(net "SCC_RMT_FULL_PWR_EN")
	)
	(segment
		(start 51.4096 -120.142)
		(end 49.8348 -121.7168)
		(width 0.127)
		(layer "In5.Cu")
		(net "SCC_RMT_FULL_PWR_EN")
	)
	(segment
		(start 84.7979 -116.4336)
		(end 84.3534 -116.4336)
		(width 0.127)
		(layer "In5.Cu")
		(net "SCC_RMT_FULL_PWR_EN")
	)
	(segment
		(start 53.3908 -120.142)
		(end 51.4096 -120.142)
		(width 0.127)
		(layer "In5.Cu")
		(net "SCC_RMT_FULL_PWR_EN")
	)
	(segment
		(start 54.61 -118.9228)
		(end 53.3908 -120.142)
		(width 0.127)
		(layer "In5.Cu")
		(net "SCC_RMT_FULL_PWR_EN")
	)
	(segment
		(start 84.3534 -116.4336)
		(end 81.9658 -114.046)
		(width 0.127)
		(layer "In5.Cu")
		(net "SCC_RMT_FULL_PWR_EN")
	)
	(segment
		(start 98.970084 -87.769446)
		(end 98.970084 -43.605196)
		(width 0.127)
		(layer "F.Cu")
		(net "SCC_LOC_FULL_PWR_EN")
	)
	(segment
		(start 48.5013 -125.35154)
		(end 48.15205 -125.70079)
		(width 0.127)
		(layer "F.Cu")
		(net "SCC_LOC_FULL_PWR_EN")
	)
	(segment
		(start 98.965512 -87.774018)
		(end 98.970084 -87.769446)
		(width 0.127)
		(layer "F.Cu")
		(net "SCC_LOC_FULL_PWR_EN")
	)
	(segment
		(start 48.15205 -125.70079)
		(end 48.15205 -127.42545)
		(width 0.127)
		(layer "F.Cu")
		(net "SCC_LOC_FULL_PWR_EN")
	)
	(segment
		(start 135.328406 -43.428666)
		(end 135.899906 -44.000166)
		(width 0.127)
		(layer "F.Cu")
		(net "SCC_LOC_FULL_PWR_EN")
	)
	(segment
		(start 119.497094 -25.364948)
		(end 134.031482 -25.364948)
		(width 0.127)
		(layer "F.Cu")
		(net "SCC_LOC_FULL_PWR_EN")
	)
	(segment
		(start 98.970084 -43.605196)
		(end 99.949762 -42.625518)
		(width 0.127)
		(layer "F.Cu")
		(net "SCC_LOC_FULL_PWR_EN")
	)
	(segment
		(start 117.7798 -22.02942)
		(end 117.7798 -23.647654)
		(width 0.127)
		(layer "F.Cu")
		(net "SCC_LOC_FULL_PWR_EN")
	)
	(segment
		(start 48.15205 -127.42545)
		(end 47.8536 -127.7239)
		(width 0.127)
		(layer "F.Cu")
		(net "SCC_LOC_FULL_PWR_EN")
	)
	(segment
		(start 99.313746 -117.191028)
		(end 99.313746 -114.681)
		(width 0.127)
		(layer "F.Cu")
		(net "SCC_LOC_FULL_PWR_EN")
	)
	(segment
		(start 48.5013 -122.4534)
		(end 48.5013 -125.35154)
		(width 0.127)
		(layer "F.Cu")
		(net "SCC_LOC_FULL_PWR_EN")
	)
	(segment
		(start 135.94842 -27.281886)
		(end 135.94842 -29.04998)
		(width 0.127)
		(layer "F.Cu")
		(net "SCC_LOC_FULL_PWR_EN")
	)
	(segment
		(start 107.939078 -19.963892)
		(end 115.714272 -19.963892)
		(width 0.127)
		(layer "F.Cu")
		(net "SCC_LOC_FULL_PWR_EN")
	)
	(segment
		(start 134.031482 -25.364948)
		(end 135.94842 -27.281886)
		(width 0.127)
		(layer "F.Cu")
		(net "SCC_LOC_FULL_PWR_EN")
	)
	(segment
		(start 135.94842 -29.04998)
		(end 135.328406 -29.669994)
		(width 0.127)
		(layer "F.Cu")
		(net "SCC_LOC_FULL_PWR_EN")
	)
	(segment
		(start 98.965512 -92.588588)
		(end 98.965512 -87.774018)
		(width 0.127)
		(layer "F.Cu")
		(net "SCC_LOC_FULL_PWR_EN")
	)
	(segment
		(start 99.313746 -117.191028)
		(end 99.313746 -117.716554)
		(width 0.127)
		(layer "F.Cu")
		(net "SCC_LOC_FULL_PWR_EN")
	)
	(segment
		(start 99.313746 -117.716554)
		(end 98.4123 -118.618)
		(width 0.127)
		(layer "F.Cu")
		(net "SCC_LOC_FULL_PWR_EN")
	)
	(segment
		(start 99.739958 -93.363034)
		(end 98.965512 -92.588588)
		(width 0.127)
		(layer "F.Cu")
		(net "SCC_LOC_FULL_PWR_EN")
	)
	(segment
		(start 99.949762 -42.625518)
		(end 99.949762 -26.729944)
		(width 0.127)
		(layer "F.Cu")
		(net "SCC_LOC_FULL_PWR_EN")
	)
	(segment
		(start 105.848404 -20.831302)
		(end 107.071668 -20.831302)
		(width 0.127)
		(layer "F.Cu")
		(net "SCC_LOC_FULL_PWR_EN")
	)
	(segment
		(start 99.739958 -114.254788)
		(end 99.739958 -93.363034)
		(width 0.127)
		(layer "F.Cu")
		(net "SCC_LOC_FULL_PWR_EN")
	)
	(segment
		(start 135.328406 -29.669994)
		(end 135.328406 -43.428666)
		(width 0.127)
		(layer "F.Cu")
		(net "SCC_LOC_FULL_PWR_EN")
	)
	(segment
		(start 115.714272 -19.963892)
		(end 117.7798 -22.02942)
		(width 0.127)
		(layer "F.Cu")
		(net "SCC_LOC_FULL_PWR_EN")
	)
	(segment
		(start 107.071668 -20.831302)
		(end 107.939078 -19.963892)
		(width 0.127)
		(layer "F.Cu")
		(net "SCC_LOC_FULL_PWR_EN")
	)
	(segment
		(start 99.949762 -26.729944)
		(end 105.848404 -20.831302)
		(width 0.127)
		(layer "F.Cu")
		(net "SCC_LOC_FULL_PWR_EN")
	)
	(segment
		(start 117.7798 -23.647654)
		(end 119.497094 -25.364948)
		(width 0.127)
		(layer "F.Cu")
		(net "SCC_LOC_FULL_PWR_EN")
	)
	(segment
		(start 99.313746 -114.681)
		(end 99.739958 -114.254788)
		(width 0.127)
		(layer "F.Cu")
		(net "SCC_LOC_FULL_PWR_EN")
	)
	(via
		(at 98.4123 -118.618)
		(size 0.508)
		(drill 0.254)
		(layers "F.Cu" "B.Cu")
		(net "SCC_LOC_FULL_PWR_EN")
	)
	(via
		(at 99.313746 -117.191028)
		(size 0.6604)
		(drill 0.3302)
		(layers "F.Cu" "B.Cu")
		(net "SCC_LOC_FULL_PWR_EN")
	)
	(via
		(at 48.5013 -122.4534)
		(size 0.508)
		(drill 0.254)
		(layers "F.Cu" "B.Cu")
		(net "SCC_LOC_FULL_PWR_EN")
	)
	(segment
		(start 48.5013 -125.6919)
		(end 49.022 -126.2126)
		(width 0.127)
		(layer "B.Cu")
		(net "SCC_LOC_FULL_PWR_EN")
	)
	(segment
		(start 49.022 -126.2126)
		(end 49.022 -127.484632)
		(width 0.127)
		(layer "B.Cu")
		(net "SCC_LOC_FULL_PWR_EN")
	)
	(segment
		(start 48.5013 -122.4534)
		(end 48.5013 -125.6919)
		(width 0.127)
		(layer "B.Cu")
		(net "SCC_LOC_FULL_PWR_EN")
	)
	(segment
		(start 49.022 -127.484632)
		(end 48.734726 -127.771906)
		(width 0.127)
		(layer "B.Cu")
		(net "SCC_LOC_FULL_PWR_EN")
	)
	(segment
		(start 77.858112 -113.665)
		(end 82.7024 -113.665)
		(width 0.127)
		(layer "In5.Cu")
		(net "SCC_LOC_FULL_PWR_EN")
	)
	(segment
		(start 85.5218 -116.4844)
		(end 85.5218 -117.698012)
		(width 0.127)
		(layer "In5.Cu")
		(net "SCC_LOC_FULL_PWR_EN")
	)
	(segment
		(start 48.5013 -120.826784)
		(end 51.014884 -118.3132)
		(width 0.127)
		(layer "In5.Cu")
		(net "SCC_LOC_FULL_PWR_EN")
	)
	(segment
		(start 96.4565 -120.5738)
		(end 98.4123 -118.618)
		(width 0.127)
		(layer "In5.Cu")
		(net "SCC_LOC_FULL_PWR_EN")
	)
	(segment
		(start 70.2056 -117.9068)
		(end 70.5612 -118.2624)
		(width 0.127)
		(layer "In5.Cu")
		(net "SCC_LOC_FULL_PWR_EN")
	)
	(segment
		(start 82.7024 -113.665)
		(end 85.5218 -116.4844)
		(width 0.127)
		(layer "In5.Cu")
		(net "SCC_LOC_FULL_PWR_EN")
	)
	(segment
		(start 73.260712 -118.2624)
		(end 77.858112 -113.665)
		(width 0.127)
		(layer "In5.Cu")
		(net "SCC_LOC_FULL_PWR_EN")
	)
	(segment
		(start 70.5612 -118.2624)
		(end 73.260712 -118.2624)
		(width 0.127)
		(layer "In5.Cu")
		(net "SCC_LOC_FULL_PWR_EN")
	)
	(segment
		(start 88.397588 -120.5738)
		(end 96.4565 -120.5738)
		(width 0.127)
		(layer "In5.Cu")
		(net "SCC_LOC_FULL_PWR_EN")
	)
	(segment
		(start 69.820282 -117.9068)
		(end 70.2056 -117.9068)
		(width 0.127)
		(layer "In5.Cu")
		(net "SCC_LOC_FULL_PWR_EN")
	)
	(segment
		(start 54.483 -118.3132)
		(end 54.7116 -118.5418)
		(width 0.127)
		(layer "In5.Cu")
		(net "SCC_LOC_FULL_PWR_EN")
	)
	(segment
		(start 54.7116 -118.5418)
		(end 69.185282 -118.5418)
		(width 0.127)
		(layer "In5.Cu")
		(net "SCC_LOC_FULL_PWR_EN")
	)
	(segment
		(start 85.5218 -117.698012)
		(end 88.397588 -120.5738)
		(width 0.127)
		(layer "In5.Cu")
		(net "SCC_LOC_FULL_PWR_EN")
	)
	(segment
		(start 48.5013 -122.4534)
		(end 48.5013 -120.826784)
		(width 0.127)
		(layer "In5.Cu")
		(net "SCC_LOC_FULL_PWR_EN")
	)
	(segment
		(start 51.014884 -118.3132)
		(end 54.483 -118.3132)
		(width 0.127)
		(layer "In5.Cu")
		(net "SCC_LOC_FULL_PWR_EN")
	)
	(segment
		(start 69.185282 -118.5418)
		(end 69.820282 -117.9068)
		(width 0.127)
		(layer "In5.Cu")
		(net "SCC_LOC_FULL_PWR_EN")
	)
	(segment
		(start 79.925164 -60.950094)
		(end 85.259926 -60.950094)
		(width 0.127)
		(layer "F.Cu")
		(net "NCSI_TXEN_R")
	)
	(segment
		(start 86.101428 -61.791596)
		(end 87.127588 -62.817756)
		(width 0.127)
		(layer "F.Cu")
		(net "NCSI_TXEN_R")
	)
	(segment
		(start 87.127588 -62.817756)
		(end 87.800688 -62.817756)
		(width 0.127)
		(layer "F.Cu")
		(net "NCSI_TXEN_R")
	)
	(segment
		(start 85.259926 -60.950094)
		(end 86.101428 -61.791596)
		(width 0.127)
		(layer "F.Cu")
		(net "NCSI_TXEN_R")
	)
	(via
		(at 86.101428 -61.791596)
		(size 0.6604)
		(drill 0.3302)
		(layers "F.Cu" "B.Cu")
		(net "NCSI_TXEN_R")
	)
	(segment
		(start 66.7639 -144.3228)
		(end 67.7545 -145.3134)
		(width 0.127)
		(layer "F.Cu")
		(net "NCSI_TXEN")
	)
	(segment
		(start 65.326514 -114.3127)
		(end 65.593214 -114.046)
		(width 0.127)
		(layer "F.Cu")
		(net "NCSI_TXEN")
	)
	(segment
		(start 74.9427 -114.2365)
		(end 76.12634 -113.05286)
		(width 0.127)
		(layer "F.Cu")
		(net "NCSI_TXEN")
	)
	(segment
		(start 53.299614 -147.40001)
		(end 53.299614 -147.399756)
		(width 0.127)
		(layer "F.Cu")
		(net "NCSI_TXEN")
	)
	(segment
		(start 65.593214 -114.046)
		(end 70.085966 -114.046)
		(width 0.127)
		(layer "F.Cu")
		(net "NCSI_TXEN")
	)
	(segment
		(start 93.737176 -112.4458)
		(end 96.1644 -110.018576)
		(width 0.127)
		(layer "F.Cu")
		(net "NCSI_TXEN")
	)
	(segment
		(start 65.4304 -146.431)
		(end 65.9638 -145.8976)
		(width 0.127)
		(layer "F.Cu")
		(net "NCSI_TXEN")
	)
	(segment
		(start 65.9638 -145.8976)
		(end 67.1703 -145.8976)
		(width 0.127)
		(layer "F.Cu")
		(net "NCSI_TXEN")
	)
	(segment
		(start 96.691958 -95.536258)
		(end 93.8022 -92.6465)
		(width 0.127)
		(layer "F.Cu")
		(net "NCSI_TXEN")
	)
	(segment
		(start 67.1703 -145.8976)
		(end 67.7545 -145.3134)
		(width 0.127)
		(layer "F.Cu")
		(net "NCSI_TXEN")
	)
	(segment
		(start 92.990416 -66.47815)
		(end 92.990416 -85.726016)
		(width 0.127)
		(layer "F.Cu")
		(net "NCSI_TXEN")
	)
	(segment
		(start 96.1644 -98.552)
		(end 96.691958 -98.024442)
		(width 0.127)
		(layer "F.Cu")
		(net "NCSI_TXEN")
	)
	(segment
		(start 66.421 -144.0942)
		(end 66.7639 -144.0942)
		(width 0.127)
		(layer "F.Cu")
		(net "NCSI_TXEN")
	)
	(segment
		(start 93.8022 -92.6465)
		(end 93.8022 -92.1004)
		(width 0.127)
		(layer "F.Cu")
		(net "NCSI_TXEN")
	)
	(segment
		(start 70.085966 -114.046)
		(end 70.276466 -114.2365)
		(width 0.127)
		(layer "F.Cu")
		(net "NCSI_TXEN")
	)
	(segment
		(start 93.8022 -86.5378)
		(end 93.8022 -92.1004)
		(width 0.127)
		(layer "F.Cu")
		(net "NCSI_TXEN")
	)
	(segment
		(start 53.299614 -147.399756)
		(end 52.899818 -146.99996)
		(width 0.127)
		(layer "F.Cu")
		(net "NCSI_TXEN")
	)
	(segment
		(start 66.7639 -144.0942)
		(end 66.7639 -144.3228)
		(width 0.127)
		(layer "F.Cu")
		(net "NCSI_TXEN")
	)
	(segment
		(start 89.167208 -113.05286)
		(end 89.774268 -112.4458)
		(width 0.127)
		(layer "F.Cu")
		(net "NCSI_TXEN")
	)
	(segment
		(start 63.627 -114.6302)
		(end 63.9445 -114.3127)
		(width 0.127)
		(layer "F.Cu")
		(net "NCSI_TXEN")
	)
	(segment
		(start 96.1644 -110.018576)
		(end 96.1644 -98.552)
		(width 0.127)
		(layer "F.Cu")
		(net "NCSI_TXEN")
	)
	(segment
		(start 65.504314 -143.201644)
		(end 66.421 -144.0942)
		(width 0.127)
		(layer "F.Cu")
		(net "NCSI_TXEN")
	)
	(segment
		(start 76.12634 -113.05286)
		(end 89.167208 -113.05286)
		(width 0.127)
		(layer "F.Cu")
		(net "NCSI_TXEN")
	)
	(segment
		(start 96.691958 -98.024442)
		(end 96.691958 -95.536258)
		(width 0.127)
		(layer "F.Cu")
		(net "NCSI_TXEN")
	)
	(segment
		(start 89.330022 -62.817756)
		(end 92.990416 -66.47815)
		(width 0.127)
		(layer "F.Cu")
		(net "NCSI_TXEN")
	)
	(segment
		(start 70.276466 -114.2365)
		(end 74.9427 -114.2365)
		(width 0.127)
		(layer "F.Cu")
		(net "NCSI_TXEN")
	)
	(segment
		(start 63.9445 -114.3127)
		(end 65.326514 -114.3127)
		(width 0.127)
		(layer "F.Cu")
		(net "NCSI_TXEN")
	)
	(segment
		(start 92.990416 -85.726016)
		(end 93.8022 -86.5378)
		(width 0.127)
		(layer "F.Cu")
		(net "NCSI_TXEN")
	)
	(segment
		(start 88.689688 -62.817756)
		(end 89.330022 -62.817756)
		(width 0.127)
		(layer "F.Cu")
		(net "NCSI_TXEN")
	)
	(segment
		(start 89.774268 -112.4458)
		(end 93.737176 -112.4458)
		(width 0.127)
		(layer "F.Cu")
		(net "NCSI_TXEN")
	)
	(via
		(at 53.299614 -147.40001)
		(size 0.4572)
		(drill 0.2032)
		(layers "F.Cu" "B.Cu")
		(net "NCSI_TXEN")
	)
	(via
		(at 93.8022 -92.1004)
		(size 0.6604)
		(drill 0.3302)
		(layers "F.Cu" "B.Cu")
		(net "NCSI_TXEN")
	)
	(via
		(at 65.4304 -146.431)
		(size 0.508)
		(drill 0.254)
		(layers "F.Cu" "B.Cu")
		(net "NCSI_TXEN")
	)
	(via
		(at 65.504314 -143.201644)
		(size 0.508)
		(drill 0.254)
		(layers "F.Cu" "B.Cu")
		(net "NCSI_TXEN")
	)
	(via
		(at 63.627 -114.6302)
		(size 0.508)
		(drill 0.254)
		(layers "F.Cu" "B.Cu")
		(net "NCSI_TXEN")
	)
	(segment
		(start 63.397384 -141.198092)
		(end 65.400936 -143.201644)
		(width 0.127)
		(layer "In2.Cu")
		(net "NCSI_TXEN")
	)
	(segment
		(start 64.1731 -126.5047)
		(end 64.1731 -129.8067)
		(width 0.127)
		(layer "In2.Cu")
		(net "NCSI_TXEN")
	)
	(segment
		(start 64.7954 -132.118608)
		(end 64.7954 -134.663434)
		(width 0.127)
		(layer "In2.Cu")
		(net "NCSI_TXEN")
	)
	(segment
		(start 64.38646 -126.29134)
		(end 64.1731 -126.5047)
		(width 0.127)
		(layer "In2.Cu")
		(net "NCSI_TXEN")
	)
	(segment
		(start 64.38646 -115.71986)
		(end 64.38646 -126.29134)
		(width 0.127)
		(layer "In2.Cu")
		(net "NCSI_TXEN")
	)
	(segment
		(start 64.7954 -134.663434)
		(end 64.262 -135.196834)
		(width 0.127)
		(layer "In2.Cu")
		(net "NCSI_TXEN")
	)
	(segment
		(start 63.627 -114.6302)
		(end 63.627 -114.9604)
		(width 0.127)
		(layer "In2.Cu")
		(net "NCSI_TXEN")
	)
	(segment
		(start 64.329564 -129.963164)
		(end 64.329564 -131.652772)
		(width 0.127)
		(layer "In2.Cu")
		(net "NCSI_TXEN")
	)
	(segment
		(start 65.400936 -143.201644)
		(end 65.504314 -143.201644)
		(width 0.127)
		(layer "In2.Cu")
		(net "NCSI_TXEN")
	)
	(segment
		(start 64.262 -138.231118)
		(end 63.397384 -139.095734)
		(width 0.127)
		(layer "In2.Cu")
		(net "NCSI_TXEN")
	)
	(segment
		(start 64.329564 -131.652772)
		(end 64.7954 -132.118608)
		(width 0.127)
		(layer "In2.Cu")
		(net "NCSI_TXEN")
	)
	(segment
		(start 63.627 -114.9604)
		(end 64.38646 -115.71986)
		(width 0.127)
		(layer "In2.Cu")
		(net "NCSI_TXEN")
	)
	(segment
		(start 64.1731 -129.8067)
		(end 64.329564 -129.963164)
		(width 0.127)
		(layer "In2.Cu")
		(net "NCSI_TXEN")
	)
	(segment
		(start 64.262 -135.196834)
		(end 64.262 -138.231118)
		(width 0.127)
		(layer "In2.Cu")
		(net "NCSI_TXEN")
	)
	(segment
		(start 63.397384 -139.095734)
		(end 63.397384 -141.198092)
		(width 0.127)
		(layer "In2.Cu")
		(net "NCSI_TXEN")
	)
	(segment
		(start 64.3001 -146.7231)
		(end 64.008 -146.431)
		(width 0.127)
		(layer "In5.Cu")
		(net "NCSI_TXEN")
	)
	(segment
		(start 53.936646 -147.79371)
		(end 53.542946 -147.40001)
		(width 0.127)
		(layer "In5.Cu")
		(net "NCSI_TXEN")
	)
	(segment
		(start 57.56529 -147.79371)
		(end 53.936646 -147.79371)
		(width 0.127)
		(layer "In5.Cu")
		(net "NCSI_TXEN")
	)
	(segment
		(start 53.542946 -147.40001)
		(end 53.299614 -147.40001)
		(width 0.127)
		(layer "In5.Cu")
		(net "NCSI_TXEN")
	)
	(segment
		(start 65.1383 -146.7231)
		(end 64.3001 -146.7231)
		(width 0.127)
		(layer "In5.Cu")
		(net "NCSI_TXEN")
	)
	(segment
		(start 60.325 -147.193)
		(end 58.166 -147.193)
		(width 0.127)
		(layer "In5.Cu")
		(net "NCSI_TXEN")
	)
	(segment
		(start 65.4304 -146.431)
		(end 65.1383 -146.7231)
		(width 0.127)
		(layer "In5.Cu")
		(net "NCSI_TXEN")
	)
	(segment
		(start 61.087 -146.431)
		(end 60.325 -147.193)
		(width 0.127)
		(layer "In5.Cu")
		(net "NCSI_TXEN")
	)
	(segment
		(start 64.008 -146.431)
		(end 61.087 -146.431)
		(width 0.127)
		(layer "In5.Cu")
		(net "NCSI_TXEN")
	)
	(segment
		(start 58.166 -147.193)
		(end 57.56529 -147.79371)
		(width 0.127)
		(layer "In5.Cu")
		(net "NCSI_TXEN")
	)
	(segment
		(start 60.725812 -155.889198)
		(end 60.3885 -155.551886)
		(width 0.127)
		(layer "F.Cu")
		(net "NCSI_TXD1_R")
	)
	(segment
		(start 57.43702 -152.0571)
		(end 57.3278 -151.94788)
		(width 0.127)
		(layer "F.Cu")
		(net "NCSI_TXD1_R")
	)
	(segment
		(start 57.3278 -151.94788)
		(end 57.3278 -151.206454)
		(width 0.127)
		(layer "F.Cu")
		(net "NCSI_TXD1_R")
	)
	(segment
		(start 62.015624 -155.889198)
		(end 61.0362 -155.889198)
		(width 0.127)
		(layer "F.Cu")
		(net "NCSI_TXD1_R")
	)
	(segment
		(start 57.43702 -152.50414)
		(end 57.43702 -152.0571)
		(width 0.127)
		(layer "F.Cu")
		(net "NCSI_TXD1_R")
	)
	(segment
		(start 61.0362 -155.889198)
		(end 60.725812 -155.889198)
		(width 0.127)
		(layer "F.Cu")
		(net "NCSI_TXD1_R")
	)
	(segment
		(start 60.068714 -154.8511)
		(end 59.78398 -154.8511)
		(width 0.127)
		(layer "F.Cu")
		(net "NCSI_TXD1_R")
	)
	(segment
		(start 60.3885 -155.170886)
		(end 60.068714 -154.8511)
		(width 0.127)
		(layer "F.Cu")
		(net "NCSI_TXD1_R")
	)
	(segment
		(start 59.78398 -154.8511)
		(end 57.43702 -152.50414)
		(width 0.127)
		(layer "F.Cu")
		(net "NCSI_TXD1_R")
	)
	(segment
		(start 57.3278 -151.206454)
		(end 56.321198 -150.199852)
		(width 0.127)
		(layer "F.Cu")
		(net "NCSI_TXD1_R")
	)
	(segment
		(start 60.3885 -155.551886)
		(end 60.3885 -155.170886)
		(width 0.127)
		(layer "F.Cu")
		(net "NCSI_TXD1_R")
	)
	(segment
		(start 56.321198 -150.199852)
		(end 56.099964 -150.199852)
		(width 0.127)
		(layer "F.Cu")
		(net "NCSI_TXD1_R")
	)
	(via
		(at 61.0362 -155.889198)
		(size 0.6604)
		(drill 0.3302)
		(layers "F.Cu" "B.Cu")
		(net "NCSI_TXD1_R")
	)
	(segment
		(start 63.9826 -155.640786)
		(end 63.9826 -154.8384)
		(width 0.127)
		(layer "F.Cu")
		(net "NCSI_TXD1")
	)
	(segment
		(start 93.105478 -110.9218)
		(end 89.0524 -110.9218)
		(width 0.127)
		(layer "F.Cu")
		(net "NCSI_TXD1")
	)
	(segment
		(start 88.44534 -111.52886)
		(end 74.696574 -111.52886)
		(width 0.127)
		(layer "F.Cu")
		(net "NCSI_TXD1")
	)
	(segment
		(start 93.821504 -97.432622)
		(end 93.821504 -110.205774)
		(width 0.127)
		(layer "F.Cu")
		(net "NCSI_TXD1")
	)
	(segment
		(start 67.0306 -112.4204)
		(end 66.1924 -112.4204)
		(width 0.127)
		(layer "F.Cu")
		(net "NCSI_TXD1")
	)
	(segment
		(start 74.135234 -112.0902)
		(end 67.3608 -112.0902)
		(width 0.127)
		(layer "F.Cu")
		(net "NCSI_TXD1")
	)
	(segment
		(start 93.821504 -110.205774)
		(end 93.105478 -110.9218)
		(width 0.127)
		(layer "F.Cu")
		(net "NCSI_TXD1")
	)
	(segment
		(start 62.89421 -156.778198)
		(end 63.04661 -156.625798)
		(width 0.127)
		(layer "F.Cu")
		(net "NCSI_TXD1")
	)
	(segment
		(start 64.077088 -155.735274)
		(end 63.9826 -155.640786)
		(width 0.127)
		(layer "F.Cu")
		(net "NCSI_TXD1")
	)
	(segment
		(start 89.630758 -68.951348)
		(end 89.630758 -93.241876)
		(width 0.127)
		(layer "F.Cu")
		(net "NCSI_TXD1")
	)
	(segment
		(start 67.3608 -112.0902)
		(end 67.0306 -112.4204)
		(width 0.127)
		(layer "F.Cu")
		(net "NCSI_TXD1")
	)
	(segment
		(start 77.480668 -64.950086)
		(end 77.828648 -64.602106)
		(width 0.127)
		(layer "F.Cu")
		(net "NCSI_TXD1")
	)
	(segment
		(start 86.085172 -67.658996)
		(end 88.338406 -67.658996)
		(width 0.127)
		(layer "F.Cu")
		(net "NCSI_TXD1")
	)
	(segment
		(start 88.338406 -67.658996)
		(end 89.630758 -68.951348)
		(width 0.127)
		(layer "F.Cu")
		(net "NCSI_TXD1")
	)
	(segment
		(start 63.186564 -156.625798)
		(end 64.077088 -155.735274)
		(width 0.127)
		(layer "F.Cu")
		(net "NCSI_TXD1")
	)
	(segment
		(start 63.04661 -156.625798)
		(end 63.186564 -156.625798)
		(width 0.127)
		(layer "F.Cu")
		(net "NCSI_TXD1")
	)
	(segment
		(start 75.475084 -64.950086)
		(end 77.480668 -64.950086)
		(width 0.127)
		(layer "F.Cu")
		(net "NCSI_TXD1")
	)
	(segment
		(start 62.015624 -156.778198)
		(end 62.89421 -156.778198)
		(width 0.127)
		(layer "F.Cu")
		(net "NCSI_TXD1")
	)
	(segment
		(start 89.630758 -93.241876)
		(end 93.821504 -97.432622)
		(width 0.127)
		(layer "F.Cu")
		(net "NCSI_TXD1")
	)
	(segment
		(start 89.0524 -110.9218)
		(end 88.44534 -111.52886)
		(width 0.127)
		(layer "F.Cu")
		(net "NCSI_TXD1")
	)
	(segment
		(start 85.10524 -66.679064)
		(end 86.085172 -67.658996)
		(width 0.127)
		(layer "F.Cu")
		(net "NCSI_TXD1")
	)
	(segment
		(start 74.696574 -111.52886)
		(end 74.135234 -112.0902)
		(width 0.127)
		(layer "F.Cu")
		(net "NCSI_TXD1")
	)
	(via
		(at 85.10524 -66.679064)
		(size 0.508)
		(drill 0.254)
		(layers "F.Cu" "B.Cu")
		(net "NCSI_TXD1")
	)
	(via
		(at 77.828648 -64.602106)
		(size 0.508)
		(drill 0.254)
		(layers "F.Cu" "B.Cu")
		(net "NCSI_TXD1")
	)
	(via
		(at 79.521558 -65.296796)
		(size 0.6096)
		(drill 0.3048)
		(layers "F.Cu" "B.Cu")
		(net "NCSI_TXD1")
	)
	(via
		(at 63.9826 -154.8384)
		(size 0.508)
		(drill 0.254)
		(layers "F.Cu" "B.Cu")
		(net "NCSI_TXD1")
	)
	(via
		(at 66.1924 -112.4204)
		(size 0.508)
		(drill 0.254)
		(layers "F.Cu" "B.Cu")
		(net "NCSI_TXD1")
	)
	(segment
		(start 78.715362 -64.4906)
		(end 77.940154 -64.4906)
		(width 0.127)
		(layer "B.Cu")
		(net "NCSI_TXD1")
	)
	(segment
		(start 79.521558 -65.296796)
		(end 83.722972 -65.296796)
		(width 0.127)
		(layer "B.Cu")
		(net "NCSI_TXD1")
	)
	(segment
		(start 83.722972 -65.296796)
		(end 85.10524 -66.679064)
		(width 0.127)
		(layer "B.Cu")
		(net "NCSI_TXD1")
	)
	(segment
		(start 79.521558 -65.296796)
		(end 78.715362 -64.4906)
		(width 0.127)
		(layer "B.Cu")
		(net "NCSI_TXD1")
	)
	(segment
		(start 77.940154 -64.4906)
		(end 77.828648 -64.602106)
		(width 0.127)
		(layer "B.Cu")
		(net "NCSI_TXD1")
	)
	(segment
		(start 66.1924 -112.4204)
		(end 66.1924 -114.219482)
		(width 0.127)
		(layer "In2.Cu")
		(net "NCSI_TXD1")
	)
	(segment
		(start 65.3034 -131.908042)
		(end 65.3034 -135.1661)
		(width 0.127)
		(layer "In2.Cu")
		(net "NCSI_TXD1")
	)
	(segment
		(start 66.1924 -114.219482)
		(end 65.2272 -115.184682)
		(width 0.127)
		(layer "In2.Cu")
		(net "NCSI_TXD1")
	)
	(segment
		(start 65.2272 -115.184682)
		(end 65.2272 -115.57)
		(width 0.127)
		(layer "In2.Cu")
		(net "NCSI_TXD1")
	)
	(segment
		(start 65.014602 -131.619244)
		(end 65.3034 -131.908042)
		(width 0.127)
		(layer "In2.Cu")
		(net "NCSI_TXD1")
	)
	(segment
		(start 64.27597 -141.358112)
		(end 64.551052 -141.633194)
		(width 0.127)
		(layer "In2.Cu")
		(net "NCSI_TXD1")
	)
	(segment
		(start 65.1129 -115.6843)
		(end 65.1129 -129.633218)
		(width 0.127)
		(layer "In2.Cu")
		(net "NCSI_TXD1")
	)
	(segment
		(start 64.600582 -141.633194)
		(end 66.2813 -143.313912)
		(width 0.127)
		(layer "In2.Cu")
		(net "NCSI_TXD1")
	)
	(segment
		(start 64.8081 -135.6614)
		(end 64.8081 -140.3985)
		(width 0.127)
		(layer "In2.Cu")
		(net "NCSI_TXD1")
	)
	(segment
		(start 65.014602 -129.731516)
		(end 65.014602 -131.619244)
		(width 0.127)
		(layer "In2.Cu")
		(net "NCSI_TXD1")
	)
	(segment
		(start 67.0179 -150.8379)
		(end 65.056004 -152.799796)
		(width 0.127)
		(layer "In2.Cu")
		(net "NCSI_TXD1")
	)
	(segment
		(start 64.8081 -140.3985)
		(end 64.27597 -140.93063)
		(width 0.127)
		(layer "In2.Cu")
		(net "NCSI_TXD1")
	)
	(segment
		(start 64.27597 -140.93063)
		(end 64.27597 -141.358112)
		(width 0.127)
		(layer "In2.Cu")
		(net "NCSI_TXD1")
	)
	(segment
		(start 66.399918 -145.7198)
		(end 67.0179 -146.337782)
		(width 0.127)
		(layer "In2.Cu")
		(net "NCSI_TXD1")
	)
	(segment
		(start 66.2813 -144.399)
		(end 65.8495 -144.8308)
		(width 0.127)
		(layer "In2.Cu")
		(net "NCSI_TXD1")
	)
	(segment
		(start 65.8495 -145.381218)
		(end 66.188082 -145.7198)
		(width 0.127)
		(layer "In2.Cu")
		(net "NCSI_TXD1")
	)
	(segment
		(start 66.188082 -145.7198)
		(end 66.399918 -145.7198)
		(width 0.127)
		(layer "In2.Cu")
		(net "NCSI_TXD1")
	)
	(segment
		(start 67.0179 -146.337782)
		(end 67.0179 -150.8379)
		(width 0.127)
		(layer "In2.Cu")
		(net "NCSI_TXD1")
	)
	(segment
		(start 66.2813 -143.313912)
		(end 66.2813 -144.399)
		(width 0.127)
		(layer "In2.Cu")
		(net "NCSI_TXD1")
	)
	(segment
		(start 64.551052 -141.633194)
		(end 64.600582 -141.633194)
		(width 0.127)
		(layer "In2.Cu")
		(net "NCSI_TXD1")
	)
	(segment
		(start 65.2272 -115.57)
		(end 65.1129 -115.6843)
		(width 0.127)
		(layer "In2.Cu")
		(net "NCSI_TXD1")
	)
	(segment
		(start 65.8495 -144.8308)
		(end 65.8495 -145.381218)
		(width 0.127)
		(layer "In2.Cu")
		(net "NCSI_TXD1")
	)
	(segment
		(start 65.3034 -135.1661)
		(end 64.8081 -135.6614)
		(width 0.127)
		(layer "In2.Cu")
		(net "NCSI_TXD1")
	)
	(segment
		(start 65.056004 -153.764996)
		(end 63.9826 -154.8384)
		(width 0.127)
		(layer "In2.Cu")
		(net "NCSI_TXD1")
	)
	(segment
		(start 65.056004 -152.799796)
		(end 65.056004 -153.764996)
		(width 0.127)
		(layer "In2.Cu")
		(net "NCSI_TXD1")
	)
	(segment
		(start 65.1129 -129.633218)
		(end 65.014602 -129.731516)
		(width 0.127)
		(layer "In2.Cu")
		(net "NCSI_TXD1")
	)
	(segment
		(start 52.099972 -147.000214)
		(end 52.099972 -146.99996)
		(width 0.127)
		(layer "F.Cu")
		(net "NCSI_TXD0_R")
	)
	(segment
		(start 52.499768 -147.40001)
		(end 52.099972 -147.000214)
		(width 0.127)
		(layer "F.Cu")
		(net "NCSI_TXD0_R")
	)
	(via
		(at 67.4878 -147.373086)
		(size 0.6096)
		(drill 0.3048)
		(layers "F.Cu" "B.Cu")
		(net "NCSI_TXD0_R")
	)
	(via
		(at 66.4464 -147.32)
		(size 0.508)
		(drill 0.254)
		(layers "F.Cu" "B.Cu")
		(net "NCSI_TXD0_R")
	)
	(via
		(at 52.499768 -147.40001)
		(size 0.4572)
		(drill 0.2032)
		(layers "F.Cu" "B.Cu")
		(net "NCSI_TXD0_R")
	)
	(segment
		(start 66.5226 -147.3962)
		(end 66.4464 -147.32)
		(width 0.127)
		(layer "B.Cu")
		(net "NCSI_TXD0_R")
	)
	(segment
		(start 67.4878 -148.246338)
		(end 67.4878 -147.373086)
		(width 0.127)
		(layer "B.Cu")
		(net "NCSI_TXD0_R")
	)
	(segment
		(start 67.4878 -147.373086)
		(end 67.464686 -147.3962)
		(width 0.127)
		(layer "B.Cu")
		(net "NCSI_TXD0_R")
	)
	(segment
		(start 67.528948 -148.287486)
		(end 67.4878 -148.246338)
		(width 0.127)
		(layer "B.Cu")
		(net "NCSI_TXD0_R")
	)
	(segment
		(start 67.464686 -147.3962)
		(end 66.5226 -147.3962)
		(width 0.127)
		(layer "B.Cu")
		(net "NCSI_TXD0_R")
	)
	(segment
		(start 61.757052 -147.18792)
		(end 63.25108 -147.18792)
		(width 0.127)
		(layer "In5.Cu")
		(net "NCSI_TXD0_R")
	)
	(segment
		(start 52.742592 -147.40001)
		(end 53.148738 -147.806156)
		(width 0.127)
		(layer "In5.Cu")
		(net "NCSI_TXD0_R")
	)
	(segment
		(start 53.706014 -148.04898)
		(end 53.706014 -148.363432)
		(width 0.127)
		(layer "In5.Cu")
		(net "NCSI_TXD0_R")
	)
	(segment
		(start 65.95618 -147.81022)
		(end 66.4464 -147.32)
		(width 0.127)
		(layer "In5.Cu")
		(net "NCSI_TXD0_R")
	)
	(segment
		(start 53.148738 -147.806156)
		(end 53.46319 -147.806156)
		(width 0.127)
		(layer "In5.Cu")
		(net "NCSI_TXD0_R")
	)
	(segment
		(start 60.608972 -148.336)
		(end 61.757052 -147.18792)
		(width 0.127)
		(layer "In5.Cu")
		(net "NCSI_TXD0_R")
	)
	(segment
		(start 53.936392 -148.59381)
		(end 55.249064 -148.59381)
		(width 0.127)
		(layer "In5.Cu")
		(net "NCSI_TXD0_R")
	)
	(segment
		(start 63.25108 -147.18792)
		(end 63.87338 -147.81022)
		(width 0.127)
		(layer "In5.Cu")
		(net "NCSI_TXD0_R")
	)
	(segment
		(start 55.249064 -148.59381)
		(end 55.506874 -148.336)
		(width 0.127)
		(layer "In5.Cu")
		(net "NCSI_TXD0_R")
	)
	(segment
		(start 53.46319 -147.806156)
		(end 53.706014 -148.04898)
		(width 0.127)
		(layer "In5.Cu")
		(net "NCSI_TXD0_R")
	)
	(segment
		(start 63.87338 -147.81022)
		(end 65.95618 -147.81022)
		(width 0.127)
		(layer "In5.Cu")
		(net "NCSI_TXD0_R")
	)
	(segment
		(start 53.706014 -148.363432)
		(end 53.936392 -148.59381)
		(width 0.127)
		(layer "In5.Cu")
		(net "NCSI_TXD0_R")
	)
	(segment
		(start 52.499768 -147.40001)
		(end 52.742592 -147.40001)
		(width 0.127)
		(layer "In5.Cu")
		(net "NCSI_TXD0_R")
	)
	(segment
		(start 55.506874 -148.336)
		(end 60.608972 -148.336)
		(width 0.127)
		(layer "In5.Cu")
		(net "NCSI_TXD0_R")
	)
	(segment
		(start 75.475084 -64.149986)
		(end 77.19441 -64.149986)
		(width 0.127)
		(layer "F.Cu")
		(net "NCSI_TXD0")
	)
	(segment
		(start 89.262966 -111.4298)
		(end 93.316044 -111.4298)
		(width 0.127)
		(layer "F.Cu")
		(net "NCSI_TXD0")
	)
	(segment
		(start 74.3458 -112.5982)
		(end 74.90714 -112.03686)
		(width 0.127)
		(layer "F.Cu")
		(net "NCSI_TXD0")
	)
	(segment
		(start 63.0682 -113.2078)
		(end 64.994282 -113.2078)
		(width 0.127)
		(layer "F.Cu")
		(net "NCSI_TXD0")
	)
	(segment
		(start 88.548972 -67.150996)
		(end 86.446106 -67.150996)
		(width 0.127)
		(layer "F.Cu")
		(net "NCSI_TXD0")
	)
	(segment
		(start 65.172082 -113.03)
		(end 67.2084 -113.03)
		(width 0.127)
		(layer "F.Cu")
		(net "NCSI_TXD0")
	)
	(segment
		(start 88.655906 -112.03686)
		(end 89.262966 -111.4298)
		(width 0.127)
		(layer "F.Cu")
		(net "NCSI_TXD0")
	)
	(segment
		(start 74.90714 -112.03686)
		(end 88.655906 -112.03686)
		(width 0.127)
		(layer "F.Cu")
		(net "NCSI_TXD0")
	)
	(segment
		(start 90.138758 -93.03131)
		(end 90.138758 -68.740782)
		(width 0.127)
		(layer "F.Cu")
		(net "NCSI_TXD0")
	)
	(segment
		(start 67.2084 -113.03)
		(end 67.6402 -112.5982)
		(width 0.127)
		(layer "F.Cu")
		(net "NCSI_TXD0")
	)
	(segment
		(start 77.19441 -64.149986)
		(end 77.564742 -63.779654)
		(width 0.127)
		(layer "F.Cu")
		(net "NCSI_TXD0")
	)
	(segment
		(start 94.329504 -97.221802)
		(end 90.138758 -93.03131)
		(width 0.127)
		(layer "F.Cu")
		(net "NCSI_TXD0")
	)
	(segment
		(start 62.9666 -113.1062)
		(end 63.0682 -113.2078)
		(width 0.127)
		(layer "F.Cu")
		(net "NCSI_TXD0")
	)
	(segment
		(start 94.329504 -110.41634)
		(end 94.329504 -97.221802)
		(width 0.127)
		(layer "F.Cu")
		(net "NCSI_TXD0")
	)
	(segment
		(start 90.138758 -68.740782)
		(end 88.548972 -67.150996)
		(width 0.127)
		(layer "F.Cu")
		(net "NCSI_TXD0")
	)
	(segment
		(start 67.6402 -112.5982)
		(end 74.3458 -112.5982)
		(width 0.127)
		(layer "F.Cu")
		(net "NCSI_TXD0")
	)
	(segment
		(start 86.446106 -67.150996)
		(end 85.089492 -65.794382)
		(width 0.127)
		(layer "F.Cu")
		(net "NCSI_TXD0")
	)
	(segment
		(start 64.994282 -113.2078)
		(end 65.172082 -113.03)
		(width 0.127)
		(layer "F.Cu")
		(net "NCSI_TXD0")
	)
	(segment
		(start 93.316044 -111.4298)
		(end 94.329504 -110.41634)
		(width 0.127)
		(layer "F.Cu")
		(net "NCSI_TXD0")
	)
	(via
		(at 77.564742 -63.779654)
		(size 0.508)
		(drill 0.254)
		(layers "F.Cu" "B.Cu")
		(net "NCSI_TXD0")
	)
	(via
		(at 66.421 -146.4056)
		(size 0.508)
		(drill 0.254)
		(layers "F.Cu" "B.Cu")
		(net "NCSI_TXD0")
	)
	(via
		(at 85.089492 -65.794382)
		(size 0.508)
		(drill 0.254)
		(layers "F.Cu" "B.Cu")
		(net "NCSI_TXD0")
	)
	(via
		(at 62.9666 -113.1062)
		(size 0.508)
		(drill 0.254)
		(layers "F.Cu" "B.Cu")
		(net "NCSI_TXD0")
	)
	(via
		(at 82.587338 -64.115696)
		(size 0.6096)
		(drill 0.3048)
		(layers "F.Cu" "B.Cu")
		(net "NCSI_TXD0")
	)
	(segment
		(start 68.417186 -149.304502)
		(end 68.417186 -148.795486)
		(width 0.127)
		(layer "B.Cu")
		(net "NCSI_TXD0")
	)
	(segment
		(start 77.615796 -63.7286)
		(end 77.564742 -63.779654)
		(width 0.127)
		(layer "B.Cu")
		(net "NCSI_TXD0")
	)
	(segment
		(start 68.255134 -147.2946)
		(end 68.707 -147.2946)
		(width 0.127)
		(layer "B.Cu")
		(net "NCSI_TXD0")
	)
	(segment
		(start 79.311754 -64.115696)
		(end 78.924658 -63.7286)
		(width 0.127)
		(layer "B.Cu")
		(net "NCSI_TXD0")
	)
	(segment
		(start 83.410806 -64.115696)
		(end 82.587338 -64.115696)
		(width 0.127)
		(layer "B.Cu")
		(net "NCSI_TXD0")
	)
	(segment
		(start 67.81292 -146.852386)
		(end 68.255134 -147.2946)
		(width 0.127)
		(layer "B.Cu")
		(net "NCSI_TXD0")
	)
	(segment
		(start 69.46646 -148.05406)
		(end 69.46646 -148.425408)
		(width 0.127)
		(layer "B.Cu")
		(net "NCSI_TXD0")
	)
	(segment
		(start 85.089492 -65.794382)
		(end 83.410806 -64.115696)
		(width 0.127)
		(layer "B.Cu")
		(net "NCSI_TXD0")
	)
	(segment
		(start 68.587366 -149.304502)
		(end 69.46646 -148.425408)
		(width 0.127)
		(layer "B.Cu")
		(net "NCSI_TXD0")
	)
	(segment
		(start 68.417186 -148.795486)
		(end 68.417948 -148.795486)
		(width 0.127)
		(layer "B.Cu")
		(net "NCSI_TXD0")
	)
	(segment
		(start 66.867786 -146.852386)
		(end 67.81292 -146.852386)
		(width 0.127)
		(layer "B.Cu")
		(net "NCSI_TXD0")
	)
	(segment
		(start 68.417186 -149.304502)
		(end 68.587366 -149.304502)
		(width 0.127)
		(layer "B.Cu")
		(net "NCSI_TXD0")
	)
	(segment
		(start 66.421 -146.4056)
		(end 66.867786 -146.852386)
		(width 0.127)
		(layer "B.Cu")
		(net "NCSI_TXD0")
	)
	(segment
		(start 68.707 -147.2946)
		(end 69.46646 -148.05406)
		(width 0.127)
		(layer "B.Cu")
		(net "NCSI_TXD0")
	)
	(segment
		(start 78.924658 -63.7286)
		(end 77.615796 -63.7286)
		(width 0.127)
		(layer "B.Cu")
		(net "NCSI_TXD0")
	)
	(segment
		(start 82.587338 -64.115696)
		(end 79.311754 -64.115696)
		(width 0.127)
		(layer "B.Cu")
		(net "NCSI_TXD0")
	)
	(segment
		(start 68.417948 -148.795486)
		(end 68.417948 -148.287486)
		(width 0.127)
		(layer "B.Cu")
		(net "NCSI_TXD0")
	)
	(segment
		(start 63.821564 -130.17373)
		(end 63.821564 -131.863338)
		(width 0.127)
		(layer "In2.Cu")
		(net "NCSI_TXD0")
	)
	(segment
		(start 66.069718 -146.4056)
		(end 66.421 -146.4056)
		(width 0.127)
		(layer "In2.Cu")
		(net "NCSI_TXD0")
	)
	(segment
		(start 63.6651 -126.2253)
		(end 63.6651 -130.017266)
		(width 0.127)
		(layer "In2.Cu")
		(net "NCSI_TXD0")
	)
	(segment
		(start 62.889384 -140.998702)
		(end 62.889384 -141.530324)
		(width 0.127)
		(layer "In2.Cu")
		(net "NCSI_TXD0")
	)
	(segment
		(start 65.362582 -145.9611)
		(end 65.625218 -145.9611)
		(width 0.127)
		(layer "In2.Cu")
		(net "NCSI_TXD0")
	)
	(segment
		(start 63.754 -134.986268)
		(end 63.754 -136.66978)
		(width 0.127)
		(layer "In2.Cu")
		(net "NCSI_TXD0")
	)
	(segment
		(start 65.625218 -145.9611)
		(end 66.069718 -146.4056)
		(width 0.127)
		(layer "In2.Cu")
		(net "NCSI_TXD0")
	)
	(segment
		(start 62.9666 -115.0874)
		(end 63.87846 -115.99926)
		(width 0.127)
		(layer "In2.Cu")
		(net "NCSI_TXD0")
	)
	(segment
		(start 63.754 -136.66978)
		(end 61.948822 -138.474958)
		(width 0.127)
		(layer "In2.Cu")
		(net "NCSI_TXD0")
	)
	(segment
		(start 61.948822 -140.05814)
		(end 62.889384 -140.998702)
		(width 0.127)
		(layer "In2.Cu")
		(net "NCSI_TXD0")
	)
	(segment
		(start 62.889384 -141.530324)
		(end 63.33109 -141.97203)
		(width 0.127)
		(layer "In2.Cu")
		(net "NCSI_TXD0")
	)
	(segment
		(start 64.2874 -132.329174)
		(end 64.2874 -134.452868)
		(width 0.127)
		(layer "In2.Cu")
		(net "NCSI_TXD0")
	)
	(segment
		(start 63.6651 -130.017266)
		(end 63.821564 -130.17373)
		(width 0.127)
		(layer "In2.Cu")
		(net "NCSI_TXD0")
	)
	(segment
		(start 63.87846 -115.99926)
		(end 63.87846 -126.01194)
		(width 0.127)
		(layer "In2.Cu")
		(net "NCSI_TXD0")
	)
	(segment
		(start 63.87846 -126.01194)
		(end 63.6651 -126.2253)
		(width 0.127)
		(layer "In2.Cu")
		(net "NCSI_TXD0")
	)
	(segment
		(start 64.2874 -134.452868)
		(end 63.754 -134.986268)
		(width 0.127)
		(layer "In2.Cu")
		(net "NCSI_TXD0")
	)
	(segment
		(start 61.948822 -138.474958)
		(end 61.948822 -140.05814)
		(width 0.127)
		(layer "In2.Cu")
		(net "NCSI_TXD0")
	)
	(segment
		(start 63.821564 -131.863338)
		(end 64.2874 -132.329174)
		(width 0.127)
		(layer "In2.Cu")
		(net "NCSI_TXD0")
	)
	(segment
		(start 62.9666 -113.1062)
		(end 62.9666 -115.0874)
		(width 0.127)
		(layer "In2.Cu")
		(net "NCSI_TXD0")
	)
	(segment
		(start 63.33109 -143.929608)
		(end 65.362582 -145.9611)
		(width 0.127)
		(layer "In2.Cu")
		(net "NCSI_TXD0")
	)
	(segment
		(start 63.33109 -141.97203)
		(end 63.33109 -143.929608)
		(width 0.127)
		(layer "In2.Cu")
		(net "NCSI_TXD0")
	)
	(segment
		(start 84.652612 -67.861942)
		(end 86.152228 -69.361558)
		(width 0.127)
		(layer "F.Cu")
		(net "NCSI_RXD1_R")
	)
	(segment
		(start 86.152228 -69.361558)
		(end 86.195662 -69.318124)
		(width 0.127)
		(layer "F.Cu")
		(net "NCSI_RXD1_R")
	)
	(segment
		(start 79.925164 -66.550032)
		(end 82.996786 -66.550032)
		(width 0.127)
		(layer "F.Cu")
		(net "NCSI_RXD1_R")
	)
	(segment
		(start 82.996786 -66.550032)
		(end 84.308696 -67.861942)
		(width 0.127)
		(layer "F.Cu")
		(net "NCSI_RXD1_R")
	)
	(segment
		(start 84.308696 -67.861942)
		(end 84.652612 -67.861942)
		(width 0.127)
		(layer "F.Cu")
		(net "NCSI_RXD1_R")
	)
	(segment
		(start 86.195662 -69.318124)
		(end 87.132414 -69.318124)
		(width 0.127)
		(layer "F.Cu")
		(net "NCSI_RXD1_R")
	)
	(via
		(at 86.152228 -69.361558)
		(size 0.6604)
		(drill 0.3302)
		(layers "F.Cu" "B.Cu")
		(net "NCSI_RXD1_R")
	)
	(segment
		(start 73.2028 -111.0742)
		(end 74.3712 -109.9058)
		(width 0.127)
		(layer "F.Cu")
		(net "NCSI_RXD1")
	)
	(segment
		(start 53.699664 -149.400006)
		(end 53.699918 -149.400006)
		(width 0.127)
		(layer "F.Cu")
		(net "NCSI_RXD1")
	)
	(segment
		(start 92.763594 -109.826552)
		(end 92.763594 -107.90047)
		(width 0.127)
		(layer "F.Cu")
		(net "NCSI_RXD1")
	)
	(segment
		(start 92.805504 -107.85856)
		(end 92.805504 -98.269552)
		(width 0.127)
		(layer "F.Cu")
		(net "NCSI_RXD1")
	)
	(segment
		(start 88.021414 -69.318124)
		(end 88.614758 -69.911468)
		(width 0.127)
		(layer "F.Cu")
		(net "NCSI_RXD1")
	)
	(segment
		(start 74.3712 -109.9058)
		(end 92.684346 -109.9058)
		(width 0.127)
		(layer "F.Cu")
		(net "NCSI_RXD1")
	)
	(segment
		(start 63.373 -111.0742)
		(end 73.2028 -111.0742)
		(width 0.127)
		(layer "F.Cu")
		(net "NCSI_RXD1")
	)
	(segment
		(start 92.805504 -98.269552)
		(end 90.1319 -95.595948)
		(width 0.127)
		(layer "F.Cu")
		(net "NCSI_RXD1")
	)
	(segment
		(start 92.763594 -107.90047)
		(end 92.805504 -107.85856)
		(width 0.127)
		(layer "F.Cu")
		(net "NCSI_RXD1")
	)
	(segment
		(start 61.722 -112.7252)
		(end 63.373 -111.0742)
		(width 0.127)
		(layer "F.Cu")
		(net "NCSI_RXD1")
	)
	(segment
		(start 92.684346 -109.9058)
		(end 92.763594 -109.826552)
		(width 0.127)
		(layer "F.Cu")
		(net "NCSI_RXD1")
	)
	(segment
		(start 88.614758 -69.911468)
		(end 88.614758 -94.078806)
		(width 0.127)
		(layer "F.Cu")
		(net "NCSI_RXD1")
	)
	(segment
		(start 53.299868 -149.799802)
		(end 53.699664 -149.400006)
		(width 0.127)
		(layer "F.Cu")
		(net "NCSI_RXD1")
	)
	(segment
		(start 88.614758 -94.078806)
		(end 90.1319 -95.595948)
		(width 0.127)
		(layer "F.Cu")
		(net "NCSI_RXD1")
	)
	(via
		(at 65.4558 -148.9456)
		(size 0.508)
		(drill 0.254)
		(layers "F.Cu" "B.Cu")
		(net "NCSI_RXD1")
	)
	(via
		(at 61.722 -112.7252)
		(size 0.508)
		(drill 0.254)
		(layers "F.Cu" "B.Cu")
		(net "NCSI_RXD1")
	)
	(via
		(at 53.299868 -149.799802)
		(size 0.4572)
		(drill 0.2032)
		(layers "F.Cu" "B.Cu")
		(net "NCSI_RXD1")
	)
	(via
		(at 90.1319 -95.595948)
		(size 0.6604)
		(drill 0.3302)
		(layers "F.Cu" "B.Cu")
		(net "NCSI_RXD1")
	)
	(segment
		(start 61.661294 -143.089376)
		(end 61.661294 -143.343376)
		(width 0.127)
		(layer "In2.Cu")
		(net "NCSI_RXD1")
	)
	(segment
		(start 61.8744 -146.7358)
		(end 62.8904 -146.7358)
		(width 0.127)
		(layer "In2.Cu")
		(net "NCSI_RXD1")
	)
	(segment
		(start 61.661294 -146.240246)
		(end 61.661294 -146.522694)
		(width 0.127)
		(layer "In2.Cu")
		(net "NCSI_RXD1")
	)
	(segment
		(start 60.932822 -140.479272)
		(end 61.661294 -141.207744)
		(width 0.127)
		(layer "In2.Cu")
		(net "NCSI_RXD1")
	)
	(segment
		(start 62.3062 -142.581376)
		(end 62.3062 -142.835376)
		(width 0.127)
		(layer "In2.Cu")
		(net "NCSI_RXD1")
	)
	(segment
		(start 62.1538 -145.605246)
		(end 62.2808 -145.732246)
		(width 0.127)
		(layer "In2.Cu")
		(net "NCSI_RXD1")
	)
	(segment
		(start 61.788294 -143.470376)
		(end 62.1792 -143.470376)
		(width 0.127)
		(layer "In2.Cu")
		(net "NCSI_RXD1")
	)
	(segment
		(start 61.788294 -144.994376)
		(end 61.661294 -145.121376)
		(width 0.127)
		(layer "In2.Cu")
		(net "NCSI_RXD1")
	)
	(segment
		(start 61.661294 -141.207744)
		(end 61.661294 -142.327376)
		(width 0.127)
		(layer "In2.Cu")
		(net "NCSI_RXD1")
	)
	(segment
		(start 63.9191 -148.5011)
		(end 65.0113 -148.5011)
		(width 0.127)
		(layer "In2.Cu")
		(net "NCSI_RXD1")
	)
	(segment
		(start 65.0113 -148.5011)
		(end 65.4558 -148.9456)
		(width 0.127)
		(layer "In2.Cu")
		(net "NCSI_RXD1")
	)
	(segment
		(start 62.1538 -146.113246)
		(end 61.788294 -146.113246)
		(width 0.127)
		(layer "In2.Cu")
		(net "NCSI_RXD1")
	)
	(segment
		(start 61.661294 -142.327376)
		(end 61.788294 -142.454376)
		(width 0.127)
		(layer "In2.Cu")
		(net "NCSI_RXD1")
	)
	(segment
		(start 62.559692 -126.284736)
		(end 62.559692 -130.353308)
		(width 0.127)
		(layer "In2.Cu")
		(net "NCSI_RXD1")
	)
	(segment
		(start 61.5188 -115.2652)
		(end 62.43066 -116.17706)
		(width 0.127)
		(layer "In2.Cu")
		(net "NCSI_RXD1")
	)
	(segment
		(start 62.738 -132.4356)
		(end 62.738 -135.382)
		(width 0.127)
		(layer "In2.Cu")
		(net "NCSI_RXD1")
	)
	(segment
		(start 62.43066 -126.155704)
		(end 62.559692 -126.284736)
		(width 0.127)
		(layer "In2.Cu")
		(net "NCSI_RXD1")
	)
	(segment
		(start 61.788294 -145.605246)
		(end 62.1538 -145.605246)
		(width 0.127)
		(layer "In2.Cu")
		(net "NCSI_RXD1")
	)
	(segment
		(start 61.661294 -145.478246)
		(end 61.788294 -145.605246)
		(width 0.127)
		(layer "In2.Cu")
		(net "NCSI_RXD1")
	)
	(segment
		(start 62.559692 -130.353308)
		(end 62.0141 -130.8989)
		(width 0.127)
		(layer "In2.Cu")
		(net "NCSI_RXD1")
	)
	(segment
		(start 63.2587 -147.1041)
		(end 63.2587 -147.8407)
		(width 0.127)
		(layer "In2.Cu")
		(net "NCSI_RXD1")
	)
	(segment
		(start 61.661294 -143.343376)
		(end 61.788294 -143.470376)
		(width 0.127)
		(layer "In2.Cu")
		(net "NCSI_RXD1")
	)
	(segment
		(start 62.3062 -143.851376)
		(end 62.1792 -143.978376)
		(width 0.127)
		(layer "In2.Cu")
		(net "NCSI_RXD1")
	)
	(segment
		(start 62.1792 -143.470376)
		(end 62.3062 -143.597376)
		(width 0.127)
		(layer "In2.Cu")
		(net "NCSI_RXD1")
	)
	(segment
		(start 61.788294 -142.962376)
		(end 61.661294 -143.089376)
		(width 0.127)
		(layer "In2.Cu")
		(net "NCSI_RXD1")
	)
	(segment
		(start 61.661294 -145.121376)
		(end 61.661294 -145.478246)
		(width 0.127)
		(layer "In2.Cu")
		(net "NCSI_RXD1")
	)
	(segment
		(start 61.788294 -146.113246)
		(end 61.661294 -146.240246)
		(width 0.127)
		(layer "In2.Cu")
		(net "NCSI_RXD1")
	)
	(segment
		(start 61.722 -112.7252)
		(end 61.5188 -112.9284)
		(width 0.127)
		(layer "In2.Cu")
		(net "NCSI_RXD1")
	)
	(segment
		(start 62.8904 -146.7358)
		(end 63.2587 -147.1041)
		(width 0.127)
		(layer "In2.Cu")
		(net "NCSI_RXD1")
	)
	(segment
		(start 61.661294 -144.359376)
		(end 61.788294 -144.486376)
		(width 0.127)
		(layer "In2.Cu")
		(net "NCSI_RXD1")
	)
	(segment
		(start 62.2808 -145.986246)
		(end 62.1538 -146.113246)
		(width 0.127)
		(layer "In2.Cu")
		(net "NCSI_RXD1")
	)
	(segment
		(start 62.3062 -144.867376)
		(end 62.1792 -144.994376)
		(width 0.127)
		(layer "In2.Cu")
		(net "NCSI_RXD1")
	)
	(segment
		(start 61.661294 -146.522694)
		(end 61.8744 -146.7358)
		(width 0.127)
		(layer "In2.Cu")
		(net "NCSI_RXD1")
	)
	(segment
		(start 62.0141 -131.7117)
		(end 62.738 -132.4356)
		(width 0.127)
		(layer "In2.Cu")
		(net "NCSI_RXD1")
	)
	(segment
		(start 61.788294 -143.978376)
		(end 61.661294 -144.105376)
		(width 0.127)
		(layer "In2.Cu")
		(net "NCSI_RXD1")
	)
	(segment
		(start 61.788294 -142.454376)
		(end 62.1792 -142.454376)
		(width 0.127)
		(layer "In2.Cu")
		(net "NCSI_RXD1")
	)
	(segment
		(start 62.43066 -116.17706)
		(end 62.43066 -126.155704)
		(width 0.127)
		(layer "In2.Cu")
		(net "NCSI_RXD1")
	)
	(segment
		(start 62.1792 -144.486376)
		(end 62.3062 -144.613376)
		(width 0.127)
		(layer "In2.Cu")
		(net "NCSI_RXD1")
	)
	(segment
		(start 62.3062 -142.835376)
		(end 62.1792 -142.962376)
		(width 0.127)
		(layer "In2.Cu")
		(net "NCSI_RXD1")
	)
	(segment
		(start 63.2587 -147.8407)
		(end 63.9191 -148.5011)
		(width 0.127)
		(layer "In2.Cu")
		(net "NCSI_RXD1")
	)
	(segment
		(start 61.788294 -144.486376)
		(end 62.1792 -144.486376)
		(width 0.127)
		(layer "In2.Cu")
		(net "NCSI_RXD1")
	)
	(segment
		(start 62.1792 -144.994376)
		(end 61.788294 -144.994376)
		(width 0.127)
		(layer "In2.Cu")
		(net "NCSI_RXD1")
	)
	(segment
		(start 62.0141 -130.8989)
		(end 62.0141 -131.7117)
		(width 0.127)
		(layer "In2.Cu")
		(net "NCSI_RXD1")
	)
	(segment
		(start 62.3062 -143.597376)
		(end 62.3062 -143.851376)
		(width 0.127)
		(layer "In2.Cu")
		(net "NCSI_RXD1")
	)
	(segment
		(start 62.1792 -142.454376)
		(end 62.3062 -142.581376)
		(width 0.127)
		(layer "In2.Cu")
		(net "NCSI_RXD1")
	)
	(segment
		(start 62.1792 -142.962376)
		(end 61.788294 -142.962376)
		(width 0.127)
		(layer "In2.Cu")
		(net "NCSI_RXD1")
	)
	(segment
		(start 61.5188 -112.9284)
		(end 61.5188 -115.2652)
		(width 0.127)
		(layer "In2.Cu")
		(net "NCSI_RXD1")
	)
	(segment
		(start 61.661294 -144.105376)
		(end 61.661294 -144.359376)
		(width 0.127)
		(layer "In2.Cu")
		(net "NCSI_RXD1")
	)
	(segment
		(start 62.1792 -143.978376)
		(end 61.788294 -143.978376)
		(width 0.127)
		(layer "In2.Cu")
		(net "NCSI_RXD1")
	)
	(segment
		(start 62.738 -135.382)
		(end 60.932822 -137.187178)
		(width 0.127)
		(layer "In2.Cu")
		(net "NCSI_RXD1")
	)
	(segment
		(start 62.2808 -145.732246)
		(end 62.2808 -145.986246)
		(width 0.127)
		(layer "In2.Cu")
		(net "NCSI_RXD1")
	)
	(segment
		(start 62.3062 -144.613376)
		(end 62.3062 -144.867376)
		(width 0.127)
		(layer "In2.Cu")
		(net "NCSI_RXD1")
	)
	(segment
		(start 60.932822 -137.187178)
		(end 60.932822 -140.479272)
		(width 0.127)
		(layer "In2.Cu")
		(net "NCSI_RXD1")
	)
	(segment
		(start 65.4558 -148.9456)
		(end 64.89446 -149.50694)
		(width 0.127)
		(layer "In5.Cu")
		(net "NCSI_RXD1")
	)
	(segment
		(start 61.546232 -149.352)
		(end 57.0992 -149.352)
		(width 0.127)
		(layer "In5.Cu")
		(net "NCSI_RXD1")
	)
	(segment
		(start 61.770006 -149.128226)
		(end 61.546232 -149.352)
		(width 0.127)
		(layer "In5.Cu")
		(net "NCSI_RXD1")
	)
	(segment
		(start 64.89446 -149.50694)
		(end 63.42126 -149.50694)
		(width 0.127)
		(layer "In5.Cu")
		(net "NCSI_RXD1")
	)
	(segment
		(start 63.042546 -149.128226)
		(end 61.770006 -149.128226)
		(width 0.127)
		(layer "In5.Cu")
		(net "NCSI_RXD1")
	)
	(segment
		(start 57.0992 -149.352)
		(end 56.257444 -150.193756)
		(width 0.127)
		(layer "In5.Cu")
		(net "NCSI_RXD1")
	)
	(segment
		(start 63.42126 -149.50694)
		(end 63.042546 -149.128226)
		(width 0.127)
		(layer "In5.Cu")
		(net "NCSI_RXD1")
	)
	(segment
		(start 56.257444 -150.193756)
		(end 53.693822 -150.193756)
		(width 0.127)
		(layer "In5.Cu")
		(net "NCSI_RXD1")
	)
	(segment
		(start 53.693822 -150.193756)
		(end 53.299868 -149.799802)
		(width 0.127)
		(layer "In5.Cu")
		(net "NCSI_RXD1")
	)
	(segment
		(start 87.056976 -68.22059)
		(end 86.042754 -68.22059)
		(width 0.127)
		(layer "F.Cu")
		(net "NCSI_RXD0_R")
	)
	(segment
		(start 82.915252 -65.749932)
		(end 84.519262 -67.353942)
		(width 0.127)
		(layer "F.Cu")
		(net "NCSI_RXD0_R")
	)
	(segment
		(start 84.519262 -67.353942)
		(end 84.864194 -67.353942)
		(width 0.127)
		(layer "F.Cu")
		(net "NCSI_RXD0_R")
	)
	(segment
		(start 84.864194 -67.353942)
		(end 85.730842 -68.22059)
		(width 0.127)
		(layer "F.Cu")
		(net "NCSI_RXD0_R")
	)
	(segment
		(start 85.730842 -68.22059)
		(end 86.042754 -68.22059)
		(width 0.127)
		(layer "F.Cu")
		(net "NCSI_RXD0_R")
	)
	(segment
		(start 79.925164 -65.749932)
		(end 82.915252 -65.749932)
		(width 0.127)
		(layer "F.Cu")
		(net "NCSI_RXD0_R")
	)
	(via
		(at 86.042754 -68.22059)
		(size 0.6604)
		(drill 0.3302)
		(layers "F.Cu" "B.Cu")
		(net "NCSI_RXD0_R")
	)
	(segment
		(start 61.1124 -113.3602)
		(end 61.849 -113.3602)
		(width 0.127)
		(layer "F.Cu")
		(net "NCSI_RXD0")
	)
	(segment
		(start 57.496456 -153.533602)
		(end 56.75122 -152.788366)
		(width 0.127)
		(layer "F.Cu")
		(net "NCSI_RXD0")
	)
	(segment
		(start 63.627 -111.5822)
		(end 73.924668 -111.5822)
		(width 0.127)
		(layer "F.Cu")
		(net "NCSI_RXD0")
	)
	(segment
		(start 60.7822 -113.03)
		(end 61.1124 -113.3602)
		(width 0.127)
		(layer "F.Cu")
		(net "NCSI_RXD0")
	)
	(segment
		(start 87.945976 -68.22059)
		(end 88.181434 -68.22059)
		(width 0.127)
		(layer "F.Cu")
		(net "NCSI_RXD0")
	)
	(segment
		(start 74.486008 -111.02086)
		(end 88.234774 -111.02086)
		(width 0.127)
		(layer "F.Cu")
		(net "NCSI_RXD0")
	)
	(segment
		(start 93.313504 -109.995208)
		(end 93.313504 -97.99574)
		(width 0.127)
		(layer "F.Cu")
		(net "NCSI_RXD0")
	)
	(segment
		(start 56.75122 -152.406858)
		(end 56.34736 -152.002998)
		(width 0.127)
		(layer "F.Cu")
		(net "NCSI_RXD0")
	)
	(segment
		(start 58.96102 -155.6893)
		(end 58.855356 -155.583636)
		(width 0.127)
		(layer "F.Cu")
		(net "NCSI_RXD0")
	)
	(segment
		(start 88.234774 -111.02086)
		(end 88.841834 -110.4138)
		(width 0.127)
		(layer "F.Cu")
		(net "NCSI_RXD0")
	)
	(segment
		(start 56.34736 -152.002998)
		(end 56.30291 -152.002998)
		(width 0.127)
		(layer "F.Cu")
		(net "NCSI_RXD0")
	)
	(segment
		(start 61.849 -113.3602)
		(end 63.627 -111.5822)
		(width 0.127)
		(layer "F.Cu")
		(net "NCSI_RXD0")
	)
	(segment
		(start 89.122758 -69.161914)
		(end 89.122758 -93.804994)
		(width 0.127)
		(layer "F.Cu")
		(net "NCSI_RXD0")
	)
	(segment
		(start 93.313504 -97.99574)
		(end 91.738704 -96.42094)
		(width 0.127)
		(layer "F.Cu")
		(net "NCSI_RXD0")
	)
	(segment
		(start 58.855356 -155.583636)
		(end 58.261504 -155.583636)
		(width 0.127)
		(layer "F.Cu")
		(net "NCSI_RXD0")
	)
	(segment
		(start 57.496456 -154.818588)
		(end 57.496456 -153.533602)
		(width 0.127)
		(layer "F.Cu")
		(net "NCSI_RXD0")
	)
	(segment
		(start 56.30291 -152.002998)
		(end 56.099964 -151.800052)
		(width 0.127)
		(layer "F.Cu")
		(net "NCSI_RXD0")
	)
	(segment
		(start 92.894912 -110.4138)
		(end 93.313504 -109.995208)
		(width 0.127)
		(layer "F.Cu")
		(net "NCSI_RXD0")
	)
	(segment
		(start 73.924668 -111.5822)
		(end 74.486008 -111.02086)
		(width 0.127)
		(layer "F.Cu")
		(net "NCSI_RXD0")
	)
	(segment
		(start 60.7822 -112.7252)
		(end 60.7822 -113.03)
		(width 0.127)
		(layer "F.Cu")
		(net "NCSI_RXD0")
	)
	(segment
		(start 88.841834 -110.4138)
		(end 92.894912 -110.4138)
		(width 0.127)
		(layer "F.Cu")
		(net "NCSI_RXD0")
	)
	(segment
		(start 89.122758 -93.804994)
		(end 91.738704 -96.42094)
		(width 0.127)
		(layer "F.Cu")
		(net "NCSI_RXD0")
	)
	(segment
		(start 88.181434 -68.22059)
		(end 89.122758 -69.161914)
		(width 0.127)
		(layer "F.Cu")
		(net "NCSI_RXD0")
	)
	(segment
		(start 56.75122 -152.788366)
		(end 56.75122 -152.406858)
		(width 0.127)
		(layer "F.Cu")
		(net "NCSI_RXD0")
	)
	(segment
		(start 58.261504 -155.583636)
		(end 57.496456 -154.818588)
		(width 0.127)
		(layer "F.Cu")
		(net "NCSI_RXD0")
	)
	(via
		(at 58.96102 -155.6893)
		(size 0.508)
		(drill 0.254)
		(layers "F.Cu" "B.Cu")
		(net "NCSI_RXD0")
	)
	(via
		(at 91.738704 -96.42094)
		(size 0.6604)
		(drill 0.3302)
		(layers "F.Cu" "B.Cu")
		(net "NCSI_RXD0")
	)
	(via
		(at 60.7822 -112.7252)
		(size 0.508)
		(drill 0.254)
		(layers "F.Cu" "B.Cu")
		(net "NCSI_RXD0")
	)
	(segment
		(start 61.1378 -118.212362)
		(end 61.2648 -118.339362)
		(width 0.127)
		(layer "In2.Cu")
		(net "NCSI_RXD0")
	)
	(segment
		(start 61.1378 -118.974362)
		(end 61.1378 -119.228362)
		(width 0.127)
		(layer "In2.Cu")
		(net "NCSI_RXD0")
	)
	(segment
		(start 61.92266 -117.704362)
		(end 61.79566 -117.831362)
		(width 0.127)
		(layer "In2.Cu")
		(net "NCSI_RXD0")
	)
	(segment
		(start 61.2648 -117.323362)
		(end 61.79566 -117.323362)
		(width 0.127)
		(layer "In2.Cu")
		(net "NCSI_RXD0")
	)
	(segment
		(start 60.7822 -115.2652)
		(end 61.92266 -116.40566)
		(width 0.127)
		(layer "In2.Cu")
		(net "NCSI_RXD0")
	)
	(segment
		(start 61.92266 -116.40566)
		(end 61.92266 -116.688362)
		(width 0.127)
		(layer "In2.Cu")
		(net "NCSI_RXD0")
	)
	(segment
		(start 61.92266 -117.450362)
		(end 61.92266 -117.704362)
		(width 0.127)
		(layer "In2.Cu")
		(net "NCSI_RXD0")
	)
	(segment
		(start 61.2648 -118.339362)
		(end 61.79566 -118.339362)
		(width 0.127)
		(layer "In2.Cu")
		(net "NCSI_RXD0")
	)
	(segment
		(start 61.2648 -118.847362)
		(end 61.1378 -118.974362)
		(width 0.127)
		(layer "In2.Cu")
		(net "NCSI_RXD0")
	)
	(segment
		(start 61.92266 -118.720362)
		(end 61.79566 -118.847362)
		(width 0.127)
		(layer "In2.Cu")
		(net "NCSI_RXD0")
	)
	(segment
		(start 60.424822 -140.689838)
		(end 61.153294 -141.41831)
		(width 0.127)
		(layer "In2.Cu")
		(net "NCSI_RXD0")
	)
	(segment
		(start 61.1251 -136.276334)
		(end 60.424822 -136.976612)
		(width 0.127)
		(layer "In2.Cu")
		(net "NCSI_RXD0")
	)
	(segment
		(start 63.6778 -151.068024)
		(end 63.213488 -151.532336)
		(width 0.127)
		(layer "In2.Cu")
		(net "NCSI_RXD0")
	)
	(segment
		(start 62.051692 -130.142742)
		(end 61.1251 -131.069334)
		(width 0.127)
		(layer "In2.Cu")
		(net "NCSI_RXD0")
	)
	(segment
		(start 61.1378 -117.196362)
		(end 61.2648 -117.323362)
		(width 0.127)
		(layer "In2.Cu")
		(net "NCSI_RXD0")
	)
	(segment
		(start 61.79566 -117.323362)
		(end 61.92266 -117.450362)
		(width 0.127)
		(layer "In2.Cu")
		(net "NCSI_RXD0")
	)
	(segment
		(start 63.6778 -149.7838)
		(end 63.6778 -151.068024)
		(width 0.127)
		(layer "In2.Cu")
		(net "NCSI_RXD0")
	)
	(segment
		(start 61.1378 -116.942362)
		(end 61.1378 -117.196362)
		(width 0.127)
		(layer "In2.Cu")
		(net "NCSI_RXD0")
	)
	(segment
		(start 61.153294 -141.41831)
		(end 61.153294 -147.259294)
		(width 0.127)
		(layer "In2.Cu")
		(net "NCSI_RXD0")
	)
	(segment
		(start 61.1378 -117.958362)
		(end 61.1378 -118.212362)
		(width 0.127)
		(layer "In2.Cu")
		(net "NCSI_RXD0")
	)
	(segment
		(start 60.424822 -136.976612)
		(end 60.424822 -140.689838)
		(width 0.127)
		(layer "In2.Cu")
		(net "NCSI_RXD0")
	)
	(segment
		(start 61.79566 -116.815362)
		(end 61.2648 -116.815362)
		(width 0.127)
		(layer "In2.Cu")
		(net "NCSI_RXD0")
	)
	(segment
		(start 63.213488 -153.042112)
		(end 60.54344 -155.71216)
		(width 0.127)
		(layer "In2.Cu")
		(net "NCSI_RXD0")
	)
	(segment
		(start 61.1378 -119.228362)
		(end 61.2648 -119.355362)
		(width 0.127)
		(layer "In2.Cu")
		(net "NCSI_RXD0")
	)
	(segment
		(start 61.2648 -116.815362)
		(end 61.1378 -116.942362)
		(width 0.127)
		(layer "In2.Cu")
		(net "NCSI_RXD0")
	)
	(segment
		(start 61.153294 -147.259294)
		(end 63.6778 -149.7838)
		(width 0.127)
		(layer "In2.Cu")
		(net "NCSI_RXD0")
	)
	(segment
		(start 61.92266 -126.36627)
		(end 62.051692 -126.495302)
		(width 0.127)
		(layer "In2.Cu")
		(net "NCSI_RXD0")
	)
	(segment
		(start 61.79566 -118.847362)
		(end 61.2648 -118.847362)
		(width 0.127)
		(layer "In2.Cu")
		(net "NCSI_RXD0")
	)
	(segment
		(start 62.051692 -126.495302)
		(end 62.051692 -130.142742)
		(width 0.127)
		(layer "In2.Cu")
		(net "NCSI_RXD0")
	)
	(segment
		(start 61.2648 -117.831362)
		(end 61.1378 -117.958362)
		(width 0.127)
		(layer "In2.Cu")
		(net "NCSI_RXD0")
	)
	(segment
		(start 58.98388 -155.71216)
		(end 58.96102 -155.6893)
		(width 0.127)
		(layer "In2.Cu")
		(net "NCSI_RXD0")
	)
	(segment
		(start 61.92266 -119.482362)
		(end 61.92266 -126.36627)
		(width 0.127)
		(layer "In2.Cu")
		(net "NCSI_RXD0")
	)
	(segment
		(start 61.1251 -131.069334)
		(end 61.1251 -136.276334)
		(width 0.127)
		(layer "In2.Cu")
		(net "NCSI_RXD0")
	)
	(segment
		(start 61.79566 -118.339362)
		(end 61.92266 -118.466362)
		(width 0.127)
		(layer "In2.Cu")
		(net "NCSI_RXD0")
	)
	(segment
		(start 61.92266 -116.688362)
		(end 61.79566 -116.815362)
		(width 0.127)
		(layer "In2.Cu")
		(net "NCSI_RXD0")
	)
	(segment
		(start 61.2648 -119.355362)
		(end 61.79566 -119.355362)
		(width 0.127)
		(layer "In2.Cu")
		(net "NCSI_RXD0")
	)
	(segment
		(start 63.213488 -151.532336)
		(end 63.213488 -153.042112)
		(width 0.127)
		(layer "In2.Cu")
		(net "NCSI_RXD0")
	)
	(segment
		(start 60.54344 -155.71216)
		(end 58.98388 -155.71216)
		(width 0.127)
		(layer "In2.Cu")
		(net "NCSI_RXD0")
	)
	(segment
		(start 61.79566 -117.831362)
		(end 61.2648 -117.831362)
		(width 0.127)
		(layer "In2.Cu")
		(net "NCSI_RXD0")
	)
	(segment
		(start 61.79566 -119.355362)
		(end 61.92266 -119.482362)
		(width 0.127)
		(layer "In2.Cu")
		(net "NCSI_RXD0")
	)
	(segment
		(start 60.7822 -112.7252)
		(end 60.7822 -115.2652)
		(width 0.127)
		(layer "In2.Cu")
		(net "NCSI_RXD0")
	)
	(segment
		(start 61.92266 -118.466362)
		(end 61.92266 -118.720362)
		(width 0.127)
		(layer "In2.Cu")
		(net "NCSI_RXD0")
	)
	(segment
		(start 75.475084 -62.55004)
		(end 77.070204 -62.55004)
		(width 0.127)
		(layer "F.Cu")
		(net "NCSI_RX_ER_R")
	)
	(segment
		(start 86.413086 -66.225674)
		(end 85.089492 -64.90208)
		(width 0.127)
		(layer "F.Cu")
		(net "NCSI_RX_ER_R")
	)
	(segment
		(start 77.070204 -62.55004)
		(end 77.52715 -62.093094)
		(width 0.127)
		(layer "F.Cu")
		(net "NCSI_RX_ER_R")
	)
	(segment
		(start 77.52715 -62.093094)
		(end 77.585316 -62.093094)
		(width 0.127)
		(layer "F.Cu")
		(net "NCSI_RX_ER_R")
	)
	(segment
		(start 86.413086 -66.322448)
		(end 86.413086 -66.225674)
		(width 0.127)
		(layer "F.Cu")
		(net "NCSI_RX_ER_R")
	)
	(via
		(at 77.585316 -62.093094)
		(size 0.508)
		(drill 0.254)
		(layers "F.Cu" "B.Cu")
		(net "NCSI_RX_ER_R")
	)
	(via
		(at 79.3242 -62.9666)
		(size 0.6096)
		(drill 0.3048)
		(layers "F.Cu" "B.Cu")
		(net "NCSI_RX_ER_R")
	)
	(via
		(at 85.089492 -64.90208)
		(size 0.508)
		(drill 0.254)
		(layers "F.Cu" "B.Cu")
		(net "NCSI_RX_ER_R")
	)
	(segment
		(start 78.927706 -62.9666)
		(end 78.0542 -62.093094)
		(width 0.127)
		(layer "B.Cu")
		(net "NCSI_RX_ER_R")
	)
	(segment
		(start 84.937092 -64.90208)
		(end 83.001612 -62.9666)
		(width 0.127)
		(layer "B.Cu")
		(net "NCSI_RX_ER_R")
	)
	(segment
		(start 78.0542 -62.093094)
		(end 77.585316 -62.093094)
		(width 0.127)
		(layer "B.Cu")
		(net "NCSI_RX_ER_R")
	)
	(segment
		(start 79.3242 -62.9666)
		(end 78.927706 -62.9666)
		(width 0.127)
		(layer "B.Cu")
		(net "NCSI_RX_ER_R")
	)
	(segment
		(start 83.001612 -62.9666)
		(end 79.3242 -62.9666)
		(width 0.127)
		(layer "B.Cu")
		(net "NCSI_RX_ER_R")
	)
	(segment
		(start 85.089492 -64.90208)
		(end 84.937092 -64.90208)
		(width 0.127)
		(layer "B.Cu")
		(net "NCSI_RX_ER_R")
	)
	(segment
		(start 88.823038 -66.322448)
		(end 87.302086 -66.322448)
		(width 0.127)
		(layer "F.Cu")
		(net "NCSI_RX_ER")
	)
	(segment
		(start 89.412318 -66.911728)
		(end 88.823038 -66.322448)
		(width 0.127)
		(layer "F.Cu")
		(net "NCSI_RX_ER")
	)
	(segment
		(start 75.56754 -112.54486)
		(end 74.549 -113.5634)
		(width 0.127)
		(layer "F.Cu")
		(net "NCSI_RX_ER")
	)
	(segment
		(start 74.549 -113.5634)
		(end 70.321932 -113.5634)
		(width 0.127)
		(layer "F.Cu")
		(net "NCSI_RX_ER")
	)
	(segment
		(start 93.52661 -111.9378)
		(end 89.5096 -111.9378)
		(width 0.127)
		(layer "F.Cu")
		(net "NCSI_RX_ER")
	)
	(segment
		(start 89.412318 -66.911728)
		(end 90.646758 -68.146168)
		(width 0.127)
		(layer "F.Cu")
		(net "NCSI_RX_ER")
	)
	(segment
		(start 54.500018 -150.999444)
		(end 54.500018 -150.999952)
		(width 0.127)
		(layer "F.Cu")
		(net "NCSI_RX_ER")
	)
	(segment
		(start 94.837504 -97.011236)
		(end 94.837504 -110.626906)
		(width 0.127)
		(layer "F.Cu")
		(net "NCSI_RX_ER")
	)
	(segment
		(start 89.5096 -111.9378)
		(end 88.90254 -112.54486)
		(width 0.127)
		(layer "F.Cu")
		(net "NCSI_RX_ER")
	)
	(segment
		(start 63.0682 -113.7158)
		(end 62.8142 -113.9698)
		(width 0.127)
		(layer "F.Cu")
		(net "NCSI_RX_ER")
	)
	(segment
		(start 88.90254 -112.54486)
		(end 75.56754 -112.54486)
		(width 0.127)
		(layer "F.Cu")
		(net "NCSI_RX_ER")
	)
	(segment
		(start 65.204848 -113.7158)
		(end 63.0682 -113.7158)
		(width 0.127)
		(layer "F.Cu")
		(net "NCSI_RX_ER")
	)
	(segment
		(start 54.100222 -150.599648)
		(end 54.500018 -150.999444)
		(width 0.127)
		(layer "F.Cu")
		(net "NCSI_RX_ER")
	)
	(segment
		(start 94.837504 -110.626906)
		(end 93.52661 -111.9378)
		(width 0.127)
		(layer "F.Cu")
		(net "NCSI_RX_ER")
	)
	(segment
		(start 70.321932 -113.5634)
		(end 70.296532 -113.538)
		(width 0.127)
		(layer "F.Cu")
		(net "NCSI_RX_ER")
	)
	(segment
		(start 70.296532 -113.538)
		(end 65.382648 -113.538)
		(width 0.127)
		(layer "F.Cu")
		(net "NCSI_RX_ER")
	)
	(segment
		(start 65.382648 -113.538)
		(end 65.204848 -113.7158)
		(width 0.127)
		(layer "F.Cu")
		(net "NCSI_RX_ER")
	)
	(segment
		(start 60.8838 -113.9698)
		(end 59.9694 -113.0554)
		(width 0.127)
		(layer "F.Cu")
		(net "NCSI_RX_ER")
	)
	(segment
		(start 90.646758 -92.82049)
		(end 94.837504 -97.011236)
		(width 0.127)
		(layer "F.Cu")
		(net "NCSI_RX_ER")
	)
	(segment
		(start 62.8142 -113.9698)
		(end 60.8838 -113.9698)
		(width 0.127)
		(layer "F.Cu")
		(net "NCSI_RX_ER")
	)
	(segment
		(start 90.646758 -68.146168)
		(end 90.646758 -92.82049)
		(width 0.127)
		(layer "F.Cu")
		(net "NCSI_RX_ER")
	)
	(via
		(at 60.2234 -149.86)
		(size 0.508)
		(drill 0.254)
		(layers "F.Cu" "B.Cu")
		(net "NCSI_RX_ER")
	)
	(via
		(at 54.100222 -150.599648)
		(size 0.4572)
		(drill 0.2032)
		(layers "F.Cu" "B.Cu")
		(net "NCSI_RX_ER")
	)
	(via
		(at 59.9694 -113.0554)
		(size 0.508)
		(drill 0.254)
		(layers "F.Cu" "B.Cu")
		(net "NCSI_RX_ER")
	)
	(via
		(at 89.412318 -66.911728)
		(size 0.6604)
		(drill 0.3302)
		(layers "F.Cu" "B.Cu")
		(net "NCSI_RX_ER")
	)
	(segment
		(start 60.6171 -130.8227)
		(end 60.6171 -136.065768)
		(width 0.127)
		(layer "In2.Cu")
		(net "NCSI_RX_ER")
	)
	(segment
		(start 59.916822 -136.766046)
		(end 59.916822 -140.900404)
		(width 0.127)
		(layer "In2.Cu")
		(net "NCSI_RX_ER")
	)
	(segment
		(start 59.9694 -115.7224)
		(end 60.6298 -116.3828)
		(width 0.127)
		(layer "In2.Cu")
		(net "NCSI_RX_ER")
	)
	(segment
		(start 61.1886 -126.411482)
		(end 61.1886 -130.2512)
		(width 0.127)
		(layer "In2.Cu")
		(net "NCSI_RX_ER")
	)
	(segment
		(start 59.9694 -113.0554)
		(end 59.9694 -115.7224)
		(width 0.127)
		(layer "In2.Cu")
		(net "NCSI_RX_ER")
	)
	(segment
		(start 60.6298 -120.0658)
		(end 61.41466 -120.85066)
		(width 0.127)
		(layer "In2.Cu")
		(net "NCSI_RX_ER")
	)
	(segment
		(start 61.41466 -126.185422)
		(end 61.1886 -126.411482)
		(width 0.127)
		(layer "In2.Cu")
		(net "NCSI_RX_ER")
	)
	(segment
		(start 60.6171 -136.065768)
		(end 59.916822 -136.766046)
		(width 0.127)
		(layer "In2.Cu")
		(net "NCSI_RX_ER")
	)
	(segment
		(start 59.916822 -140.900404)
		(end 60.645294 -141.628876)
		(width 0.127)
		(layer "In2.Cu")
		(net "NCSI_RX_ER")
	)
	(segment
		(start 61.1886 -130.2512)
		(end 60.6171 -130.8227)
		(width 0.127)
		(layer "In2.Cu")
		(net "NCSI_RX_ER")
	)
	(segment
		(start 60.645294 -141.628876)
		(end 60.645294 -149.438106)
		(width 0.127)
		(layer "In2.Cu")
		(net "NCSI_RX_ER")
	)
	(segment
		(start 60.645294 -149.438106)
		(end 60.2234 -149.86)
		(width 0.127)
		(layer "In2.Cu")
		(net "NCSI_RX_ER")
	)
	(segment
		(start 61.41466 -120.85066)
		(end 61.41466 -126.185422)
		(width 0.127)
		(layer "In2.Cu")
		(net "NCSI_RX_ER")
	)
	(segment
		(start 60.6298 -116.3828)
		(end 60.6298 -120.0658)
		(width 0.127)
		(layer "In2.Cu")
		(net "NCSI_RX_ER")
	)
	(segment
		(start 54.100222 -150.599648)
		(end 57.197752 -150.599648)
		(width 0.127)
		(layer "In5.Cu")
		(net "NCSI_RX_ER")
	)
	(segment
		(start 57.9374 -149.86)
		(end 60.2234 -149.86)
		(width 0.127)
		(layer "In5.Cu")
		(net "NCSI_RX_ER")
	)
	(segment
		(start 57.197752 -150.599648)
		(end 57.9374 -149.86)
		(width 0.127)
		(layer "In5.Cu")
		(net "NCSI_RX_ER")
	)
	(segment
		(start 86.487 -60.0964)
		(end 86.489032 -60.0964)
		(width 0.127)
		(layer "F.Cu")
		(net "NCSI_RCSDV_R")
	)
	(segment
		(start 86.489032 -60.0964)
		(end 87.777574 -61.384942)
		(width 0.127)
		(layer "F.Cu")
		(net "NCSI_RCSDV_R")
	)
	(segment
		(start 85.742526 -59.349894)
		(end 86.487 -60.094368)
		(width 0.127)
		(layer "F.Cu")
		(net "NCSI_RCSDV_R")
	)
	(segment
		(start 86.487 -60.094368)
		(end 86.487 -60.0964)
		(width 0.127)
		(layer "F.Cu")
		(net "NCSI_RCSDV_R")
	)
	(segment
		(start 87.777574 -61.384942)
		(end 87.777574 -61.534294)
		(width 0.127)
		(layer "F.Cu")
		(net "NCSI_RCSDV_R")
	)
	(segment
		(start 79.925164 -59.349894)
		(end 85.742526 -59.349894)
		(width 0.127)
		(layer "F.Cu")
		(net "NCSI_RCSDV_R")
	)
	(via
		(at 86.487 -60.0964)
		(size 0.6604)
		(drill 0.3302)
		(layers "F.Cu" "B.Cu")
		(net "NCSI_RCSDV_R")
	)
	(segment
		(start 89.076276 -114.06886)
		(end 76.807314 -114.06886)
		(width 0.127)
		(layer "F.Cu")
		(net "NCSI_RCSDV")
	)
	(segment
		(start 65.762886 -114.594894)
		(end 65.53708 -114.8207)
		(width 0.127)
		(layer "F.Cu")
		(net "NCSI_RCSDV")
	)
	(segment
		(start 95.0468 -85.7504)
		(end 95.0468 -92.180918)
		(width 0.127)
		(layer "F.Cu")
		(net "NCSI_RCSDV")
	)
	(segment
		(start 94.158308 -113.4618)
		(end 90.2462 -113.4618)
		(width 0.127)
		(layer "F.Cu")
		(net "NCSI_RCSDV")
	)
	(segment
		(start 95.0468 -92.180918)
		(end 97.707958 -94.842076)
		(width 0.127)
		(layer "F.Cu")
		(net "NCSI_RCSDV")
	)
	(segment
		(start 72.1106 -115.9002)
		(end 71.2216 -115.9002)
		(width 0.127)
		(layer "F.Cu")
		(net "NCSI_RCSDV")
	)
	(segment
		(start 89.638886 -114.069114)
		(end 89.07653 -114.069114)
		(width 0.127)
		(layer "F.Cu")
		(net "NCSI_RCSDV")
	)
	(segment
		(start 65.76314 -114.594894)
		(end 65.762886 -114.594894)
		(width 0.127)
		(layer "F.Cu")
		(net "NCSI_RCSDV")
	)
	(segment
		(start 89.07653 -114.069114)
		(end 89.076276 -114.06886)
		(width 0.127)
		(layer "F.Cu")
		(net "NCSI_RCSDV")
	)
	(segment
		(start 97.5106 -99.381564)
		(end 97.5106 -107.2134)
		(width 0.127)
		(layer "F.Cu")
		(net "NCSI_RCSDV")
	)
	(segment
		(start 72.6186 -115.3922)
		(end 72.1106 -115.9002)
		(width 0.127)
		(layer "F.Cu")
		(net "NCSI_RCSDV")
	)
	(segment
		(start 94.006924 -65.937892)
		(end 94.006924 -84.710524)
		(width 0.127)
		(layer "F.Cu")
		(net "NCSI_RCSDV")
	)
	(segment
		(start 65.53708 -114.8207)
		(end 64.5287 -114.8207)
		(width 0.127)
		(layer "F.Cu")
		(net "NCSI_RCSDV")
	)
	(segment
		(start 97.5106 -107.2134)
		(end 97.5106 -110.109508)
		(width 0.127)
		(layer "F.Cu")
		(net "NCSI_RCSDV")
	)
	(segment
		(start 88.666574 -61.534294)
		(end 89.603326 -61.534294)
		(width 0.127)
		(layer "F.Cu")
		(net "NCSI_RCSDV")
	)
	(segment
		(start 97.707958 -99.184206)
		(end 97.5106 -99.381564)
		(width 0.127)
		(layer "F.Cu")
		(net "NCSI_RCSDV")
	)
	(segment
		(start 65.804034 -114.554)
		(end 65.76314 -114.594894)
		(width 0.127)
		(layer "F.Cu")
		(net "NCSI_RCSDV")
	)
	(segment
		(start 94.006924 -84.710524)
		(end 95.0468 -85.7504)
		(width 0.127)
		(layer "F.Cu")
		(net "NCSI_RCSDV")
	)
	(segment
		(start 64.0334 -115.316)
		(end 62.865 -115.316)
		(width 0.127)
		(layer "F.Cu")
		(net "NCSI_RCSDV")
	)
	(segment
		(start 64.5287 -114.8207)
		(end 64.0334 -115.316)
		(width 0.127)
		(layer "F.Cu")
		(net "NCSI_RCSDV")
	)
	(segment
		(start 62.865 -115.316)
		(end 62.1538 -114.6048)
		(width 0.127)
		(layer "F.Cu")
		(net "NCSI_RCSDV")
	)
	(segment
		(start 69.8754 -114.554)
		(end 65.804034 -114.554)
		(width 0.127)
		(layer "F.Cu")
		(net "NCSI_RCSDV")
	)
	(segment
		(start 90.2462 -113.4618)
		(end 89.638886 -114.069114)
		(width 0.127)
		(layer "F.Cu")
		(net "NCSI_RCSDV")
	)
	(segment
		(start 71.2216 -115.9002)
		(end 69.8754 -114.554)
		(width 0.127)
		(layer "F.Cu")
		(net "NCSI_RCSDV")
	)
	(segment
		(start 75.483974 -115.3922)
		(end 72.6186 -115.3922)
		(width 0.127)
		(layer "F.Cu")
		(net "NCSI_RCSDV")
	)
	(segment
		(start 97.5106 -110.109508)
		(end 94.158308 -113.4618)
		(width 0.127)
		(layer "F.Cu")
		(net "NCSI_RCSDV")
	)
	(segment
		(start 76.807314 -114.06886)
		(end 75.483974 -115.3922)
		(width 0.127)
		(layer "F.Cu")
		(net "NCSI_RCSDV")
	)
	(segment
		(start 89.603326 -61.534294)
		(end 94.006924 -65.937892)
		(width 0.127)
		(layer "F.Cu")
		(net "NCSI_RCSDV")
	)
	(segment
		(start 54.500018 -150.199344)
		(end 54.500018 -150.199852)
		(width 0.127)
		(layer "F.Cu")
		(net "NCSI_RCSDV")
	)
	(segment
		(start 54.899814 -149.799548)
		(end 54.500018 -150.199344)
		(width 0.127)
		(layer "F.Cu")
		(net "NCSI_RCSDV")
	)
	(segment
		(start 97.707958 -94.842076)
		(end 97.707958 -99.184206)
		(width 0.127)
		(layer "F.Cu")
		(net "NCSI_RCSDV")
	)
	(via
		(at 62.1538 -114.6048)
		(size 0.508)
		(drill 0.254)
		(layers "F.Cu" "B.Cu")
		(net "NCSI_RCSDV")
	)
	(via
		(at 54.899814 -149.799548)
		(size 0.4572)
		(drill 0.2032)
		(layers "F.Cu" "B.Cu")
		(net "NCSI_RCSDV")
	)
	(via
		(at 66.372232 -148.180552)
		(size 0.508)
		(drill 0.254)
		(layers "F.Cu" "B.Cu")
		(net "NCSI_RCSDV")
	)
	(via
		(at 97.5106 -107.2134)
		(size 0.6604)
		(drill 0.3302)
		(layers "F.Cu" "B.Cu")
		(net "NCSI_RCSDV")
	)
	(segment
		(start 63.313564 -132.073904)
		(end 63.7794 -132.53974)
		(width 0.127)
		(layer "In2.Cu")
		(net "NCSI_RCSDV")
	)
	(segment
		(start 62.169294 -140.997178)
		(end 62.169294 -141.5288)
		(width 0.127)
		(layer "In2.Cu")
		(net "NCSI_RCSDV")
	)
	(segment
		(start 63.7794 -134.040118)
		(end 63.246 -134.573518)
		(width 0.127)
		(layer "In2.Cu")
		(net "NCSI_RCSDV")
	)
	(segment
		(start 64.1096 -146.971766)
		(end 64.1096 -147.3708)
		(width 0.127)
		(layer "In2.Cu")
		(net "NCSI_RCSDV")
	)
	(segment
		(start 63.067946 -126.074424)
		(end 63.067946 -129.717546)
		(width 0.127)
		(layer "In2.Cu")
		(net "NCSI_RCSDV")
	)
	(segment
		(start 62.82309 -145.685256)
		(end 64.1096 -146.971766)
		(width 0.127)
		(layer "In2.Cu")
		(net "NCSI_RCSDV")
	)
	(segment
		(start 64.1096 -147.3708)
		(end 64.6176 -147.8788)
		(width 0.127)
		(layer "In2.Cu")
		(net "NCSI_RCSDV")
	)
	(segment
		(start 63.7794 -132.53974)
		(end 63.7794 -134.040118)
		(width 0.127)
		(layer "In2.Cu")
		(net "NCSI_RCSDV")
	)
	(segment
		(start 62.1538 -114.6048)
		(end 62.1538 -115.1382)
		(width 0.127)
		(layer "In2.Cu")
		(net "NCSI_RCSDV")
	)
	(segment
		(start 63.246 -136.45896)
		(end 62.801754 -136.903206)
		(width 0.127)
		(layer "In2.Cu")
		(net "NCSI_RCSDV")
	)
	(segment
		(start 63.067692 -129.7178)
		(end 63.067692 -130.138424)
		(width 0.127)
		(layer "In2.Cu")
		(net "NCSI_RCSDV")
	)
	(segment
		(start 62.169294 -141.5288)
		(end 62.82309 -142.182596)
		(width 0.127)
		(layer "In2.Cu")
		(net "NCSI_RCSDV")
	)
	(segment
		(start 62.801754 -136.903206)
		(end 62.801246 -136.903206)
		(width 0.127)
		(layer "In2.Cu")
		(net "NCSI_RCSDV")
	)
	(segment
		(start 62.1538 -115.1382)
		(end 62.93866 -115.92306)
		(width 0.127)
		(layer "In2.Cu")
		(net "NCSI_RCSDV")
	)
	(segment
		(start 62.93866 -125.945138)
		(end 63.067946 -126.074424)
		(width 0.127)
		(layer "In2.Cu")
		(net "NCSI_RCSDV")
	)
	(segment
		(start 63.313564 -130.384296)
		(end 63.313564 -132.073904)
		(width 0.127)
		(layer "In2.Cu")
		(net "NCSI_RCSDV")
	)
	(segment
		(start 61.440822 -140.268706)
		(end 62.169294 -140.997178)
		(width 0.127)
		(layer "In2.Cu")
		(net "NCSI_RCSDV")
	)
	(segment
		(start 63.067692 -130.138424)
		(end 63.313564 -130.384296)
		(width 0.127)
		(layer "In2.Cu")
		(net "NCSI_RCSDV")
	)
	(segment
		(start 62.93866 -115.92306)
		(end 62.93866 -125.945138)
		(width 0.127)
		(layer "In2.Cu")
		(net "NCSI_RCSDV")
	)
	(segment
		(start 66.07048 -147.8788)
		(end 66.372232 -148.180552)
		(width 0.127)
		(layer "In2.Cu")
		(net "NCSI_RCSDV")
	)
	(segment
		(start 63.246 -134.573518)
		(end 63.246 -136.45896)
		(width 0.127)
		(layer "In2.Cu")
		(net "NCSI_RCSDV")
	)
	(segment
		(start 61.440822 -138.264138)
		(end 61.440822 -140.268706)
		(width 0.127)
		(layer "In2.Cu")
		(net "NCSI_RCSDV")
	)
	(segment
		(start 63.067946 -129.717546)
		(end 63.067692 -129.7178)
		(width 0.127)
		(layer "In2.Cu")
		(net "NCSI_RCSDV")
	)
	(segment
		(start 64.6176 -147.8788)
		(end 66.07048 -147.8788)
		(width 0.127)
		(layer "In2.Cu")
		(net "NCSI_RCSDV")
	)
	(segment
		(start 62.82309 -142.182596)
		(end 62.82309 -145.685256)
		(width 0.127)
		(layer "In2.Cu")
		(net "NCSI_RCSDV")
	)
	(segment
		(start 61.569346 -138.135614)
		(end 61.440822 -138.264138)
		(width 0.127)
		(layer "In2.Cu")
		(net "NCSI_RCSDV")
	)
	(segment
		(start 62.801246 -136.903206)
		(end 61.569346 -138.135614)
		(width 0.127)
		(layer "In2.Cu")
		(net "NCSI_RCSDV")
	)
	(segment
		(start 66.234564 -148.31822)
		(end 66.372232 -148.180552)
		(width 0.127)
		(layer "In5.Cu")
		(net "NCSI_RCSDV")
	)
	(segment
		(start 61.031882 -148.844)
		(end 61.445902 -148.42998)
		(width 0.127)
		(layer "In5.Cu")
		(net "NCSI_RCSDV")
	)
	(segment
		(start 63.25616 -148.42998)
		(end 63.33744 -148.3487)
		(width 0.127)
		(layer "In5.Cu")
		(net "NCSI_RCSDV")
	)
	(segment
		(start 63.660274 -148.31822)
		(end 66.234564 -148.31822)
		(width 0.127)
		(layer "In5.Cu")
		(net "NCSI_RCSDV")
	)
	(segment
		(start 63.629794 -148.3487)
		(end 63.660274 -148.31822)
		(width 0.127)
		(layer "In5.Cu")
		(net "NCSI_RCSDV")
	)
	(segment
		(start 63.33744 -148.3487)
		(end 63.629794 -148.3487)
		(width 0.127)
		(layer "In5.Cu")
		(net "NCSI_RCSDV")
	)
	(segment
		(start 55.855362 -148.844)
		(end 61.031882 -148.844)
		(width 0.127)
		(layer "In5.Cu")
		(net "NCSI_RCSDV")
	)
	(segment
		(start 54.899814 -149.799548)
		(end 55.855362 -148.844)
		(width 0.127)
		(layer "In5.Cu")
		(net "NCSI_RCSDV")
	)
	(segment
		(start 61.445902 -148.42998)
		(end 63.25616 -148.42998)
		(width 0.127)
		(layer "In5.Cu")
		(net "NCSI_RCSDV")
	)
	(segment
		(start 68.2244 -146.05)
		(end 67.8688 -146.4056)
		(width 0.127)
		(layer "F.Cu")
		(net "NCSI_RCLK_R")
	)
	(segment
		(start 67.9704 -146.8374)
		(end 67.9704 -147.828)
		(width 0.127)
		(layer "F.Cu")
		(net "NCSI_RCLK_R")
	)
	(segment
		(start 67.8688 -146.4056)
		(end 67.8688 -146.7358)
		(width 0.127)
		(layer "F.Cu")
		(net "NCSI_RCLK_R")
	)
	(segment
		(start 69.6595 -146.05)
		(end 68.2244 -146.05)
		(width 0.127)
		(layer "F.Cu")
		(net "NCSI_RCLK_R")
	)
	(segment
		(start 67.8688 -146.7358)
		(end 67.9704 -146.8374)
		(width 0.127)
		(layer "F.Cu")
		(net "NCSI_RCLK_R")
	)
	(via
		(at 67.8688 -146.4056)
		(size 0.6604)
		(drill 0.3302)
		(layers "F.Cu" "B.Cu")
		(net "NCSI_RCLK_R")
	)
	(segment
		(start 89.286842 -113.56086)
		(end 76.50734 -113.56086)
		(width 0.127)
		(layer "F.Cu")
		(net "NCSI_RCLK")
	)
	(segment
		(start 71.247 -147.828)
		(end 71.628 -148.209)
		(width 0.127)
		(layer "F.Cu")
		(net "NCSI_RCLK")
	)
	(segment
		(start 93.49867 -85.24367)
		(end 94.488 -86.233)
		(width 0.127)
		(layer "F.Cu")
		(net "NCSI_RCLK")
	)
	(segment
		(start 70.5485 -146.05)
		(end 71.247 -146.7485)
		(width 0.127)
		(layer "F.Cu")
		(net "NCSI_RCLK")
	)
	(segment
		(start 75.2856 -114.7826)
		(end 73.533 -114.7826)
		(width 0.127)
		(layer "F.Cu")
		(net "NCSI_RCLK")
	)
	(segment
		(start 89.984834 -112.9538)
		(end 89.37752 -113.561114)
		(width 0.127)
		(layer "F.Cu")
		(net "NCSI_RCLK")
	)
	(segment
		(start 93.49867 -66.267838)
		(end 93.49867 -85.24367)
		(width 0.127)
		(layer "F.Cu")
		(net "NCSI_RCLK")
	)
	(segment
		(start 97.199958 -98.380042)
		(end 96.7232 -98.8568)
		(width 0.127)
		(layer "F.Cu")
		(net "NCSI_RCLK")
	)
	(segment
		(start 97.199958 -95.052642)
		(end 97.199958 -98.380042)
		(width 0.127)
		(layer "F.Cu")
		(net "NCSI_RCLK")
	)
	(segment
		(start 71.8312 -114.7826)
		(end 71.4248 -115.189)
		(width 0.127)
		(layer "F.Cu")
		(net "NCSI_RCLK")
	)
	(segment
		(start 94.488 -86.233)
		(end 94.488 -92.340684)
		(width 0.127)
		(layer "F.Cu")
		(net "NCSI_RCLK")
	)
	(segment
		(start 73.533 -114.7826)
		(end 71.8312 -114.7826)
		(width 0.127)
		(layer "F.Cu")
		(net "NCSI_RCLK")
	)
	(segment
		(start 89.466928 -62.236096)
		(end 93.49867 -66.267838)
		(width 0.127)
		(layer "F.Cu")
		(net "NCSI_RCLK")
	)
	(segment
		(start 96.7232 -110.178342)
		(end 93.947742 -112.9538)
		(width 0.127)
		(layer "F.Cu")
		(net "NCSI_RCLK")
	)
	(segment
		(start 71.247 -146.7485)
		(end 71.247 -147.828)
		(width 0.127)
		(layer "F.Cu")
		(net "NCSI_RCLK")
	)
	(segment
		(start 93.947742 -112.9538)
		(end 89.984834 -112.9538)
		(width 0.127)
		(layer "F.Cu")
		(net "NCSI_RCLK")
	)
	(segment
		(start 87.454994 -62.236096)
		(end 89.466928 -62.236096)
		(width 0.127)
		(layer "F.Cu")
		(net "NCSI_RCLK")
	)
	(segment
		(start 94.488 -92.340684)
		(end 97.199958 -95.052642)
		(width 0.127)
		(layer "F.Cu")
		(net "NCSI_RCLK")
	)
	(segment
		(start 96.7232 -98.8568)
		(end 96.7232 -110.178342)
		(width 0.127)
		(layer "F.Cu")
		(net "NCSI_RCLK")
	)
	(segment
		(start 89.287096 -113.561114)
		(end 89.286842 -113.56086)
		(width 0.127)
		(layer "F.Cu")
		(net "NCSI_RCLK")
	)
	(segment
		(start 85.368892 -60.149994)
		(end 87.454994 -62.236096)
		(width 0.127)
		(layer "F.Cu")
		(net "NCSI_RCLK")
	)
	(segment
		(start 79.925164 -60.149994)
		(end 85.368892 -60.149994)
		(width 0.127)
		(layer "F.Cu")
		(net "NCSI_RCLK")
	)
	(segment
		(start 89.37752 -113.561114)
		(end 89.287096 -113.561114)
		(width 0.127)
		(layer "F.Cu")
		(net "NCSI_RCLK")
	)
	(segment
		(start 76.50734 -113.56086)
		(end 75.2856 -114.7826)
		(width 0.127)
		(layer "F.Cu")
		(net "NCSI_RCLK")
	)
	(via
		(at 73.533 -114.7826)
		(size 0.6604)
		(drill 0.3302)
		(layers "F.Cu" "B.Cu")
		(net "NCSI_RCLK")
	)
	(via
		(at 71.628 -148.209)
		(size 0.508)
		(drill 0.254)
		(layers "F.Cu" "B.Cu")
		(net "NCSI_RCLK")
	)
	(via
		(at 71.4248 -115.189)
		(size 0.508)
		(drill 0.254)
		(layers "F.Cu" "B.Cu")
		(net "NCSI_RCLK")
	)
	(segment
		(start 70.200266 -138.467338)
		(end 69.4436 -137.710672)
		(width 0.127)
		(layer "In2.Cu")
		(net "NCSI_RCLK")
	)
	(segment
		(start 69.7992 -123.343416)
		(end 69.7992 -121.7168)
		(width 0.127)
		(layer "In2.Cu")
		(net "NCSI_RCLK")
	)
	(segment
		(start 71.30161 -145.452592)
		(end 71.30161 -143.680688)
		(width 0.127)
		(layer "In2.Cu")
		(net "NCSI_RCLK")
	)
	(segment
		(start 69.4436 -136.262618)
		(end 69.207126 -136.026144)
		(width 0.127)
		(layer "In2.Cu")
		(net "NCSI_RCLK")
	)
	(segment
		(start 69.7992 -121.7168)
		(end 70.5104 -121.0056)
		(width 0.127)
		(layer "In2.Cu")
		(net "NCSI_RCLK")
	)
	(segment
		(start 71.4248 -118.5418)
		(end 71.4248 -117.3988)
		(width 0.127)
		(layer "In2.Cu")
		(net "NCSI_RCLK")
	)
	(segment
		(start 70.5104 -121.0056)
		(end 70.5104 -119.4562)
		(width 0.127)
		(layer "In2.Cu")
		(net "NCSI_RCLK")
	)
	(segment
		(start 69.207126 -136.026144)
		(end 69.207126 -123.93549)
		(width 0.127)
		(layer "In2.Cu")
		(net "NCSI_RCLK")
	)
	(segment
		(start 71.1454 -117.1194)
		(end 71.1454 -115.4938)
		(width 0.127)
		(layer "In2.Cu")
		(net "NCSI_RCLK")
	)
	(segment
		(start 71.4248 -117.3988)
		(end 71.1454 -117.1194)
		(width 0.127)
		(layer "In2.Cu")
		(net "NCSI_RCLK")
	)
	(segment
		(start 70.200266 -142.579344)
		(end 70.200266 -138.467338)
		(width 0.127)
		(layer "In2.Cu")
		(net "NCSI_RCLK")
	)
	(segment
		(start 71.628 -148.209)
		(end 71.628 -145.778982)
		(width 0.127)
		(layer "In2.Cu")
		(net "NCSI_RCLK")
	)
	(segment
		(start 69.207126 -123.93549)
		(end 69.7992 -123.343416)
		(width 0.127)
		(layer "In2.Cu")
		(net "NCSI_RCLK")
	)
	(segment
		(start 71.30161 -143.680688)
		(end 70.200266 -142.579344)
		(width 0.127)
		(layer "In2.Cu")
		(net "NCSI_RCLK")
	)
	(segment
		(start 71.1454 -115.4938)
		(end 71.4248 -115.2144)
		(width 0.127)
		(layer "In2.Cu")
		(net "NCSI_RCLK")
	)
	(segment
		(start 70.5104 -119.4562)
		(end 71.4248 -118.5418)
		(width 0.127)
		(layer "In2.Cu")
		(net "NCSI_RCLK")
	)
	(segment
		(start 69.4436 -137.710672)
		(end 69.4436 -136.262618)
		(width 0.127)
		(layer "In2.Cu")
		(net "NCSI_RCLK")
	)
	(segment
		(start 71.4248 -115.2144)
		(end 71.4248 -115.189)
		(width 0.127)
		(layer "In2.Cu")
		(net "NCSI_RCLK")
	)
	(segment
		(start 71.628 -145.778982)
		(end 71.30161 -145.452592)
		(width 0.127)
		(layer "In2.Cu")
		(net "NCSI_RCLK")
	)
	(segment
		(start 68.628514 -141.59992)
		(end 68.61683 -141.611604)
		(width 0.127)
		(layer "F.Cu")
		(net "I2C_COMP_ALERT_N")
	)
	(segment
		(start 52.899818 -142.999968)
		(end 53.299868 -142.599918)
		(width 0.127)
		(layer "F.Cu")
		(net "I2C_COMP_ALERT_N")
	)
	(segment
		(start 69.422518 -141.59992)
		(end 68.628514 -141.59992)
		(width 0.127)
		(layer "F.Cu")
		(net "I2C_COMP_ALERT_N")
	)
	(via
		(at 96.618298 -174.056294)
		(size 0.508)
		(drill 0.254)
		(layers "F.Cu" "B.Cu")
		(net "I2C_COMP_ALERT_N")
	)
	(via
		(at 94.726506 -142.198852)
		(size 0.508)
		(drill 0.254)
		(layers "F.Cu" "B.Cu")
		(net "I2C_COMP_ALERT_N")
	)
	(via
		(at 53.299868 -142.599918)
		(size 0.4572)
		(drill 0.2032)
		(layers "F.Cu" "B.Cu")
		(net "I2C_COMP_ALERT_N")
	)
	(via
		(at 68.61683 -141.611604)
		(size 0.508)
		(drill 0.254)
		(layers "F.Cu" "B.Cu")
		(net "I2C_COMP_ALERT_N")
	)
	(segment
		(start 94.100904 -176.832514)
		(end 94.100904 -179.216558)
		(width 0.127)
		(layer "B.Cu")
		(net "I2C_COMP_ALERT_N")
	)
	(segment
		(start 96.618298 -174.315374)
		(end 94.100904 -176.832514)
		(width 0.127)
		(layer "B.Cu")
		(net "I2C_COMP_ALERT_N")
	)
	(segment
		(start 94.652846 -179.7685)
		(end 95.377 -179.7685)
		(width 0.127)
		(layer "B.Cu")
		(net "I2C_COMP_ALERT_N")
	)
	(segment
		(start 94.100904 -179.216558)
		(end 94.652846 -179.7685)
		(width 0.127)
		(layer "B.Cu")
		(net "I2C_COMP_ALERT_N")
	)
	(segment
		(start 95.6183 -180.0098)
		(end 97.12198 -180.0098)
		(width 0.127)
		(layer "B.Cu")
		(net "I2C_COMP_ALERT_N")
	)
	(segment
		(start 96.618298 -174.056294)
		(end 96.618298 -174.315374)
		(width 0.127)
		(layer "B.Cu")
		(net "I2C_COMP_ALERT_N")
	)
	(segment
		(start 95.377 -179.7685)
		(end 95.6183 -180.0098)
		(width 0.127)
		(layer "B.Cu")
		(net "I2C_COMP_ALERT_N")
	)
	(segment
		(start 94.5769 -162.810444)
		(end 95.78213 -164.015674)
		(width 0.127)
		(layer "In2.Cu")
		(net "I2C_COMP_ALERT_N")
	)
	(segment
		(start 94.81058 -172.248576)
		(end 96.618298 -174.056294)
		(width 0.127)
		(layer "In2.Cu")
		(net "I2C_COMP_ALERT_N")
	)
	(segment
		(start 94.264988 -149.176994)
		(end 95.4151 -150.327106)
		(width 0.127)
		(layer "In2.Cu")
		(net "I2C_COMP_ALERT_N")
	)
	(segment
		(start 94.264988 -148.32965)
		(end 94.264988 -149.176994)
		(width 0.127)
		(layer "In2.Cu")
		(net "I2C_COMP_ALERT_N")
	)
	(segment
		(start 95.78213 -167.83685)
		(end 94.81058 -168.8084)
		(width 0.127)
		(layer "In2.Cu")
		(net "I2C_COMP_ALERT_N")
	)
	(segment
		(start 95.4151 -152.967436)
		(end 95.8469 -153.399236)
		(width 0.127)
		(layer "In2.Cu")
		(net "I2C_COMP_ALERT_N")
	)
	(segment
		(start 94.81058 -168.8084)
		(end 94.81058 -172.248576)
		(width 0.127)
		(layer "In2.Cu")
		(net "I2C_COMP_ALERT_N")
	)
	(segment
		(start 94.726506 -142.198852)
		(end 94.769686 -142.242032)
		(width 0.127)
		(layer "In2.Cu")
		(net "I2C_COMP_ALERT_N")
	)
	(segment
		(start 95.4151 -150.327106)
		(end 95.4151 -152.967436)
		(width 0.127)
		(layer "In2.Cu")
		(net "I2C_COMP_ALERT_N")
	)
	(segment
		(start 94.5769 -160.61944)
		(end 94.5769 -162.810444)
		(width 0.127)
		(layer "In2.Cu")
		(net "I2C_COMP_ALERT_N")
	)
	(segment
		(start 94.1705 -148.235162)
		(end 94.264988 -148.32965)
		(width 0.127)
		(layer "In2.Cu")
		(net "I2C_COMP_ALERT_N")
	)
	(segment
		(start 94.1705 -146.16176)
		(end 94.1705 -148.235162)
		(width 0.127)
		(layer "In2.Cu")
		(net "I2C_COMP_ALERT_N")
	)
	(segment
		(start 95.78213 -164.015674)
		(end 95.78213 -167.83685)
		(width 0.127)
		(layer "In2.Cu")
		(net "I2C_COMP_ALERT_N")
	)
	(segment
		(start 95.8469 -159.34944)
		(end 94.5769 -160.61944)
		(width 0.127)
		(layer "In2.Cu")
		(net "I2C_COMP_ALERT_N")
	)
	(segment
		(start 95.8469 -153.399236)
		(end 95.8469 -159.34944)
		(width 0.127)
		(layer "In2.Cu")
		(net "I2C_COMP_ALERT_N")
	)
	(segment
		(start 94.769686 -142.242032)
		(end 94.769686 -145.562574)
		(width 0.127)
		(layer "In2.Cu")
		(net "I2C_COMP_ALERT_N")
	)
	(segment
		(start 94.769686 -145.562574)
		(end 94.1705 -146.16176)
		(width 0.127)
		(layer "In2.Cu")
		(net "I2C_COMP_ALERT_N")
	)
	(segment
		(start 89.548716 -142.1257)
		(end 86.916768 -142.1257)
		(width 0.127)
		(layer "In5.Cu")
		(net "I2C_COMP_ALERT_N")
	)
	(segment
		(start 52.906168 -142.993618)
		(end 52.906168 -143.56334)
		(width 0.127)
		(layer "In5.Cu")
		(net "I2C_COMP_ALERT_N")
	)
	(segment
		(start 81.599786 -143.0782)
		(end 81.355184 -143.322802)
		(width 0.127)
		(layer "In5.Cu")
		(net "I2C_COMP_ALERT_N")
	)
	(segment
		(start 65.266062 -141.870938)
		(end 67.326764 -141.870938)
		(width 0.127)
		(layer "In5.Cu")
		(net "I2C_COMP_ALERT_N")
	)
	(segment
		(start 53.299868 -142.599918)
		(end 52.906168 -142.993618)
		(width 0.127)
		(layer "In5.Cu")
		(net "I2C_COMP_ALERT_N")
	)
	(segment
		(start 52.906168 -143.56334)
		(end 53.137054 -143.794226)
		(width 0.127)
		(layer "In5.Cu")
		(net "I2C_COMP_ALERT_N")
	)
	(segment
		(start 92.52204 -142.198852)
		(end 92.366592 -142.3543)
		(width 0.127)
		(layer "In5.Cu")
		(net "I2C_COMP_ALERT_N")
	)
	(segment
		(start 67.326764 -141.870938)
		(end 67.586098 -141.611604)
		(width 0.127)
		(layer "In5.Cu")
		(net "I2C_COMP_ALERT_N")
	)
	(segment
		(start 70.101206 -141.611604)
		(end 68.61683 -141.611604)
		(width 0.127)
		(layer "In5.Cu")
		(net "I2C_COMP_ALERT_N")
	)
	(segment
		(start 92.366592 -142.3543)
		(end 89.777316 -142.3543)
		(width 0.127)
		(layer "In5.Cu")
		(net "I2C_COMP_ALERT_N")
	)
	(segment
		(start 94.726506 -142.198852)
		(end 92.52204 -142.198852)
		(width 0.127)
		(layer "In5.Cu")
		(net "I2C_COMP_ALERT_N")
	)
	(segment
		(start 65.0494 -142.0876)
		(end 65.266062 -141.870938)
		(width 0.127)
		(layer "In5.Cu")
		(net "I2C_COMP_ALERT_N")
	)
	(segment
		(start 81.355184 -143.322802)
		(end 74.50328 -143.322802)
		(width 0.127)
		(layer "In5.Cu")
		(net "I2C_COMP_ALERT_N")
	)
	(segment
		(start 71.356728 -142.867126)
		(end 70.101206 -141.611604)
		(width 0.127)
		(layer "In5.Cu")
		(net "I2C_COMP_ALERT_N")
	)
	(segment
		(start 56.45912 -143.794226)
		(end 58.165746 -142.0876)
		(width 0.127)
		(layer "In5.Cu")
		(net "I2C_COMP_ALERT_N")
	)
	(segment
		(start 85.964268 -143.0782)
		(end 81.599786 -143.0782)
		(width 0.127)
		(layer "In5.Cu")
		(net "I2C_COMP_ALERT_N")
	)
	(segment
		(start 74.50328 -143.322802)
		(end 74.047604 -142.867126)
		(width 0.127)
		(layer "In5.Cu")
		(net "I2C_COMP_ALERT_N")
	)
	(segment
		(start 89.777316 -142.3543)
		(end 89.548716 -142.1257)
		(width 0.127)
		(layer "In5.Cu")
		(net "I2C_COMP_ALERT_N")
	)
	(segment
		(start 74.047604 -142.867126)
		(end 71.356728 -142.867126)
		(width 0.127)
		(layer "In5.Cu")
		(net "I2C_COMP_ALERT_N")
	)
	(segment
		(start 53.137054 -143.794226)
		(end 56.45912 -143.794226)
		(width 0.127)
		(layer "In5.Cu")
		(net "I2C_COMP_ALERT_N")
	)
	(segment
		(start 67.586098 -141.611604)
		(end 68.61683 -141.611604)
		(width 0.127)
		(layer "In5.Cu")
		(net "I2C_COMP_ALERT_N")
	)
	(segment
		(start 58.165746 -142.0876)
		(end 65.0494 -142.0876)
		(width 0.127)
		(layer "In5.Cu")
		(net "I2C_COMP_ALERT_N")
	)
	(segment
		(start 86.916768 -142.1257)
		(end 85.964268 -143.0782)
		(width 0.127)
		(layer "In5.Cu")
		(net "I2C_COMP_ALERT_N")
	)
	(via
		(at 86.741 -179.578)
		(size 0.6096)
		(drill 0.3048)
		(layers "F.Cu" "B.Cu")
		(net "I2C_BMC_COMP_SDA_R")
	)
	(segment
		(start 88.0745 -179.578)
		(end 88.265 -179.3875)
		(width 0.127)
		(layer "B.Cu")
		(net "I2C_BMC_COMP_SDA_R")
	)
	(segment
		(start 85.678264 -179.578)
		(end 85.334348 -179.234084)
		(width 0.127)
		(layer "B.Cu")
		(net "I2C_BMC_COMP_SDA_R")
	)
	(segment
		(start 90.06078 -178.31816)
		(end 89.33434 -178.31816)
		(width 0.127)
		(layer "B.Cu")
		(net "I2C_BMC_COMP_SDA_R")
	)
	(segment
		(start 86.741 -179.578)
		(end 88.0745 -179.578)
		(width 0.127)
		(layer "B.Cu")
		(net "I2C_BMC_COMP_SDA_R")
	)
	(segment
		(start 89.33434 -178.31816)
		(end 88.265 -179.3875)
		(width 0.127)
		(layer "B.Cu")
		(net "I2C_BMC_COMP_SDA_R")
	)
	(segment
		(start 86.741 -179.578)
		(end 85.678264 -179.578)
		(width 0.127)
		(layer "B.Cu")
		(net "I2C_BMC_COMP_SDA_R")
	)
	(segment
		(start 62.98946 -147.03806)
		(end 62.98946 -147.13712)
		(width 0.127)
		(layer "F.Cu")
		(net "I2C_BMC_COMP_SDA_OUT")
	)
	(segment
		(start 64.048894 -147.586954)
		(end 64.353694 -147.891754)
		(width 0.127)
		(layer "F.Cu")
		(net "I2C_BMC_COMP_SDA_OUT")
	)
	(segment
		(start 62.8396 -146.8882)
		(end 62.1919 -146.8882)
		(width 0.127)
		(layer "F.Cu")
		(net "I2C_BMC_COMP_SDA_OUT")
	)
	(segment
		(start 64.94272 -147.891754)
		(end 65.494154 -147.34032)
		(width 0.127)
		(layer "F.Cu")
		(net "I2C_BMC_COMP_SDA_OUT")
	)
	(segment
		(start 62.98946 -147.13712)
		(end 63.439294 -147.586954)
		(width 0.127)
		(layer "F.Cu")
		(net "I2C_BMC_COMP_SDA_OUT")
	)
	(segment
		(start 64.353694 -147.891754)
		(end 64.94272 -147.891754)
		(width 0.127)
		(layer "F.Cu")
		(net "I2C_BMC_COMP_SDA_OUT")
	)
	(segment
		(start 62.8396 -146.8882)
		(end 62.98946 -147.03806)
		(width 0.127)
		(layer "F.Cu")
		(net "I2C_BMC_COMP_SDA_OUT")
	)
	(segment
		(start 62.1919 -146.8882)
		(end 61.8363 -146.5326)
		(width 0.127)
		(layer "F.Cu")
		(net "I2C_BMC_COMP_SDA_OUT")
	)
	(segment
		(start 63.439294 -147.586954)
		(end 64.048894 -147.586954)
		(width 0.127)
		(layer "F.Cu")
		(net "I2C_BMC_COMP_SDA_OUT")
	)
	(via
		(at 88.0364 -181.483)
		(size 0.508)
		(drill 0.254)
		(layers "F.Cu" "B.Cu")
		(net "I2C_BMC_COMP_SDA_OUT")
	)
	(via
		(at 84.7344 -159.517842)
		(size 0.6096)
		(drill 0.3048)
		(layers "F.Cu" "B.Cu")
		(net "I2C_BMC_COMP_SDA_OUT")
	)
	(via
		(at 87.884 -173.8122)
		(size 0.508)
		(drill 0.254)
		(layers "F.Cu" "B.Cu")
		(net "I2C_BMC_COMP_SDA_OUT")
	)
	(via
		(at 97.4852 -174.8536)
		(size 0.508)
		(drill 0.254)
		(layers "F.Cu" "B.Cu")
		(net "I2C_BMC_COMP_SDA_OUT")
	)
	(via
		(at 65.494154 -147.34032)
		(size 0.508)
		(drill 0.254)
		(layers "F.Cu" "B.Cu")
		(net "I2C_BMC_COMP_SDA_OUT")
	)
	(segment
		(start 88.265 -180.2765)
		(end 88.265 -181.2544)
		(width 0.127)
		(layer "B.Cu")
		(net "I2C_BMC_COMP_SDA_OUT")
	)
	(segment
		(start 83.833716 -159.517842)
		(end 84.7344 -159.517842)
		(width 0.127)
		(layer "B.Cu")
		(net "I2C_BMC_COMP_SDA_OUT")
	)
	(segment
		(start 94.807532 -163.018216)
		(end 95.487744 -163.698428)
		(width 0.127)
		(layer "B.Cu")
		(net "I2C_BMC_COMP_SDA_OUT")
	)
	(segment
		(start 92.039948 -159.665924)
		(end 92.221558 -159.847534)
		(width 0.127)
		(layer "B.Cu")
		(net "I2C_BMC_COMP_SDA_OUT")
	)
	(segment
		(start 65.902332 -148.37537)
		(end 65.9257 -148.398738)
		(width 0.127)
		(layer "B.Cu")
		(net "I2C_BMC_COMP_SDA_OUT")
	)
	(segment
		(start 66.951606 -152.146254)
		(end 67.37223 -152.146254)
		(width 0.127)
		(layer "B.Cu")
		(net "I2C_BMC_COMP_SDA_OUT")
	)
	(segment
		(start 74.781918 -155.181808)
		(end 79.497682 -155.181808)
		(width 0.127)
		(layer "B.Cu")
		(net "I2C_BMC_COMP_SDA_OUT")
	)
	(segment
		(start 97.197418 -165.595554)
		(end 97.486978 -165.595554)
		(width 0.127)
		(layer "B.Cu")
		(net "I2C_BMC_COMP_SDA_OUT")
	)
	(segment
		(start 97.49536 -171.423584)
		(end 97.49536 -174.84344)
		(width 0.127)
		(layer "B.Cu")
		(net "I2C_BMC_COMP_SDA_OUT")
	)
	(segment
		(start 94.020132 -163.018216)
		(end 94.807532 -163.018216)
		(width 0.127)
		(layer "B.Cu")
		(net "I2C_BMC_COMP_SDA_OUT")
	)
	(segment
		(start 87.923624 -158.1023)
		(end 90.212672 -158.1023)
		(width 0.127)
		(layer "B.Cu")
		(net "I2C_BMC_COMP_SDA_OUT")
	)
	(segment
		(start 95.487744 -163.88588)
		(end 97.197418 -165.595554)
		(width 0.127)
		(layer "B.Cu")
		(net "I2C_BMC_COMP_SDA_OUT")
	)
	(segment
		(start 65.9257 -148.398738)
		(end 65.9257 -149.260052)
		(width 0.127)
		(layer "B.Cu")
		(net "I2C_BMC_COMP_SDA_OUT")
	)
	(segment
		(start 65.4431 -149.742652)
		(end 65.4431 -150.637748)
		(width 0.127)
		(layer "B.Cu")
		(net "I2C_BMC_COMP_SDA_OUT")
	)
	(segment
		(start 92.039948 -159.006286)
		(end 92.039948 -159.665924)
		(width 0.127)
		(layer "B.Cu")
		(net "I2C_BMC_COMP_SDA_OUT")
	)
	(segment
		(start 67.372484 -152.146)
		(end 71.74611 -152.146)
		(width 0.127)
		(layer "B.Cu")
		(net "I2C_BMC_COMP_SDA_OUT")
	)
	(segment
		(start 65.9257 -149.260052)
		(end 65.4431 -149.742652)
		(width 0.127)
		(layer "B.Cu")
		(net "I2C_BMC_COMP_SDA_OUT")
	)
	(segment
		(start 65.494154 -147.34032)
		(end 65.902332 -147.748498)
		(width 0.127)
		(layer "B.Cu")
		(net "I2C_BMC_COMP_SDA_OUT")
	)
	(segment
		(start 87.087964 -158.93796)
		(end 87.923624 -158.1023)
		(width 0.127)
		(layer "B.Cu")
		(net "I2C_BMC_COMP_SDA_OUT")
	)
	(segment
		(start 65.4431 -150.637748)
		(end 66.951606 -152.146254)
		(width 0.127)
		(layer "B.Cu")
		(net "I2C_BMC_COMP_SDA_OUT")
	)
	(segment
		(start 71.74611 -152.146)
		(end 74.781918 -155.181808)
		(width 0.127)
		(layer "B.Cu")
		(net "I2C_BMC_COMP_SDA_OUT")
	)
	(segment
		(start 85.786722 -158.93796)
		(end 87.087964 -158.93796)
		(width 0.127)
		(layer "B.Cu")
		(net "I2C_BMC_COMP_SDA_OUT")
	)
	(segment
		(start 97.486978 -165.595554)
		(end 97.487232 -165.595808)
		(width 0.127)
		(layer "B.Cu")
		(net "I2C_BMC_COMP_SDA_OUT")
	)
	(segment
		(start 90.06078 -178.9684)
		(end 89.5731 -178.9684)
		(width 0.127)
		(layer "B.Cu")
		(net "I2C_BMC_COMP_SDA_OUT")
	)
	(segment
		(start 97.736406 -165.595808)
		(end 99.898454 -167.757856)
		(width 0.127)
		(layer "B.Cu")
		(net "I2C_BMC_COMP_SDA_OUT")
	)
	(segment
		(start 91.367102 -158.33344)
		(end 92.039948 -159.006286)
		(width 0.127)
		(layer "B.Cu")
		(net "I2C_BMC_COMP_SDA_OUT")
	)
	(segment
		(start 88.265 -181.2544)
		(end 88.0364 -181.483)
		(width 0.127)
		(layer "B.Cu")
		(net "I2C_BMC_COMP_SDA_OUT")
	)
	(segment
		(start 79.497682 -155.181808)
		(end 83.833716 -159.517842)
		(width 0.127)
		(layer "B.Cu")
		(net "I2C_BMC_COMP_SDA_OUT")
	)
	(segment
		(start 84.7344 -159.517842)
		(end 85.20684 -159.517842)
		(width 0.127)
		(layer "B.Cu")
		(net "I2C_BMC_COMP_SDA_OUT")
	)
	(segment
		(start 90.212672 -158.1023)
		(end 90.443812 -158.33344)
		(width 0.127)
		(layer "B.Cu")
		(net "I2C_BMC_COMP_SDA_OUT")
	)
	(segment
		(start 99.898454 -167.757856)
		(end 99.898454 -169.02049)
		(width 0.127)
		(layer "B.Cu")
		(net "I2C_BMC_COMP_SDA_OUT")
	)
	(segment
		(start 95.487744 -163.698428)
		(end 95.487744 -163.88588)
		(width 0.127)
		(layer "B.Cu")
		(net "I2C_BMC_COMP_SDA_OUT")
	)
	(segment
		(start 65.902332 -147.748498)
		(end 65.902332 -148.37537)
		(width 0.127)
		(layer "B.Cu")
		(net "I2C_BMC_COMP_SDA_OUT")
	)
	(segment
		(start 92.221558 -159.847534)
		(end 92.221558 -161.219642)
		(width 0.127)
		(layer "B.Cu")
		(net "I2C_BMC_COMP_SDA_OUT")
	)
	(segment
		(start 67.37223 -152.146254)
		(end 67.372484 -152.146)
		(width 0.127)
		(layer "B.Cu")
		(net "I2C_BMC_COMP_SDA_OUT")
	)
	(segment
		(start 92.221558 -161.219642)
		(end 94.020132 -163.018216)
		(width 0.127)
		(layer "B.Cu")
		(net "I2C_BMC_COMP_SDA_OUT")
	)
	(segment
		(start 97.487232 -165.595808)
		(end 97.736406 -165.595808)
		(width 0.127)
		(layer "B.Cu")
		(net "I2C_BMC_COMP_SDA_OUT")
	)
	(segment
		(start 85.20684 -159.517842)
		(end 85.786722 -158.93796)
		(width 0.127)
		(layer "B.Cu")
		(net "I2C_BMC_COMP_SDA_OUT")
	)
	(segment
		(start 97.49536 -174.84344)
		(end 97.4852 -174.8536)
		(width 0.127)
		(layer "B.Cu")
		(net "I2C_BMC_COMP_SDA_OUT")
	)
	(segment
		(start 89.5731 -178.9684)
		(end 88.265 -180.2765)
		(width 0.127)
		(layer "B.Cu")
		(net "I2C_BMC_COMP_SDA_OUT")
	)
	(segment
		(start 90.443812 -158.33344)
		(end 91.367102 -158.33344)
		(width 0.127)
		(layer "B.Cu")
		(net "I2C_BMC_COMP_SDA_OUT")
	)
	(segment
		(start 99.898454 -169.02049)
		(end 97.49536 -171.423584)
		(width 0.127)
		(layer "B.Cu")
		(net "I2C_BMC_COMP_SDA_OUT")
	)
	(segment
		(start 88.0364 -180.3146)
		(end 87.32901 -179.60721)
		(width 0.127)
		(layer "In2.Cu")
		(net "I2C_BMC_COMP_SDA_OUT")
	)
	(segment
		(start 87.884 -177.766726)
		(end 87.884 -173.8122)
		(width 0.127)
		(layer "In2.Cu")
		(net "I2C_BMC_COMP_SDA_OUT")
	)
	(segment
		(start 87.32901 -179.60721)
		(end 87.32901 -178.321716)
		(width 0.127)
		(layer "In2.Cu")
		(net "I2C_BMC_COMP_SDA_OUT")
	)
	(segment
		(start 88.0364 -181.483)
		(end 88.0364 -180.3146)
		(width 0.127)
		(layer "In2.Cu")
		(net "I2C_BMC_COMP_SDA_OUT")
	)
	(segment
		(start 87.32901 -178.321716)
		(end 87.884 -177.766726)
		(width 0.127)
		(layer "In2.Cu")
		(net "I2C_BMC_COMP_SDA_OUT")
	)
	(segment
		(start 97.4852 -174.8536)
		(end 97.44202 -174.81042)
		(width 0.127)
		(layer "In5.Cu")
		(net "I2C_BMC_COMP_SDA_OUT")
	)
	(segment
		(start 97.44202 -174.81042)
		(end 96.2914 -174.81042)
		(width 0.127)
		(layer "In5.Cu")
		(net "I2C_BMC_COMP_SDA_OUT")
	)
	(segment
		(start 91.966034 -173.4566)
		(end 91.102434 -174.3202)
		(width 0.127)
		(layer "In5.Cu")
		(net "I2C_BMC_COMP_SDA_OUT")
	)
	(segment
		(start 88.392 -174.3202)
		(end 87.884 -173.8122)
		(width 0.127)
		(layer "In5.Cu")
		(net "I2C_BMC_COMP_SDA_OUT")
	)
	(segment
		(start 94.93758 -173.4566)
		(end 91.966034 -173.4566)
		(width 0.127)
		(layer "In5.Cu")
		(net "I2C_BMC_COMP_SDA_OUT")
	)
	(segment
		(start 96.2914 -174.81042)
		(end 94.93758 -173.4566)
		(width 0.127)
		(layer "In5.Cu")
		(net "I2C_BMC_COMP_SDA_OUT")
	)
	(segment
		(start 91.102434 -174.3202)
		(end 88.392 -174.3202)
		(width 0.127)
		(layer "In5.Cu")
		(net "I2C_BMC_COMP_SDA_OUT")
	)
	(segment
		(start 99.45878 -121.89968)
		(end 99.459034 -121.899426)
		(width 0.127)
		(layer "F.Cu")
		(net "I2C_BMC_COMP_SDA")
	)
	(segment
		(start 117.1448 -24.4348)
		(end 118.471442 -25.761442)
		(width 0.127)
		(layer "F.Cu")
		(net "I2C_BMC_COMP_SDA")
	)
	(segment
		(start 100.457762 -42.301922)
		(end 100.457762 -26.94051)
		(width 0.127)
		(layer "F.Cu")
		(net "I2C_BMC_COMP_SDA")
	)
	(segment
		(start 115.435126 -20.471892)
		(end 117.1448 -22.181566)
		(width 0.127)
		(layer "F.Cu")
		(net "I2C_BMC_COMP_SDA")
	)
	(segment
		(start 99.478084 -46.223682)
		(end 101.17836 -44.523406)
		(width 0.127)
		(layer "F.Cu")
		(net "I2C_BMC_COMP_SDA")
	)
	(segment
		(start 108.149644 -20.471892)
		(end 115.435126 -20.471892)
		(width 0.127)
		(layer "F.Cu")
		(net "I2C_BMC_COMP_SDA")
	)
	(segment
		(start 99.478084 -87.980012)
		(end 99.478084 -46.223682)
		(width 0.127)
		(layer "F.Cu")
		(net "I2C_BMC_COMP_SDA")
	)
	(segment
		(start 100.166932 -126.865634)
		(end 99.087686 -125.786388)
		(width 0.127)
		(layer "F.Cu")
		(net "I2C_BMC_COMP_SDA")
	)
	(segment
		(start 101.17836 -44.523406)
		(end 101.17836 -43.02252)
		(width 0.127)
		(layer "F.Cu")
		(net "I2C_BMC_COMP_SDA")
	)
	(segment
		(start 102.366064 -135.919972)
		(end 101.74351 -135.297418)
		(width 0.127)
		(layer "F.Cu")
		(net "I2C_BMC_COMP_SDA")
	)
	(segment
		(start 100.166932 -127.37084)
		(end 100.166932 -126.865634)
		(width 0.127)
		(layer "F.Cu")
		(net "I2C_BMC_COMP_SDA")
	)
	(segment
		(start 99.45878 -123.148852)
		(end 99.45878 -121.89968)
		(width 0.127)
		(layer "F.Cu")
		(net "I2C_BMC_COMP_SDA")
	)
	(segment
		(start 107.282234 -21.339302)
		(end 108.149644 -20.471892)
		(width 0.127)
		(layer "F.Cu")
		(net "I2C_BMC_COMP_SDA")
	)
	(segment
		(start 99.473512 -92.229178)
		(end 99.473512 -87.984584)
		(width 0.127)
		(layer "F.Cu")
		(net "I2C_BMC_COMP_SDA")
	)
	(segment
		(start 118.471442 -41.228518)
		(end 117.899942 -41.800018)
		(width 0.127)
		(layer "F.Cu")
		(net "I2C_BMC_COMP_SDA")
	)
	(segment
		(start 100.604828 -127.808736)
		(end 100.166932 -127.37084)
		(width 0.127)
		(layer "F.Cu")
		(net "I2C_BMC_COMP_SDA")
	)
	(segment
		(start 99.087686 -125.786388)
		(end 99.087686 -123.519946)
		(width 0.127)
		(layer "F.Cu")
		(net "I2C_BMC_COMP_SDA")
	)
	(segment
		(start 101.17836 -43.02252)
		(end 100.457762 -42.301922)
		(width 0.127)
		(layer "F.Cu")
		(net "I2C_BMC_COMP_SDA")
	)
	(segment
		(start 99.459034 -121.899426)
		(end 99.459034 -121.410476)
		(width 0.127)
		(layer "F.Cu")
		(net "I2C_BMC_COMP_SDA")
	)
	(segment
		(start 117.1448 -22.181566)
		(end 117.1448 -24.4348)
		(width 0.127)
		(layer "F.Cu")
		(net "I2C_BMC_COMP_SDA")
	)
	(segment
		(start 99.087686 -123.519946)
		(end 99.45878 -123.148852)
		(width 0.127)
		(layer "F.Cu")
		(net "I2C_BMC_COMP_SDA")
	)
	(segment
		(start 100.457762 -26.94051)
		(end 106.05897 -21.339302)
		(width 0.127)
		(layer "F.Cu")
		(net "I2C_BMC_COMP_SDA")
	)
	(segment
		(start 101.29139 -135.297418)
		(end 100.604828 -134.610856)
		(width 0.127)
		(layer "F.Cu")
		(net "I2C_BMC_COMP_SDA")
	)
	(segment
		(start 100.604828 -134.610856)
		(end 100.604828 -127.808736)
		(width 0.127)
		(layer "F.Cu")
		(net "I2C_BMC_COMP_SDA")
	)
	(segment
		(start 102.366064 -176.806352)
		(end 102.366064 -135.919972)
		(width 0.127)
		(layer "F.Cu")
		(net "I2C_BMC_COMP_SDA")
	)
	(segment
		(start 101.74351 -135.297418)
		(end 101.29139 -135.297418)
		(width 0.127)
		(layer "F.Cu")
		(net "I2C_BMC_COMP_SDA")
	)
	(segment
		(start 100.247958 -93.003624)
		(end 99.473512 -92.229178)
		(width 0.127)
		(layer "F.Cu")
		(net "I2C_BMC_COMP_SDA")
	)
	(segment
		(start 100.247958 -120.621552)
		(end 100.247958 -93.003624)
		(width 0.127)
		(layer "F.Cu")
		(net "I2C_BMC_COMP_SDA")
	)
	(segment
		(start 99.459034 -121.410476)
		(end 100.247958 -120.621552)
		(width 0.127)
		(layer "F.Cu")
		(net "I2C_BMC_COMP_SDA")
	)
	(segment
		(start 101.385116 -177.7873)
		(end 102.366064 -176.806352)
		(width 0.127)
		(layer "F.Cu")
		(net "I2C_BMC_COMP_SDA")
	)
	(segment
		(start 118.471442 -25.761442)
		(end 118.471442 -41.228518)
		(width 0.127)
		(layer "F.Cu")
		(net "I2C_BMC_COMP_SDA")
	)
	(segment
		(start 106.05897 -21.339302)
		(end 107.282234 -21.339302)
		(width 0.127)
		(layer "F.Cu")
		(net "I2C_BMC_COMP_SDA")
	)
	(segment
		(start 99.473512 -87.984584)
		(end 99.478084 -87.980012)
		(width 0.127)
		(layer "F.Cu")
		(net "I2C_BMC_COMP_SDA")
	)
	(via
		(at 86.8426 -175.3489)
		(size 0.508)
		(drill 0.254)
		(layers "F.Cu" "B.Cu")
		(net "I2C_BMC_COMP_SDA")
	)
	(via
		(at 84.667852 -177.026062)
		(size 0.6096)
		(drill 0.3048)
		(layers "F.Cu" "B.Cu")
		(net "I2C_BMC_COMP_SDA")
	)
	(via
		(at 101.385116 -177.7873)
		(size 0.508)
		(drill 0.254)
		(layers "F.Cu" "B.Cu")
		(net "I2C_BMC_COMP_SDA")
	)
	(segment
		(start 85.860382 -175.133)
		(end 84.667852 -176.32553)
		(width 0.127)
		(layer "B.Cu")
		(net "I2C_BMC_COMP_SDA")
	)
	(segment
		(start 84.667852 -177.678588)
		(end 85.334348 -178.345084)
		(width 0.127)
		(layer "B.Cu")
		(net "I2C_BMC_COMP_SDA")
	)
	(segment
		(start 84.667852 -176.32553)
		(end 84.667852 -177.026062)
		(width 0.127)
		(layer "B.Cu")
		(net "I2C_BMC_COMP_SDA")
	)
	(segment
		(start 86.6267 -175.133)
		(end 85.860382 -175.133)
		(width 0.127)
		(layer "B.Cu")
		(net "I2C_BMC_COMP_SDA")
	)
	(segment
		(start 86.8426 -175.3489)
		(end 86.6267 -175.133)
		(width 0.127)
		(layer "B.Cu")
		(net "I2C_BMC_COMP_SDA")
	)
	(segment
		(start 84.667852 -177.026062)
		(end 84.667852 -177.678588)
		(width 0.127)
		(layer "B.Cu")
		(net "I2C_BMC_COMP_SDA")
	)
	(segment
		(start 98.33737 -176.45253)
		(end 100.050346 -176.45253)
		(width 0.127)
		(layer "In5.Cu")
		(net "I2C_BMC_COMP_SDA")
	)
	(segment
		(start 95.2373 -176.71542)
		(end 98.07448 -176.71542)
		(width 0.127)
		(layer "In5.Cu")
		(net "I2C_BMC_COMP_SDA")
	)
	(segment
		(start 100.050346 -176.45253)
		(end 101.385116 -177.7873)
		(width 0.127)
		(layer "In5.Cu")
		(net "I2C_BMC_COMP_SDA")
	)
	(segment
		(start 93.683582 -176.5935)
		(end 94.073218 -176.5935)
		(width 0.127)
		(layer "In5.Cu")
		(net "I2C_BMC_COMP_SDA")
	)
	(segment
		(start 94.214188 -176.45253)
		(end 94.97441 -176.45253)
		(width 0.127)
		(layer "In5.Cu")
		(net "I2C_BMC_COMP_SDA")
	)
	(segment
		(start 93.542612 -176.45253)
		(end 93.683582 -176.5935)
		(width 0.127)
		(layer "In5.Cu")
		(net "I2C_BMC_COMP_SDA")
	)
	(segment
		(start 87.94623 -176.45253)
		(end 93.542612 -176.45253)
		(width 0.127)
		(layer "In5.Cu")
		(net "I2C_BMC_COMP_SDA")
	)
	(segment
		(start 86.8426 -175.3489)
		(end 87.94623 -176.45253)
		(width 0.127)
		(layer "In5.Cu")
		(net "I2C_BMC_COMP_SDA")
	)
	(segment
		(start 98.07448 -176.71542)
		(end 98.33737 -176.45253)
		(width 0.127)
		(layer "In5.Cu")
		(net "I2C_BMC_COMP_SDA")
	)
	(segment
		(start 94.073218 -176.5935)
		(end 94.214188 -176.45253)
		(width 0.127)
		(layer "In5.Cu")
		(net "I2C_BMC_COMP_SDA")
	)
	(segment
		(start 94.97441 -176.45253)
		(end 95.2373 -176.71542)
		(width 0.127)
		(layer "In5.Cu")
		(net "I2C_BMC_COMP_SDA")
	)
	(via
		(at 88.14054 -175.787304)
		(size 0.6096)
		(drill 0.3048)
		(layers "F.Cu" "B.Cu")
		(net "I2C_BMC_COMP_SCL_R")
	)
	(segment
		(start 86.9061 -176.9364)
		(end 86.7791 -176.8094)
		(width 0.127)
		(layer "B.Cu")
		(net "I2C_BMC_COMP_SCL_R")
	)
	(segment
		(start 87.796116 -176.92751)
		(end 87.796116 -176.131728)
		(width 0.127)
		(layer "B.Cu")
		(net "I2C_BMC_COMP_SCL_R")
	)
	(segment
		(start 87.787226 -176.9364)
		(end 86.9061 -176.9364)
		(width 0.127)
		(layer "B.Cu")
		(net "I2C_BMC_COMP_SCL_R")
	)
	(segment
		(start 87.796116 -176.131728)
		(end 88.14054 -175.787304)
		(width 0.127)
		(layer "B.Cu")
		(net "I2C_BMC_COMP_SCL_R")
	)
	(segment
		(start 88.14054 -175.787304)
		(end 88.810084 -175.11776)
		(width 0.127)
		(layer "B.Cu")
		(net "I2C_BMC_COMP_SCL_R")
	)
	(segment
		(start 88.810084 -175.11776)
		(end 90.03538 -175.11776)
		(width 0.127)
		(layer "B.Cu")
		(net "I2C_BMC_COMP_SCL_R")
	)
	(segment
		(start 87.796116 -176.92751)
		(end 87.787226 -176.9364)
		(width 0.127)
		(layer "B.Cu")
		(net "I2C_BMC_COMP_SCL_R")
	)
	(segment
		(start 66.22796 -149.00656)
		(end 65.4304 -148.209)
		(width 0.127)
		(layer "F.Cu")
		(net "I2C_BMC_COMP_SCL_OUT")
	)
	(segment
		(start 63.4619 -148.209)
		(end 62.9031 -148.7678)
		(width 0.127)
		(layer "F.Cu")
		(net "I2C_BMC_COMP_SCL_OUT")
	)
	(segment
		(start 61.8109 -147.6756)
		(end 62.9031 -148.7678)
		(width 0.127)
		(layer "F.Cu")
		(net "I2C_BMC_COMP_SCL_OUT")
	)
	(segment
		(start 65.4304 -148.209)
		(end 63.4619 -148.209)
		(width 0.127)
		(layer "F.Cu")
		(net "I2C_BMC_COMP_SCL_OUT")
	)
	(segment
		(start 66.548 -149.0726)
		(end 66.48196 -149.00656)
		(width 0.127)
		(layer "F.Cu")
		(net "I2C_BMC_COMP_SCL_OUT")
	)
	(segment
		(start 66.48196 -149.00656)
		(end 66.22796 -149.00656)
		(width 0.127)
		(layer "F.Cu")
		(net "I2C_BMC_COMP_SCL_OUT")
	)
	(segment
		(start 61.8109 -147.5994)
		(end 61.8109 -147.6756)
		(width 0.127)
		(layer "F.Cu")
		(net "I2C_BMC_COMP_SCL_OUT")
	)
	(via
		(at 82.090514 -157.03804)
		(size 0.6096)
		(drill 0.3048)
		(layers "F.Cu" "B.Cu")
		(net "I2C_BMC_COMP_SCL_OUT")
	)
	(via
		(at 86.4362 -178.5874)
		(size 0.508)
		(drill 0.254)
		(layers "F.Cu" "B.Cu")
		(net "I2C_BMC_COMP_SCL_OUT")
	)
	(via
		(at 66.548 -149.0726)
		(size 0.508)
		(drill 0.254)
		(layers "F.Cu" "B.Cu")
		(net "I2C_BMC_COMP_SCL_OUT")
	)
	(via
		(at 96.5962 -178.562)
		(size 0.508)
		(drill 0.254)
		(layers "F.Cu" "B.Cu")
		(net "I2C_BMC_COMP_SCL_OUT")
	)
	(segment
		(start 74.992484 -154.673808)
		(end 79.726282 -154.673808)
		(width 0.127)
		(layer "B.Cu")
		(net "I2C_BMC_COMP_SCL_OUT")
	)
	(segment
		(start 71.956676 -151.638)
		(end 74.992484 -154.673808)
		(width 0.127)
		(layer "B.Cu")
		(net "I2C_BMC_COMP_SCL_OUT")
	)
	(segment
		(start 95.995744 -163.675314)
		(end 97.407984 -165.087554)
		(width 0.127)
		(layer "B.Cu")
		(net "I2C_BMC_COMP_SCL_OUT")
	)
	(segment
		(start 92.767912 -161.04743)
		(end 94.230698 -162.510216)
		(width 0.127)
		(layer "B.Cu")
		(net "I2C_BMC_COMP_SCL_OUT")
	)
	(segment
		(start 79.726282 -154.673808)
		(end 82.090514 -157.03804)
		(width 0.127)
		(layer "B.Cu")
		(net "I2C_BMC_COMP_SCL_OUT")
	)
	(segment
		(start 98.138488 -171.499022)
		(end 98.138488 -176.029112)
		(width 0.127)
		(layer "B.Cu")
		(net "I2C_BMC_COMP_SCL_OUT")
	)
	(segment
		(start 87.796116 -177.81651)
		(end 88.699848 -176.912778)
		(width 0.127)
		(layer "B.Cu")
		(net "I2C_BMC_COMP_SCL_OUT")
	)
	(segment
		(start 66.548 -149.0726)
		(end 66.4337 -149.1869)
		(width 0.127)
		(layer "B.Cu")
		(net "I2C_BMC_COMP_SCL_OUT")
	)
	(segment
		(start 97.407984 -165.087554)
		(end 97.955354 -165.087554)
		(width 0.127)
		(layer "B.Cu")
		(net "I2C_BMC_COMP_SCL_OUT")
	)
	(segment
		(start 87.796116 -177.81651)
		(end 87.025226 -178.5874)
		(width 0.127)
		(layer "B.Cu")
		(net "I2C_BMC_COMP_SCL_OUT")
	)
	(segment
		(start 96.902524 -177.265076)
		(end 96.902524 -178.255676)
		(width 0.127)
		(layer "B.Cu")
		(net "I2C_BMC_COMP_SCL_OUT")
	)
	(segment
		(start 90.654378 -157.82544)
		(end 91.664536 -157.82544)
		(width 0.127)
		(layer "B.Cu")
		(net "I2C_BMC_COMP_SCL_OUT")
	)
	(segment
		(start 92.547948 -159.455358)
		(end 92.767912 -159.675322)
		(width 0.127)
		(layer "B.Cu")
		(net "I2C_BMC_COMP_SCL_OUT")
	)
	(segment
		(start 96.902524 -178.255676)
		(end 96.5962 -178.562)
		(width 0.127)
		(layer "B.Cu")
		(net "I2C_BMC_COMP_SCL_OUT")
	)
	(segment
		(start 98.138488 -176.029112)
		(end 96.902524 -177.265076)
		(width 0.127)
		(layer "B.Cu")
		(net "I2C_BMC_COMP_SCL_OUT")
	)
	(segment
		(start 67.161918 -151.638)
		(end 71.956676 -151.638)
		(width 0.127)
		(layer "B.Cu")
		(net "I2C_BMC_COMP_SCL_OUT")
	)
	(segment
		(start 100.406454 -169.231056)
		(end 98.138488 -171.499022)
		(width 0.127)
		(layer "B.Cu")
		(net "I2C_BMC_COMP_SCL_OUT")
	)
	(segment
		(start 92.767912 -159.675322)
		(end 92.767912 -161.04743)
		(width 0.127)
		(layer "B.Cu")
		(net "I2C_BMC_COMP_SCL_OUT")
	)
	(segment
		(start 92.547948 -158.708852)
		(end 92.547948 -159.455358)
		(width 0.127)
		(layer "B.Cu")
		(net "I2C_BMC_COMP_SCL_OUT")
	)
	(segment
		(start 100.406454 -167.538654)
		(end 100.406454 -169.231056)
		(width 0.127)
		(layer "B.Cu")
		(net "I2C_BMC_COMP_SCL_OUT")
	)
	(segment
		(start 65.9511 -149.953218)
		(end 65.9511 -150.427182)
		(width 0.127)
		(layer "B.Cu")
		(net "I2C_BMC_COMP_SCL_OUT")
	)
	(segment
		(start 87.60714 -157.49397)
		(end 90.322908 -157.49397)
		(width 0.127)
		(layer "B.Cu")
		(net "I2C_BMC_COMP_SCL_OUT")
	)
	(segment
		(start 83.482434 -158.42996)
		(end 86.67115 -158.42996)
		(width 0.127)
		(layer "B.Cu")
		(net "I2C_BMC_COMP_SCL_OUT")
	)
	(segment
		(start 87.025226 -178.5874)
		(end 86.4362 -178.5874)
		(width 0.127)
		(layer "B.Cu")
		(net "I2C_BMC_COMP_SCL_OUT")
	)
	(segment
		(start 95.995744 -163.487862)
		(end 95.995744 -163.675314)
		(width 0.127)
		(layer "B.Cu")
		(net "I2C_BMC_COMP_SCL_OUT")
	)
	(segment
		(start 94.230698 -162.510216)
		(end 95.018098 -162.510216)
		(width 0.127)
		(layer "B.Cu")
		(net "I2C_BMC_COMP_SCL_OUT")
	)
	(segment
		(start 66.4337 -149.1869)
		(end 66.4337 -149.470618)
		(width 0.127)
		(layer "B.Cu")
		(net "I2C_BMC_COMP_SCL_OUT")
	)
	(segment
		(start 89.362534 -175.768)
		(end 90.03538 -175.768)
		(width 0.127)
		(layer "B.Cu")
		(net "I2C_BMC_COMP_SCL_OUT")
	)
	(segment
		(start 82.090514 -157.03804)
		(end 83.482434 -158.42996)
		(width 0.127)
		(layer "B.Cu")
		(net "I2C_BMC_COMP_SCL_OUT")
	)
	(segment
		(start 95.018098 -162.510216)
		(end 95.995744 -163.487862)
		(width 0.127)
		(layer "B.Cu")
		(net "I2C_BMC_COMP_SCL_OUT")
	)
	(segment
		(start 86.67115 -158.42996)
		(end 87.60714 -157.49397)
		(width 0.127)
		(layer "B.Cu")
		(net "I2C_BMC_COMP_SCL_OUT")
	)
	(segment
		(start 88.699848 -176.912778)
		(end 88.699848 -176.430686)
		(width 0.127)
		(layer "B.Cu")
		(net "I2C_BMC_COMP_SCL_OUT")
	)
	(segment
		(start 90.322908 -157.49397)
		(end 90.654378 -157.82544)
		(width 0.127)
		(layer "B.Cu")
		(net "I2C_BMC_COMP_SCL_OUT")
	)
	(segment
		(start 65.9511 -150.427182)
		(end 67.161918 -151.638)
		(width 0.127)
		(layer "B.Cu")
		(net "I2C_BMC_COMP_SCL_OUT")
	)
	(segment
		(start 97.955354 -165.087554)
		(end 100.406454 -167.538654)
		(width 0.127)
		(layer "B.Cu")
		(net "I2C_BMC_COMP_SCL_OUT")
	)
	(segment
		(start 66.4337 -149.470618)
		(end 65.9511 -149.953218)
		(width 0.127)
		(layer "B.Cu")
		(net "I2C_BMC_COMP_SCL_OUT")
	)
	(segment
		(start 88.699848 -176.430686)
		(end 89.362534 -175.768)
		(width 0.127)
		(layer "B.Cu")
		(net "I2C_BMC_COMP_SCL_OUT")
	)
	(segment
		(start 91.664536 -157.82544)
		(end 92.547948 -158.708852)
		(width 0.127)
		(layer "B.Cu")
		(net "I2C_BMC_COMP_SCL_OUT")
	)
	(segment
		(start 89.3318 -178.562)
		(end 96.5962 -178.562)
		(width 0.127)
		(layer "In5.Cu")
		(net "I2C_BMC_COMP_SCL_OUT")
	)
	(segment
		(start 86.4362 -178.5874)
		(end 86.7537 -178.9049)
		(width 0.127)
		(layer "In5.Cu")
		(net "I2C_BMC_COMP_SCL_OUT")
	)
	(segment
		(start 87.3633 -178.9049)
		(end 87.6046 -179.1462)
		(width 0.127)
		(layer "In5.Cu")
		(net "I2C_BMC_COMP_SCL_OUT")
	)
	(segment
		(start 88.7476 -179.1462)
		(end 89.3318 -178.562)
		(width 0.127)
		(layer "In5.Cu")
		(net "I2C_BMC_COMP_SCL_OUT")
	)
	(segment
		(start 87.6046 -179.1462)
		(end 88.7476 -179.1462)
		(width 0.127)
		(layer "In5.Cu")
		(net "I2C_BMC_COMP_SCL_OUT")
	)
	(segment
		(start 86.7537 -178.9049)
		(end 87.3633 -178.9049)
		(width 0.127)
		(layer "In5.Cu")
		(net "I2C_BMC_COMP_SCL_OUT")
	)
	(segment
		(start 99.986084 -88.190578)
		(end 99.981512 -88.19515)
		(width 0.127)
		(layer "F.Cu")
		(net "I2C_BMC_COMP_SCL")
	)
	(segment
		(start 99.967034 -123.359164)
		(end 99.595686 -123.730512)
		(width 0.127)
		(layer "F.Cu")
		(net "I2C_BMC_COMP_SCL")
	)
	(segment
		(start 101.68636 -42.811954)
		(end 101.68636 -44.733972)
		(width 0.127)
		(layer "F.Cu")
		(net "I2C_BMC_COMP_SCL")
	)
	(segment
		(start 106.26979 -21.847302)
		(end 100.965762 -27.15133)
		(width 0.127)
		(layer "F.Cu")
		(net "I2C_BMC_COMP_SCL")
	)
	(segment
		(start 116.648484 -32.260032)
		(end 116.671344 -32.237172)
		(width 0.127)
		(layer "F.Cu")
		(net "I2C_BMC_COMP_SCL")
	)
	(segment
		(start 117.899942 -40.39997)
		(end 117.899942 -40.150542)
		(width 0.127)
		(layer "F.Cu")
		(net "I2C_BMC_COMP_SCL")
	)
	(segment
		(start 108.36021 -20.979892)
		(end 107.4928 -21.847302)
		(width 0.127)
		(layer "F.Cu")
		(net "I2C_BMC_COMP_SCL")
	)
	(segment
		(start 116.648484 -36.740338)
		(end 116.648484 -35.859974)
		(width 0.127)
		(layer "F.Cu")
		(net "I2C_BMC_COMP_SCL")
	)
	(segment
		(start 99.986084 -46.434248)
		(end 99.986084 -88.190578)
		(width 0.127)
		(layer "F.Cu")
		(net "I2C_BMC_COMP_SCL")
	)
	(segment
		(start 116.671344 -35.837114)
		(end 116.671344 -33.163002)
		(width 0.127)
		(layer "F.Cu")
		(net "I2C_BMC_COMP_SCL")
	)
	(segment
		(start 99.595686 -123.730512)
		(end 99.595686 -125.575822)
		(width 0.127)
		(layer "F.Cu")
		(net "I2C_BMC_COMP_SCL")
	)
	(segment
		(start 116.671344 -33.163002)
		(end 116.648484 -33.140142)
		(width 0.127)
		(layer "F.Cu")
		(net "I2C_BMC_COMP_SCL")
	)
	(segment
		(start 100.674932 -127.160274)
		(end 101.112828 -127.59817)
		(width 0.127)
		(layer "F.Cu")
		(net "I2C_BMC_COMP_SCL")
	)
	(segment
		(start 116.272564 -22.437344)
		(end 115.93322 -22.098)
		(width 0.127)
		(layer "F.Cu")
		(net "I2C_BMC_COMP_SCL")
	)
	(segment
		(start 101.112828 -134.40029)
		(end 101.501956 -134.789418)
		(width 0.127)
		(layer "F.Cu")
		(net "I2C_BMC_COMP_SCL")
	)
	(segment
		(start 100.674932 -126.655068)
		(end 100.674932 -127.160274)
		(width 0.127)
		(layer "F.Cu")
		(net "I2C_BMC_COMP_SCL")
	)
	(segment
		(start 101.954076 -134.789418)
		(end 102.874064 -135.709406)
		(width 0.127)
		(layer "F.Cu")
		(net "I2C_BMC_COMP_SCL")
	)
	(segment
		(start 116.671344 -32.237172)
		(end 116.671344 -30.663134)
		(width 0.127)
		(layer "F.Cu")
		(net "I2C_BMC_COMP_SCL")
	)
	(segment
		(start 107.4928 -21.847302)
		(end 106.26979 -21.847302)
		(width 0.127)
		(layer "F.Cu")
		(net "I2C_BMC_COMP_SCL")
	)
	(segment
		(start 102.874064 -135.709406)
		(end 102.874064 -177.146458)
		(width 0.127)
		(layer "F.Cu")
		(net "I2C_BMC_COMP_SCL")
	)
	(segment
		(start 100.965762 -27.15133)
		(end 100.965762 -42.091356)
		(width 0.127)
		(layer "F.Cu")
		(net "I2C_BMC_COMP_SCL")
	)
	(segment
		(start 99.967034 -121.621042)
		(end 99.967034 -123.359164)
		(width 0.127)
		(layer "F.Cu")
		(net "I2C_BMC_COMP_SCL")
	)
	(segment
		(start 102.874064 -177.146458)
		(end 101.369622 -178.6509)
		(width 0.127)
		(layer "F.Cu")
		(net "I2C_BMC_COMP_SCL")
	)
	(segment
		(start 116.671344 -30.663134)
		(end 116.272564 -30.264354)
		(width 0.127)
		(layer "F.Cu")
		(net "I2C_BMC_COMP_SCL")
	)
	(segment
		(start 116.648484 -35.859974)
		(end 116.671344 -35.837114)
		(width 0.127)
		(layer "F.Cu")
		(net "I2C_BMC_COMP_SCL")
	)
	(segment
		(start 101.68636 -44.733972)
		(end 99.986084 -46.434248)
		(width 0.127)
		(layer "F.Cu")
		(net "I2C_BMC_COMP_SCL")
	)
	(segment
		(start 114.815112 -20.979892)
		(end 108.36021 -20.979892)
		(width 0.127)
		(layer "F.Cu")
		(net "I2C_BMC_COMP_SCL")
	)
	(segment
		(start 116.272564 -30.264354)
		(end 116.272564 -22.437344)
		(width 0.127)
		(layer "F.Cu")
		(net "I2C_BMC_COMP_SCL")
	)
	(segment
		(start 101.501956 -134.789418)
		(end 101.954076 -134.789418)
		(width 0.127)
		(layer "F.Cu")
		(net "I2C_BMC_COMP_SCL")
	)
	(segment
		(start 99.595686 -125.575822)
		(end 100.674932 -126.655068)
		(width 0.127)
		(layer "F.Cu")
		(net "I2C_BMC_COMP_SCL")
	)
	(segment
		(start 100.755958 -92.793058)
		(end 100.755958 -120.832118)
		(width 0.127)
		(layer "F.Cu")
		(net "I2C_BMC_COMP_SCL")
	)
	(segment
		(start 99.981512 -92.018612)
		(end 100.755958 -92.793058)
		(width 0.127)
		(layer "F.Cu")
		(net "I2C_BMC_COMP_SCL")
	)
	(segment
		(start 116.671344 -36.763198)
		(end 116.648484 -36.740338)
		(width 0.127)
		(layer "F.Cu")
		(net "I2C_BMC_COMP_SCL")
	)
	(segment
		(start 99.981512 -88.19515)
		(end 99.981512 -92.018612)
		(width 0.127)
		(layer "F.Cu")
		(net "I2C_BMC_COMP_SCL")
	)
	(segment
		(start 116.648484 -33.140142)
		(end 116.648484 -32.260032)
		(width 0.127)
		(layer "F.Cu")
		(net "I2C_BMC_COMP_SCL")
	)
	(segment
		(start 101.112828 -127.59817)
		(end 101.112828 -134.40029)
		(width 0.127)
		(layer "F.Cu")
		(net "I2C_BMC_COMP_SCL")
	)
	(segment
		(start 100.965762 -42.091356)
		(end 101.68636 -42.811954)
		(width 0.127)
		(layer "F.Cu")
		(net "I2C_BMC_COMP_SCL")
	)
	(segment
		(start 115.93322 -22.098)
		(end 114.815112 -20.979892)
		(width 0.127)
		(layer "F.Cu")
		(net "I2C_BMC_COMP_SCL")
	)
	(segment
		(start 116.671344 -38.921944)
		(end 116.671344 -36.763198)
		(width 0.127)
		(layer "F.Cu")
		(net "I2C_BMC_COMP_SCL")
	)
	(segment
		(start 117.899942 -40.150542)
		(end 116.671344 -38.921944)
		(width 0.127)
		(layer "F.Cu")
		(net "I2C_BMC_COMP_SCL")
	)
	(segment
		(start 100.755958 -120.832118)
		(end 99.967034 -121.621042)
		(width 0.127)
		(layer "F.Cu")
		(net "I2C_BMC_COMP_SCL")
	)
	(via
		(at 101.369622 -178.6509)
		(size 0.508)
		(drill 0.254)
		(layers "F.Cu" "B.Cu")
		(net "I2C_BMC_COMP_SCL")
	)
	(via
		(at 86.462362 -177.6476)
		(size 0.508)
		(drill 0.254)
		(layers "F.Cu" "B.Cu")
		(net "I2C_BMC_COMP_SCL")
	)
	(via
		(at 115.93322 -22.098)
		(size 0.6604)
		(drill 0.3302)
		(layers "F.Cu" "B.Cu")
		(net "I2C_BMC_COMP_SCL")
	)
	(segment
		(start 85.8901 -176.8094)
		(end 85.8901 -177.075338)
		(width 0.127)
		(layer "B.Cu")
		(net "I2C_BMC_COMP_SCL")
	)
	(segment
		(start 85.8901 -177.075338)
		(end 86.462362 -177.6476)
		(width 0.127)
		(layer "B.Cu")
		(net "I2C_BMC_COMP_SCL")
	)
	(segment
		(start 101.369622 -178.6509)
		(end 99.840796 -178.6509)
		(width 0.127)
		(layer "In5.Cu")
		(net "I2C_BMC_COMP_SCL")
	)
	(segment
		(start 96.403414 -177.9651)
		(end 86.779862 -177.9651)
		(width 0.127)
		(layer "In5.Cu")
		(net "I2C_BMC_COMP_SCL")
	)
	(segment
		(start 98.676968 -177.487072)
		(end 96.881442 -177.487072)
		(width 0.127)
		(layer "In5.Cu")
		(net "I2C_BMC_COMP_SCL")
	)
	(segment
		(start 99.840796 -178.6509)
		(end 98.676968 -177.487072)
		(width 0.127)
		(layer "In5.Cu")
		(net "I2C_BMC_COMP_SCL")
	)
	(segment
		(start 86.779862 -177.9651)
		(end 86.462362 -177.6476)
		(width 0.127)
		(layer "In5.Cu")
		(net "I2C_BMC_COMP_SCL")
	)
	(segment
		(start 96.881442 -177.487072)
		(end 96.403414 -177.9651)
		(width 0.127)
		(layer "In5.Cu")
		(net "I2C_BMC_COMP_SCL")
	)
	(via
		(at 95.808546 -177.767742)
		(size 0.6096)
		(drill 0.3048)
		(layers "F.Cu" "B.Cu")
		(net "I2C_BMC_COMP_ALERT_N_R")
	)
	(segment
		(start 95.808546 -177.767742)
		(end 96.318578 -177.25771)
		(width 0.127)
		(layer "B.Cu")
		(net "I2C_BMC_COMP_ALERT_N_R")
	)
	(segment
		(start 95.377 -178.199288)
		(end 95.808546 -177.767742)
		(width 0.127)
		(layer "B.Cu")
		(net "I2C_BMC_COMP_ALERT_N_R")
	)
	(segment
		(start 96.318578 -177.25771)
		(end 96.318578 -176.581562)
		(width 0.127)
		(layer "B.Cu")
		(net "I2C_BMC_COMP_ALERT_N_R")
	)
	(segment
		(start 97.12198 -179.35956)
		(end 95.85706 -179.35956)
		(width 0.127)
		(layer "B.Cu")
		(net "I2C_BMC_COMP_ALERT_N_R")
	)
	(segment
		(start 95.85706 -179.35956)
		(end 95.377 -178.8795)
		(width 0.127)
		(layer "B.Cu")
		(net "I2C_BMC_COMP_ALERT_N_R")
	)
	(segment
		(start 95.377 -178.8795)
		(end 95.377 -178.199288)
		(width 0.127)
		(layer "B.Cu")
		(net "I2C_BMC_COMP_ALERT_N_R")
	)
	(segment
		(start 86.291674 -175.391572)
		(end 86.021926 -175.66132)
		(width 0.127)
		(layer "F.Cu")
		(net "I2C_BMC_COMP_ALERT_N")
	)
	(segment
		(start 86.3092 -172.725588)
		(end 86.3092 -172.474636)
		(width 0.127)
		(layer "F.Cu")
		(net "I2C_BMC_COMP_ALERT_N")
	)
	(segment
		(start 86.291674 -172.743114)
		(end 86.3092 -172.725588)
		(width 0.127)
		(layer "F.Cu")
		(net "I2C_BMC_COMP_ALERT_N")
	)
	(segment
		(start 86.291674 -173.41342)
		(end 86.291674 -172.743114)
		(width 0.127)
		(layer "F.Cu")
		(net "I2C_BMC_COMP_ALERT_N")
	)
	(segment
		(start 86.3092 -172.474636)
		(end 86.310216 -172.47362)
		(width 0.127)
		(layer "F.Cu")
		(net "I2C_BMC_COMP_ALERT_N")
	)
	(segment
		(start 86.291674 -173.41342)
		(end 86.291674 -175.391572)
		(width 0.127)
		(layer "F.Cu")
		(net "I2C_BMC_COMP_ALERT_N")
	)
	(via
		(at 86.021926 -175.66132)
		(size 0.508)
		(drill 0.254)
		(layers "F.Cu" "B.Cu")
		(net "I2C_BMC_COMP_ALERT_N")
	)
	(via
		(at 86.310216 -172.47362)
		(size 0.508)
		(drill 0.254)
		(layers "F.Cu" "B.Cu")
		(net "I2C_BMC_COMP_ALERT_N")
	)
	(via
		(at 94.5769 -177.3936)
		(size 0.508)
		(drill 0.254)
		(layers "F.Cu" "B.Cu")
		(net "I2C_BMC_COMP_ALERT_N")
	)
	(via
		(at 86.291674 -173.41342)
		(size 0.6604)
		(drill 0.3302)
		(layers "F.Cu" "B.Cu")
		(net "I2C_BMC_COMP_ALERT_N")
	)
	(segment
		(start 95.429578 -176.581562)
		(end 95.388938 -176.581562)
		(width 0.127)
		(layer "B.Cu")
		(net "I2C_BMC_COMP_ALERT_N")
	)
	(segment
		(start 95.388938 -176.581562)
		(end 94.5769 -177.3936)
		(width 0.127)
		(layer "B.Cu")
		(net "I2C_BMC_COMP_ALERT_N")
	)
	(segment
		(start 94.3991 -150.748238)
		(end 93.248988 -149.598126)
		(width 0.127)
		(layer "In2.Cu")
		(net "I2C_BMC_COMP_ALERT_N")
	)
	(segment
		(start 119.741442 -27.969718)
		(end 120.77954 -29.007816)
		(width 0.127)
		(layer "In2.Cu")
		(net "I2C_BMC_COMP_ALERT_N")
	)
	(segment
		(start 93.153992 -125.343412)
		(end 93.153992 -122.760994)
		(width 0.127)
		(layer "In2.Cu")
		(net "I2C_BMC_COMP_ALERT_N")
	)
	(segment
		(start 119.741442 -27.407108)
		(end 119.741442 -27.969718)
		(width 0.127)
		(layer "In2.Cu")
		(net "I2C_BMC_COMP_ALERT_N")
	)
	(segment
		(start 94.5134 -116.7892)
		(end 94.5134 -115.8748)
		(width 0.127)
		(layer "In2.Cu")
		(net "I2C_BMC_COMP_ALERT_N")
	)
	(segment
		(start 116.80444 -24.470106)
		(end 119.741442 -27.407108)
		(width 0.127)
		(layer "In2.Cu")
		(net "I2C_BMC_COMP_ALERT_N")
	)
	(segment
		(start 93.8911 -128.312672)
		(end 93.8911 -126.08052)
		(width 0.127)
		(layer "In2.Cu")
		(net "I2C_BMC_COMP_ALERT_N")
	)
	(segment
		(start 94.5134 -115.8748)
		(end 95.208852 -115.179348)
		(width 0.127)
		(layer "In2.Cu")
		(net "I2C_BMC_COMP_ALERT_N")
	)
	(segment
		(start 95.208852 -95.830136)
		(end 95.908114 -95.130874)
		(width 0.127)
		(layer "In2.Cu")
		(net "I2C_BMC_COMP_ALERT_N")
	)
	(segment
		(start 96.945958 -53.19014)
		(end 96.945958 -42.757852)
		(width 0.127)
		(layer "In2.Cu")
		(net "I2C_BMC_COMP_ALERT_N")
	)
	(segment
		(start 95.208852 -115.179348)
		(end 95.208852 -95.830136)
		(width 0.127)
		(layer "In2.Cu")
		(net "I2C_BMC_COMP_ALERT_N")
	)
	(segment
		(start 95.908114 -95.130874)
		(end 95.908114 -54.227984)
		(width 0.127)
		(layer "In2.Cu")
		(net "I2C_BMC_COMP_ALERT_N")
	)
	(segment
		(start 93.1545 -144.799304)
		(end 93.16466 -144.789144)
		(width 0.127)
		(layer "In2.Cu")
		(net "I2C_BMC_COMP_ALERT_N")
	)
	(segment
		(start 93.2561 -132.268722)
		(end 93.2561 -128.947672)
		(width 0.127)
		(layer "In2.Cu")
		(net "I2C_BMC_COMP_ALERT_N")
	)
	(segment
		(start 86.310216 -172.47362)
		(end 88.8746 -169.909236)
		(width 0.127)
		(layer "In2.Cu")
		(net "I2C_BMC_COMP_ALERT_N")
	)
	(segment
		(start 94.2213 -137.452862)
		(end 94.2213 -133.233922)
		(width 0.127)
		(layer "In2.Cu")
		(net "I2C_BMC_COMP_ALERT_N")
	)
	(segment
		(start 93.248988 -148.750782)
		(end 93.1545 -148.656294)
		(width 0.127)
		(layer "In2.Cu")
		(net "I2C_BMC_COMP_ALERT_N")
	)
	(segment
		(start 120.77954 -29.007816)
		(end 120.77954 -39.520622)
		(width 0.127)
		(layer "In2.Cu")
		(net "I2C_BMC_COMP_ALERT_N")
	)
	(segment
		(start 93.463872 -122.451114)
		(end 93.463872 -120.607328)
		(width 0.127)
		(layer "In2.Cu")
		(net "I2C_BMC_COMP_ALERT_N")
	)
	(segment
		(start 93.516704 -143.284956)
		(end 93.516704 -142.02537)
		(width 0.127)
		(layer "In2.Cu")
		(net "I2C_BMC_COMP_ALERT_N")
	)
	(segment
		(start 94.518988 -137.75055)
		(end 94.2213 -137.452862)
		(width 0.127)
		(layer "In2.Cu")
		(net "I2C_BMC_COMP_ALERT_N")
	)
	(segment
		(start 104.027732 -24.470106)
		(end 116.80444 -24.470106)
		(width 0.127)
		(layer "In2.Cu")
		(net "I2C_BMC_COMP_ALERT_N")
	)
	(segment
		(start 97.339658 -42.364152)
		(end 97.339658 -31.15818)
		(width 0.127)
		(layer "In2.Cu")
		(net "I2C_BMC_COMP_ALERT_N")
	)
	(segment
		(start 95.908114 -54.227984)
		(end 96.945958 -53.19014)
		(width 0.127)
		(layer "In2.Cu")
		(net "I2C_BMC_COMP_ALERT_N")
	)
	(segment
		(start 93.2561 -128.947672)
		(end 93.8911 -128.312672)
		(width 0.127)
		(layer "In2.Cu")
		(net "I2C_BMC_COMP_ALERT_N")
	)
	(segment
		(start 93.275404 -160.135316)
		(end 93.275404 -158.910528)
		(width 0.127)
		(layer "In2.Cu")
		(net "I2C_BMC_COMP_ALERT_N")
	)
	(segment
		(start 88.8746 -167.099488)
		(end 89.1286 -166.845488)
		(width 0.127)
		(layer "In2.Cu")
		(net "I2C_BMC_COMP_ALERT_N")
	)
	(segment
		(start 93.516704 -142.02537)
		(end 94.518988 -141.023086)
		(width 0.127)
		(layer "In2.Cu")
		(net "I2C_BMC_COMP_ALERT_N")
	)
	(segment
		(start 94.518988 -141.023086)
		(end 94.518988 -137.75055)
		(width 0.127)
		(layer "In2.Cu")
		(net "I2C_BMC_COMP_ALERT_N")
	)
	(segment
		(start 93.16466 -143.637)
		(end 93.516704 -143.284956)
		(width 0.127)
		(layer "In2.Cu")
		(net "I2C_BMC_COMP_ALERT_N")
	)
	(segment
		(start 93.463872 -120.607328)
		(end 93.6752 -120.396)
		(width 0.127)
		(layer "In2.Cu")
		(net "I2C_BMC_COMP_ALERT_N")
	)
	(segment
		(start 93.248988 -149.598126)
		(end 93.248988 -148.750782)
		(width 0.127)
		(layer "In2.Cu")
		(net "I2C_BMC_COMP_ALERT_N")
	)
	(segment
		(start 94.8309 -157.355032)
		(end 94.8309 -153.820368)
		(width 0.127)
		(layer "In2.Cu")
		(net "I2C_BMC_COMP_ALERT_N")
	)
	(segment
		(start 97.339658 -31.15818)
		(end 104.027732 -24.470106)
		(width 0.127)
		(layer "In2.Cu")
		(net "I2C_BMC_COMP_ALERT_N")
	)
	(segment
		(start 93.6752 -117.6274)
		(end 94.5134 -116.7892)
		(width 0.127)
		(layer "In2.Cu")
		(net "I2C_BMC_COMP_ALERT_N")
	)
	(segment
		(start 91.35872 -162.052)
		(end 93.275404 -160.135316)
		(width 0.127)
		(layer "In2.Cu")
		(net "I2C_BMC_COMP_ALERT_N")
	)
	(segment
		(start 94.3991 -153.388568)
		(end 94.3991 -150.748238)
		(width 0.127)
		(layer "In2.Cu")
		(net "I2C_BMC_COMP_ALERT_N")
	)
	(segment
		(start 89.70645 -163.405058)
		(end 91.059508 -162.052)
		(width 0.127)
		(layer "In2.Cu")
		(net "I2C_BMC_COMP_ALERT_N")
	)
	(segment
		(start 93.1545 -148.656294)
		(end 93.1545 -144.799304)
		(width 0.127)
		(layer "In2.Cu")
		(net "I2C_BMC_COMP_ALERT_N")
	)
	(segment
		(start 94.2213 -133.233922)
		(end 93.2561 -132.268722)
		(width 0.127)
		(layer "In2.Cu")
		(net "I2C_BMC_COMP_ALERT_N")
	)
	(segment
		(start 91.059508 -162.052)
		(end 91.35872 -162.052)
		(width 0.127)
		(layer "In2.Cu")
		(net "I2C_BMC_COMP_ALERT_N")
	)
	(segment
		(start 89.1286 -166.845488)
		(end 89.1286 -165.1)
		(width 0.127)
		(layer "In2.Cu")
		(net "I2C_BMC_COMP_ALERT_N")
	)
	(segment
		(start 88.8746 -169.909236)
		(end 88.8746 -167.099488)
		(width 0.127)
		(layer "In2.Cu")
		(net "I2C_BMC_COMP_ALERT_N")
	)
	(segment
		(start 93.16466 -144.789144)
		(end 93.16466 -143.637)
		(width 0.127)
		(layer "In2.Cu")
		(net "I2C_BMC_COMP_ALERT_N")
	)
	(segment
		(start 93.6752 -120.396)
		(end 93.6752 -117.6274)
		(width 0.127)
		(layer "In2.Cu")
		(net "I2C_BMC_COMP_ALERT_N")
	)
	(segment
		(start 94.8309 -153.820368)
		(end 94.3991 -153.388568)
		(width 0.127)
		(layer "In2.Cu")
		(net "I2C_BMC_COMP_ALERT_N")
	)
	(segment
		(start 89.1286 -165.1)
		(end 89.70645 -164.52215)
		(width 0.127)
		(layer "In2.Cu")
		(net "I2C_BMC_COMP_ALERT_N")
	)
	(segment
		(start 89.70645 -164.52215)
		(end 89.70645 -163.405058)
		(width 0.127)
		(layer "In2.Cu")
		(net "I2C_BMC_COMP_ALERT_N")
	)
	(segment
		(start 96.945958 -42.757852)
		(end 97.339658 -42.364152)
		(width 0.127)
		(layer "In2.Cu")
		(net "I2C_BMC_COMP_ALERT_N")
	)
	(segment
		(start 93.275404 -158.910528)
		(end 94.8309 -157.355032)
		(width 0.127)
		(layer "In2.Cu")
		(net "I2C_BMC_COMP_ALERT_N")
	)
	(segment
		(start 120.77954 -39.520622)
		(end 119.70004 -40.600122)
		(width 0.127)
		(layer "In2.Cu")
		(net "I2C_BMC_COMP_ALERT_N")
	)
	(segment
		(start 93.8911 -126.08052)
		(end 93.153992 -125.343412)
		(width 0.127)
		(layer "In2.Cu")
		(net "I2C_BMC_COMP_ALERT_N")
	)
	(segment
		(start 93.153992 -122.760994)
		(end 93.463872 -122.451114)
		(width 0.127)
		(layer "In2.Cu")
		(net "I2C_BMC_COMP_ALERT_N")
	)
	(segment
		(start 90.8685 -177.4571)
		(end 93.565218 -177.4571)
		(width 0.127)
		(layer "In5.Cu")
		(net "I2C_BMC_COMP_ALERT_N")
	)
	(segment
		(start 90.389456 -176.978056)
		(end 90.8685 -177.4571)
		(width 0.127)
		(layer "In5.Cu")
		(net "I2C_BMC_COMP_ALERT_N")
	)
	(segment
		(start 93.628718 -177.3936)
		(end 94.5769 -177.3936)
		(width 0.127)
		(layer "In5.Cu")
		(net "I2C_BMC_COMP_ALERT_N")
	)
	(segment
		(start 87.338662 -176.978056)
		(end 90.389456 -176.978056)
		(width 0.127)
		(layer "In5.Cu")
		(net "I2C_BMC_COMP_ALERT_N")
	)
	(segment
		(start 86.021926 -175.66132)
		(end 87.338662 -176.978056)
		(width 0.127)
		(layer "In5.Cu")
		(net "I2C_BMC_COMP_ALERT_N")
	)
	(segment
		(start 93.565218 -177.4571)
		(end 93.628718 -177.3936)
		(width 0.127)
		(layer "In5.Cu")
		(net "I2C_BMC_COMP_ALERT_N")
	)
	(segment
		(start 195.975986 -135.128)
		(end 197.1802 -135.128)
		(width 0.127)
		(layer "F.Cu")
		(net "Q9_G")
	)
	(segment
		(start 197.3834 -134.9248)
		(end 197.379336 -134.920736)
		(width 0.127)
		(layer "F.Cu")
		(net "Q9_G")
	)
	(segment
		(start 197.379336 -134.920736)
		(end 197.379336 -133.731)
		(width 0.127)
		(layer "F.Cu")
		(net "Q9_G")
	)
	(segment
		(start 197.1802 -135.128)
		(end 197.3834 -134.9248)
		(width 0.127)
		(layer "F.Cu")
		(net "Q9_G")
	)
	(via
		(at 197.3834 -134.9248)
		(size 0.6604)
		(drill 0.3302)
		(layers "F.Cu" "B.Cu")
		(net "Q9_G")
	)
	(segment
		(start 194.991736 -136.497314)
		(end 194.991736 -133.223)
		(width 0.127)
		(layer "F.Cu")
		(net "Q8_G")
	)
	(segment
		(start 200.776586 -135.255)
		(end 200.776586 -136.84758)
		(width 0.127)
		(layer "F.Cu")
		(net "Q8_G")
	)
	(segment
		(start 194.991736 -131.699)
		(end 194.991736 -133.223)
		(width 0.127)
		(layer "F.Cu")
		(net "Q8_G")
	)
	(segment
		(start 195.861686 -137.367264)
		(end 194.991736 -136.497314)
		(width 0.127)
		(layer "F.Cu")
		(net "Q8_G")
	)
	(segment
		(start 200.776586 -136.84758)
		(end 200.256902 -137.367264)
		(width 0.127)
		(layer "F.Cu")
		(net "Q8_G")
	)
	(segment
		(start 200.256902 -137.367264)
		(end 195.861686 -137.367264)
		(width 0.127)
		(layer "F.Cu")
		(net "Q8_G")
	)
	(via
		(at 200.776586 -136.84758)
		(size 0.6604)
		(drill 0.3302)
		(layers "F.Cu" "B.Cu")
		(net "Q8_G")
	)
	(segment
		(start 171.6913 -127.9906)
		(end 171.6913 -126.9111)
		(width 0.127)
		(layer "F.Cu")
		(net "Q7_G")
	)
	(segment
		(start 170.8785 -126.0983)
		(end 171.5262 -126.746)
		(width 0.127)
		(layer "F.Cu")
		(net "Q7_G")
	)
	(segment
		(start 171.6913 -126.9111)
		(end 171.5262 -126.746)
		(width 0.127)
		(layer "F.Cu")
		(net "Q7_G")
	)
	(segment
		(start 170.8785 -125.31725)
		(end 170.8785 -126.0983)
		(width 0.127)
		(layer "F.Cu")
		(net "Q7_G")
	)
	(via
		(at 171.5262 -126.746)
		(size 0.6604)
		(drill 0.3302)
		(layers "F.Cu" "B.Cu")
		(net "Q7_G")
	)
	(segment
		(start 172.7835 -126.583694)
		(end 173.136306 -126.9365)
		(width 0.127)
		(layer "F.Cu")
		(net "Q6_G")
	)
	(segment
		(start 174.9044 -126.1618)
		(end 174.9044 -125.372114)
		(width 0.127)
		(layer "F.Cu")
		(net "Q6_G")
	)
	(segment
		(start 175.006 -126.9365)
		(end 175.006 -126.2634)
		(width 0.127)
		(layer "F.Cu")
		(net "Q6_G")
	)
	(segment
		(start 173.136306 -126.9365)
		(end 175.006 -126.9365)
		(width 0.127)
		(layer "F.Cu")
		(net "Q6_G")
	)
	(segment
		(start 172.7835 -124.333)
		(end 172.7835 -126.583694)
		(width 0.127)
		(layer "F.Cu")
		(net "Q6_G")
	)
	(segment
		(start 175.006 -126.2634)
		(end 174.9044 -126.1618)
		(width 0.127)
		(layer "F.Cu")
		(net "Q6_G")
	)
	(via
		(at 173.136306 -126.9365)
		(size 0.6604)
		(drill 0.3302)
		(layers "F.Cu" "B.Cu")
		(net "Q6_G")
	)
	(segment
		(start 65.600326 -168.201086)
		(end 65.600326 -168.965626)
		(width 0.127)
		(layer "F.Cu")
		(net "Q4_G")
	)
	(segment
		(start 65.8241 -169.1894)
		(end 65.8241 -170.0403)
		(width 0.127)
		(layer "F.Cu")
		(net "Q4_G")
	)
	(segment
		(start 65.164462 -168.201086)
		(end 65.600326 -168.201086)
		(width 0.127)
		(layer "F.Cu")
		(net "Q4_G")
	)
	(segment
		(start 65.8241 -170.0403)
		(end 65.7352 -170.1292)
		(width 0.127)
		(layer "F.Cu")
		(net "Q4_G")
	)
	(segment
		(start 64.0715 -168.30675)
		(end 65.058798 -168.30675)
		(width 0.127)
		(layer "F.Cu")
		(net "Q4_G")
	)
	(segment
		(start 65.058798 -168.30675)
		(end 65.164462 -168.201086)
		(width 0.127)
		(layer "F.Cu")
		(net "Q4_G")
	)
	(segment
		(start 65.600326 -168.965626)
		(end 65.8241 -169.1894)
		(width 0.127)
		(layer "F.Cu")
		(net "Q4_G")
	)
	(segment
		(start 70.3072 -177.27295)
		(end 70.3072 -177.2666)
		(width 0.127)
		(layer "F.Cu")
		(net "RST_BMC_EXTRST_N_1")
	)
	(segment
		(start 70.3072 -177.2666)
		(end 70.19544 -177.15484)
		(width 0.127)
		(layer "F.Cu")
		(net "RST_BMC_EXTRST_N_1")
	)
	(segment
		(start 70.19544 -177.15484)
		(end 70.19544 -175.9839)
		(width 0.127)
		(layer "F.Cu")
		(net "RST_BMC_EXTRST_N_1")
	)
	(via
		(at 70.3072 -177.27295)
		(size 0.508)
		(drill 0.254)
		(layers "F.Cu" "B.Cu")
		(net "RST_BMC_EXTRST_N_1")
	)
	(via
		(at 51.57851 -125.47092)
		(size 0.6096)
		(drill 0.3048)
		(layers "F.Cu" "B.Cu")
		(net "RST_BMC_EXTRST_N_1")
	)
	(via
		(at 70.511162 -121.906792)
		(size 0.508)
		(drill 0.254)
		(layers "F.Cu" "B.Cu")
		(net "RST_BMC_EXTRST_N_1")
	)
	(via
		(at 38.227 -125.222)
		(size 0.508)
		(drill 0.254)
		(layers "F.Cu" "B.Cu")
		(net "RST_BMC_EXTRST_N_1")
	)
	(via
		(at 54.193186 -122.044206)
		(size 0.508)
		(drill 0.254)
		(layers "F.Cu" "B.Cu")
		(net "RST_BMC_EXTRST_N_1")
	)
	(segment
		(start 52.763928 -123.2027)
		(end 53.922422 -122.044206)
		(width 0.127)
		(layer "B.Cu")
		(net "RST_BMC_EXTRST_N_1")
	)
	(segment
		(start 53.467508 -128.37668)
		(end 52.439316 -128.37668)
		(width 0.127)
		(layer "B.Cu")
		(net "RST_BMC_EXTRST_N_1")
	)
	(segment
		(start 53.922422 -122.044206)
		(end 54.193186 -122.044206)
		(width 0.127)
		(layer "B.Cu")
		(net "RST_BMC_EXTRST_N_1")
	)
	(segment
		(start 54.36616 -128.07442)
		(end 53.769768 -128.07442)
		(width 0.127)
		(layer "B.Cu")
		(net "RST_BMC_EXTRST_N_1")
	)
	(segment
		(start 51.57851 -125.47092)
		(end 51.57851 -123.68149)
		(width 0.127)
		(layer "B.Cu")
		(net "RST_BMC_EXTRST_N_1")
	)
	(segment
		(start 51.737768 -125.630178)
		(end 51.57851 -125.47092)
		(width 0.127)
		(layer "B.Cu")
		(net "RST_BMC_EXTRST_N_1")
	)
	(segment
		(start 52.0573 -123.2027)
		(end 52.763928 -123.2027)
		(width 0.127)
		(layer "B.Cu")
		(net "RST_BMC_EXTRST_N_1")
	)
	(segment
		(start 53.769768 -128.07442)
		(end 53.467508 -128.37668)
		(width 0.127)
		(layer "B.Cu")
		(net "RST_BMC_EXTRST_N_1")
	)
	(segment
		(start 38.227 -126.06782)
		(end 38.227 -125.222)
		(width 0.127)
		(layer "B.Cu")
		(net "RST_BMC_EXTRST_N_1")
	)
	(segment
		(start 52.439316 -128.37668)
		(end 51.737768 -127.675132)
		(width 0.127)
		(layer "B.Cu")
		(net "RST_BMC_EXTRST_N_1")
	)
	(segment
		(start 51.57851 -123.68149)
		(end 52.0573 -123.2027)
		(width 0.127)
		(layer "B.Cu")
		(net "RST_BMC_EXTRST_N_1")
	)
	(segment
		(start 51.737768 -127.675132)
		(end 51.737768 -125.630178)
		(width 0.127)
		(layer "B.Cu")
		(net "RST_BMC_EXTRST_N_1")
	)
	(segment
		(start 72.3646 -171.9072)
		(end 70.3072 -173.9646)
		(width 0.127)
		(layer "In2.Cu")
		(net "RST_BMC_EXTRST_N_1")
	)
	(segment
		(start 74.07402 -154.941016)
		(end 74.07402 -158.027116)
		(width 0.127)
		(layer "In2.Cu")
		(net "RST_BMC_EXTRST_N_1")
	)
	(segment
		(start 70.70852 -142.369032)
		(end 71.80961 -143.470122)
		(width 0.127)
		(layer "In2.Cu")
		(net "RST_BMC_EXTRST_N_1")
	)
	(segment
		(start 72.0598 -161.234374)
		(end 72.3646 -161.539174)
		(width 0.127)
		(layer "In2.Cu")
		(net "RST_BMC_EXTRST_N_1")
	)
	(segment
		(start 72.0598 -160.041336)
		(end 72.0598 -161.234374)
		(width 0.127)
		(layer "In2.Cu")
		(net "RST_BMC_EXTRST_N_1")
	)
	(segment
		(start 70.511162 -125.493272)
		(end 69.715126 -126.289308)
		(width 0.127)
		(layer "In2.Cu")
		(net "RST_BMC_EXTRST_N_1")
	)
	(segment
		(start 69.715126 -126.289308)
		(end 69.715126 -135.815578)
		(width 0.127)
		(layer "In2.Cu")
		(net "RST_BMC_EXTRST_N_1")
	)
	(segment
		(start 73.198736 -154.065732)
		(end 74.07402 -154.941016)
		(width 0.127)
		(layer "In2.Cu")
		(net "RST_BMC_EXTRST_N_1")
	)
	(segment
		(start 72.136 -145.568416)
		(end 72.136 -153.002742)
		(width 0.127)
		(layer "In2.Cu")
		(net "RST_BMC_EXTRST_N_1")
	)
	(segment
		(start 73.198736 -154.065478)
		(end 73.198736 -154.065732)
		(width 0.127)
		(layer "In2.Cu")
		(net "RST_BMC_EXTRST_N_1")
	)
	(segment
		(start 69.9516 -136.052052)
		(end 69.9516 -137.415778)
		(width 0.127)
		(layer "In2.Cu")
		(net "RST_BMC_EXTRST_N_1")
	)
	(segment
		(start 71.80961 -145.242026)
		(end 72.136 -145.568416)
		(width 0.127)
		(layer "In2.Cu")
		(net "RST_BMC_EXTRST_N_1")
	)
	(segment
		(start 71.80961 -143.470122)
		(end 71.80961 -145.242026)
		(width 0.127)
		(layer "In2.Cu")
		(net "RST_BMC_EXTRST_N_1")
	)
	(segment
		(start 70.511162 -121.906792)
		(end 70.511162 -125.493272)
		(width 0.127)
		(layer "In2.Cu")
		(net "RST_BMC_EXTRST_N_1")
	)
	(segment
		(start 69.9516 -137.415778)
		(end 70.70852 -138.172698)
		(width 0.127)
		(layer "In2.Cu")
		(net "RST_BMC_EXTRST_N_1")
	)
	(segment
		(start 69.715126 -135.815578)
		(end 69.9516 -136.052052)
		(width 0.127)
		(layer "In2.Cu")
		(net "RST_BMC_EXTRST_N_1")
	)
	(segment
		(start 70.3072 -173.9646)
		(end 70.3072 -177.27295)
		(width 0.127)
		(layer "In2.Cu")
		(net "RST_BMC_EXTRST_N_1")
	)
	(segment
		(start 70.70852 -138.172698)
		(end 70.70852 -142.369032)
		(width 0.127)
		(layer "In2.Cu")
		(net "RST_BMC_EXTRST_N_1")
	)
	(segment
		(start 74.07402 -158.027116)
		(end 72.0598 -160.041336)
		(width 0.127)
		(layer "In2.Cu")
		(net "RST_BMC_EXTRST_N_1")
	)
	(segment
		(start 72.3646 -161.539174)
		(end 72.3646 -171.9072)
		(width 0.127)
		(layer "In2.Cu")
		(net "RST_BMC_EXTRST_N_1")
	)
	(segment
		(start 72.136 -153.002742)
		(end 73.198736 -154.065478)
		(width 0.127)
		(layer "In2.Cu")
		(net "RST_BMC_EXTRST_N_1")
	)
	(segment
		(start 68.72097 -121.929652)
		(end 68.457318 -121.666)
		(width 0.127)
		(layer "In5.Cu")
		(net "RST_BMC_EXTRST_N_1")
	)
	(segment
		(start 70.511162 -121.906792)
		(end 70.488302 -121.929652)
		(width 0.127)
		(layer "In5.Cu")
		(net "RST_BMC_EXTRST_N_1")
	)
	(segment
		(start 38.354 -125.222)
		(end 38.227 -125.222)
		(width 0.127)
		(layer "In5.Cu")
		(net "RST_BMC_EXTRST_N_1")
	)
	(segment
		(start 52.81422 -122.044206)
		(end 50.309526 -124.5489)
		(width 0.127)
		(layer "In5.Cu")
		(net "RST_BMC_EXTRST_N_1")
	)
	(segment
		(start 55.374286 -121.4247)
		(end 54.74208 -122.056906)
		(width 0.127)
		(layer "In5.Cu")
		(net "RST_BMC_EXTRST_N_1")
	)
	(segment
		(start 68.457064 -121.666)
		(end 68.224908 -121.43359)
		(width 0.127)
		(layer "In5.Cu")
		(net "RST_BMC_EXTRST_N_1")
	)
	(segment
		(start 54.193186 -122.044206)
		(end 52.81422 -122.044206)
		(width 0.127)
		(layer "In5.Cu")
		(net "RST_BMC_EXTRST_N_1")
	)
	(segment
		(start 41.8211 -124.5489)
		(end 40.64 -125.73)
		(width 0.127)
		(layer "In5.Cu")
		(net "RST_BMC_EXTRST_N_1")
	)
	(segment
		(start 40.64 -125.73)
		(end 38.862 -125.73)
		(width 0.127)
		(layer "In5.Cu")
		(net "RST_BMC_EXTRST_N_1")
	)
	(segment
		(start 68.216018 -121.4247)
		(end 55.374286 -121.4247)
		(width 0.127)
		(layer "In5.Cu")
		(net "RST_BMC_EXTRST_N_1")
	)
	(segment
		(start 54.74208 -122.056906)
		(end 54.205886 -122.056906)
		(width 0.127)
		(layer "In5.Cu")
		(net "RST_BMC_EXTRST_N_1")
	)
	(segment
		(start 70.488302 -121.929652)
		(end 68.72097 -121.929652)
		(width 0.127)
		(layer "In5.Cu")
		(net "RST_BMC_EXTRST_N_1")
	)
	(segment
		(start 50.309526 -124.5489)
		(end 41.8211 -124.5489)
		(width 0.127)
		(layer "In5.Cu")
		(net "RST_BMC_EXTRST_N_1")
	)
	(segment
		(start 68.224908 -121.43359)
		(end 68.216018 -121.4247)
		(width 0.127)
		(layer "In5.Cu")
		(net "RST_BMC_EXTRST_N_1")
	)
	(segment
		(start 68.457318 -121.666)
		(end 68.457064 -121.666)
		(width 0.127)
		(layer "In5.Cu")
		(net "RST_BMC_EXTRST_N_1")
	)
	(segment
		(start 38.862 -125.73)
		(end 38.354 -125.222)
		(width 0.127)
		(layer "In5.Cu")
		(net "RST_BMC_EXTRST_N_1")
	)
	(segment
		(start 54.205886 -122.056906)
		(end 54.193186 -122.044206)
		(width 0.127)
		(layer "In5.Cu")
		(net "RST_BMC_EXTRST_N_1")
	)
	(segment
		(start 81.799938 -48.438054)
		(end 81.799938 -47.962058)
		(width 0.127)
		(layer "F.Cu")
		(net "MEZZA_PRSNT1_N")
	)
	(segment
		(start 86.322154 -45.584618)
		(end 87.448136 -45.584618)
		(width 0.127)
		(layer "F.Cu")
		(net "MEZZA_PRSNT1_N")
	)
	(segment
		(start 81.287874 -48.950118)
		(end 81.799938 -48.438054)
		(width 0.127)
		(layer "F.Cu")
		(net "MEZZA_PRSNT1_N")
	)
	(segment
		(start 87.448136 -45.584618)
		(end 87.474552 -45.611034)
		(width 0.127)
		(layer "F.Cu")
		(net "MEZZA_PRSNT1_N")
	)
	(segment
		(start 79.925164 -48.950118)
		(end 81.287874 -48.950118)
		(width 0.127)
		(layer "F.Cu")
		(net "MEZZA_PRSNT1_N")
	)
	(segment
		(start 87.476838 -45.61332)
		(end 87.474552 -45.611034)
		(width 0.127)
		(layer "F.Cu")
		(net "MEZZA_PRSNT1_N")
	)
	(segment
		(start 88.647016 -45.61332)
		(end 87.476838 -45.61332)
		(width 0.127)
		(layer "F.Cu")
		(net "MEZZA_PRSNT1_N")
	)
	(segment
		(start 81.799938 -47.962058)
		(end 84.177378 -45.584618)
		(width 0.127)
		(layer "F.Cu")
		(net "MEZZA_PRSNT1_N")
	)
	(segment
		(start 84.177378 -45.584618)
		(end 86.322154 -45.584618)
		(width 0.127)
		(layer "F.Cu")
		(net "MEZZA_PRSNT1_N")
	)
	(via
		(at 87.474552 -45.611034)
		(size 0.6604)
		(drill 0.3302)
		(layers "F.Cu" "B.Cu")
		(net "MEZZA_PRSNT1_N")
	)
	(segment
		(start 76.517754 -96.149922)
		(end 77.13472 -96.766888)
		(width 0.127)
		(layer "F.Cu")
		(net "MEZZ_A_PRSNT_120_N")
	)
	(segment
		(start 75.475084 -96.149922)
		(end 76.517754 -96.149922)
		(width 0.127)
		(layer "F.Cu")
		(net "MEZZ_A_PRSNT_120_N")
	)
	(via
		(at 77.13472 -96.766888)
		(size 0.508)
		(drill 0.254)
		(layers "F.Cu" "B.Cu")
		(net "MEZZ_A_PRSNT_120_N")
	)
	(via
		(at 79.111856 -96.827594)
		(size 0.6096)
		(drill 0.3048)
		(layers "F.Cu" "B.Cu")
		(net "MEZZ_A_PRSNT_120_N")
	)
	(segment
		(start 84.276946 -100.074222)
		(end 83.102196 -98.899472)
		(width 0.127)
		(layer "B.Cu")
		(net "MEZZ_A_PRSNT_120_N")
	)
	(segment
		(start 82.911696 -98.708972)
		(end 83.102196 -98.899472)
		(width 0.127)
		(layer "B.Cu")
		(net "MEZZ_A_PRSNT_120_N")
	)
	(segment
		(start 84.431378 -100.074222)
		(end 84.276946 -100.074222)
		(width 0.127)
		(layer "B.Cu")
		(net "MEZZ_A_PRSNT_120_N")
	)
	(segment
		(start 82.402172 -98.708972)
		(end 82.911696 -98.708972)
		(width 0.127)
		(layer "B.Cu")
		(net "MEZZ_A_PRSNT_120_N")
	)
	(segment
		(start 77.13472 -96.766888)
		(end 77.195426 -96.827594)
		(width 0.127)
		(layer "B.Cu")
		(net "MEZZ_A_PRSNT_120_N")
	)
	(segment
		(start 77.195426 -96.827594)
		(end 79.111856 -96.827594)
		(width 0.127)
		(layer "B.Cu")
		(net "MEZZ_A_PRSNT_120_N")
	)
	(segment
		(start 80.520794 -96.827594)
		(end 82.402172 -98.708972)
		(width 0.127)
		(layer "B.Cu")
		(net "MEZZ_A_PRSNT_120_N")
	)
	(segment
		(start 79.111856 -96.827594)
		(end 80.520794 -96.827594)
		(width 0.127)
		(layer "B.Cu")
		(net "MEZZ_A_PRSNT_120_N")
	)
	(segment
		(start 87.6046 -130.705098)
		(end 88.232488 -130.705098)
		(width 0.127)
		(layer "F.Cu")
		(net "LED_POSTCODE_7")
	)
	(segment
		(start 53.699918 -139.800076)
		(end 54.099968 -139.400026)
		(width 0.127)
		(layer "F.Cu")
		(net "LED_POSTCODE_7")
	)
	(segment
		(start 82.417412 -129.737612)
		(end 83.1088 -130.429)
		(width 0.127)
		(layer "F.Cu")
		(net "LED_POSTCODE_7")
	)
	(segment
		(start 87.392764 -130.493262)
		(end 87.6046 -130.705098)
		(width 0.127)
		(layer "F.Cu")
		(net "LED_POSTCODE_7")
	)
	(segment
		(start 83.1088 -130.429)
		(end 84.993988 -130.429)
		(width 0.127)
		(layer "F.Cu")
		(net "LED_POSTCODE_7")
	)
	(segment
		(start 76.19238 -129.737612)
		(end 76.059792 -129.8702)
		(width 0.127)
		(layer "F.Cu")
		(net "LED_POSTCODE_7")
	)
	(segment
		(start 93.091 -138.88339)
		(end 92.43949 -139.5349)
		(width 0.127)
		(layer "F.Cu")
		(net "LED_POSTCODE_7")
	)
	(segment
		(start 91.702382 -139.5349)
		(end 91.509596 -139.727686)
		(width 0.127)
		(layer "F.Cu")
		(net "LED_POSTCODE_7")
	)
	(segment
		(start 91.509596 -139.727686)
		(end 90.357706 -139.727686)
		(width 0.127)
		(layer "F.Cu")
		(net "LED_POSTCODE_7")
	)
	(segment
		(start 86.739984 -129.2479)
		(end 87.392764 -129.90068)
		(width 0.127)
		(layer "F.Cu")
		(net "LED_POSTCODE_7")
	)
	(segment
		(start 93.091 -132.166106)
		(end 93.091 -138.88339)
		(width 0.127)
		(layer "F.Cu")
		(net "LED_POSTCODE_7")
	)
	(segment
		(start 84.993988 -130.429)
		(end 86.175088 -129.2479)
		(width 0.127)
		(layer "F.Cu")
		(net "LED_POSTCODE_7")
	)
	(segment
		(start 86.175088 -129.2479)
		(end 86.739984 -129.2479)
		(width 0.127)
		(layer "F.Cu")
		(net "LED_POSTCODE_7")
	)
	(segment
		(start 89.114122 -131.586732)
		(end 92.511626 -131.586732)
		(width 0.127)
		(layer "F.Cu")
		(net "LED_POSTCODE_7")
	)
	(segment
		(start 92.43949 -139.5349)
		(end 91.702382 -139.5349)
		(width 0.127)
		(layer "F.Cu")
		(net "LED_POSTCODE_7")
	)
	(segment
		(start 80.969612 -129.737612)
		(end 76.19238 -129.737612)
		(width 0.127)
		(layer "F.Cu")
		(net "LED_POSTCODE_7")
	)
	(segment
		(start 88.232488 -130.705098)
		(end 89.114122 -131.586732)
		(width 0.127)
		(layer "F.Cu")
		(net "LED_POSTCODE_7")
	)
	(segment
		(start 87.392764 -129.90068)
		(end 87.392764 -130.493262)
		(width 0.127)
		(layer "F.Cu")
		(net "LED_POSTCODE_7")
	)
	(segment
		(start 80.969612 -129.737612)
		(end 82.417412 -129.737612)
		(width 0.127)
		(layer "F.Cu")
		(net "LED_POSTCODE_7")
	)
	(segment
		(start 92.511626 -131.586732)
		(end 93.091 -132.166106)
		(width 0.127)
		(layer "F.Cu")
		(net "LED_POSTCODE_7")
	)
	(via
		(at 80.969612 -129.737612)
		(size 0.6604)
		(drill 0.3302)
		(layers "F.Cu" "B.Cu")
		(net "LED_POSTCODE_7")
	)
	(via
		(at 76.059792 -129.8702)
		(size 0.508)
		(drill 0.254)
		(layers "F.Cu" "B.Cu")
		(net "LED_POSTCODE_7")
	)
	(via
		(at 56.7944 -130.1496)
		(size 0.508)
		(drill 0.254)
		(layers "F.Cu" "B.Cu")
		(net "LED_POSTCODE_7")
	)
	(via
		(at 54.099968 -139.400026)
		(size 0.4572)
		(drill 0.2032)
		(layers "F.Cu" "B.Cu")
		(net "LED_POSTCODE_7")
	)
	(segment
		(start 54.493668 -136.184132)
		(end 56.7944 -133.8834)
		(width 0.127)
		(layer "In2.Cu")
		(net "LED_POSTCODE_7")
	)
	(segment
		(start 54.099968 -139.400026)
		(end 54.493668 -139.006326)
		(width 0.127)
		(layer "In2.Cu")
		(net "LED_POSTCODE_7")
	)
	(segment
		(start 54.493668 -139.006326)
		(end 54.493668 -136.184132)
		(width 0.127)
		(layer "In2.Cu")
		(net "LED_POSTCODE_7")
	)
	(segment
		(start 56.7944 -133.8834)
		(end 56.7944 -130.1496)
		(width 0.127)
		(layer "In2.Cu")
		(net "LED_POSTCODE_7")
	)
	(segment
		(start 57.923176 -131.2291)
		(end 56.843676 -130.1496)
		(width 0.127)
		(layer "In5.Cu")
		(net "LED_POSTCODE_7")
	)
	(segment
		(start 72.11822 -130.7211)
		(end 66.596514 -130.7211)
		(width 0.127)
		(layer "In5.Cu")
		(net "LED_POSTCODE_7")
	)
	(segment
		(start 66.138806 -130.263392)
		(end 65.075816 -130.263392)
		(width 0.127)
		(layer "In5.Cu")
		(net "LED_POSTCODE_7")
	)
	(segment
		(start 66.596514 -130.7211)
		(end 66.138806 -130.263392)
		(width 0.127)
		(layer "In5.Cu")
		(net "LED_POSTCODE_7")
	)
	(segment
		(start 65.075816 -130.263392)
		(end 64.618108 -130.7211)
		(width 0.127)
		(layer "In5.Cu")
		(net "LED_POSTCODE_7")
	)
	(segment
		(start 72.96912 -129.8702)
		(end 72.11822 -130.7211)
		(width 0.127)
		(layer "In5.Cu")
		(net "LED_POSTCODE_7")
	)
	(segment
		(start 56.843676 -130.1496)
		(end 56.7944 -130.1496)
		(width 0.127)
		(layer "In5.Cu")
		(net "LED_POSTCODE_7")
	)
	(segment
		(start 61.963554 -130.7211)
		(end 61.455554 -131.2291)
		(width 0.127)
		(layer "In5.Cu")
		(net "LED_POSTCODE_7")
	)
	(segment
		(start 64.618108 -130.7211)
		(end 61.963554 -130.7211)
		(width 0.127)
		(layer "In5.Cu")
		(net "LED_POSTCODE_7")
	)
	(segment
		(start 76.059792 -129.8702)
		(end 72.96912 -129.8702)
		(width 0.127)
		(layer "In5.Cu")
		(net "LED_POSTCODE_7")
	)
	(segment
		(start 61.455554 -131.2291)
		(end 57.923176 -131.2291)
		(width 0.127)
		(layer "In5.Cu")
		(net "LED_POSTCODE_7")
	)
	(segment
		(start 88.64727 -139.498324)
		(end 88.188546 -139.0396)
		(width 0.127)
		(layer "F.Cu")
		(net "LED_POSTCODE_6")
	)
	(segment
		(start 57.991502 -140.250926)
		(end 57.869074 -140.250926)
		(width 0.127)
		(layer "F.Cu")
		(net "LED_POSTCODE_6")
	)
	(segment
		(start 90.357706 -140.377926)
		(end 89.526872 -140.377926)
		(width 0.127)
		(layer "F.Cu")
		(net "LED_POSTCODE_6")
	)
	(segment
		(start 88.188546 -139.0396)
		(end 87.1728 -139.0396)
		(width 0.127)
		(layer "F.Cu")
		(net "LED_POSTCODE_6")
	)
	(segment
		(start 87.1728 -139.0396)
		(end 86.694264 -138.561064)
		(width 0.127)
		(layer "F.Cu")
		(net "LED_POSTCODE_6")
	)
	(segment
		(start 89.526872 -140.377926)
		(end 88.64727 -139.498324)
		(width 0.127)
		(layer "F.Cu")
		(net "LED_POSTCODE_6")
	)
	(segment
		(start 57.869074 -140.250926)
		(end 56.719978 -141.400022)
		(width 0.127)
		(layer "F.Cu")
		(net "LED_POSTCODE_6")
	)
	(segment
		(start 56.719978 -141.400022)
		(end 56.099964 -141.400022)
		(width 0.127)
		(layer "F.Cu")
		(net "LED_POSTCODE_6")
	)
	(segment
		(start 86.694264 -138.561064)
		(end 86.694264 -138.43)
		(width 0.127)
		(layer "F.Cu")
		(net "LED_POSTCODE_6")
	)
	(via
		(at 84.1248 -129.2606)
		(size 0.508)
		(drill 0.254)
		(layers "F.Cu" "B.Cu")
		(net "LED_POSTCODE_6")
	)
	(via
		(at 86.694264 -138.43)
		(size 0.508)
		(drill 0.254)
		(layers "F.Cu" "B.Cu")
		(net "LED_POSTCODE_6")
	)
	(via
		(at 57.991502 -140.250926)
		(size 0.508)
		(drill 0.254)
		(layers "F.Cu" "B.Cu")
		(net "LED_POSTCODE_6")
	)
	(via
		(at 58.8772 -130.0734)
		(size 0.508)
		(drill 0.254)
		(layers "F.Cu" "B.Cu")
		(net "LED_POSTCODE_6")
	)
	(via
		(at 88.64727 -139.498324)
		(size 0.6604)
		(drill 0.3302)
		(layers "F.Cu" "B.Cu")
		(net "LED_POSTCODE_6")
	)
	(segment
		(start 58.5343 -130.4163)
		(end 58.5343 -138.552936)
		(width 0.127)
		(layer "In2.Cu")
		(net "LED_POSTCODE_6")
	)
	(segment
		(start 84.53501 -131.58978)
		(end 84.53501 -132.967984)
		(width 0.127)
		(layer "In2.Cu")
		(net "LED_POSTCODE_6")
	)
	(segment
		(start 85.286596 -135.579612)
		(end 85.2678 -135.598408)
		(width 0.127)
		(layer "In2.Cu")
		(net "LED_POSTCODE_6")
	)
	(segment
		(start 84.1248 -129.2606)
		(end 84.1248 -129.3114)
		(width 0.127)
		(layer "In2.Cu")
		(net "LED_POSTCODE_6")
	)
	(segment
		(start 84.1248 -129.3114)
		(end 84.0359 -129.4003)
		(width 0.127)
		(layer "In2.Cu")
		(net "LED_POSTCODE_6")
	)
	(segment
		(start 84.53501 -132.967984)
		(end 85.286596 -133.71957)
		(width 0.127)
		(layer "In2.Cu")
		(net "LED_POSTCODE_6")
	)
	(segment
		(start 57.991502 -139.095734)
		(end 57.991502 -140.250926)
		(width 0.127)
		(layer "In2.Cu")
		(net "LED_POSTCODE_6")
	)
	(segment
		(start 84.0359 -129.4003)
		(end 84.0359 -131.09067)
		(width 0.127)
		(layer "In2.Cu")
		(net "LED_POSTCODE_6")
	)
	(segment
		(start 58.5343 -138.552936)
		(end 57.991502 -139.095734)
		(width 0.127)
		(layer "In2.Cu")
		(net "LED_POSTCODE_6")
	)
	(segment
		(start 84.0359 -131.09067)
		(end 84.53501 -131.58978)
		(width 0.127)
		(layer "In2.Cu")
		(net "LED_POSTCODE_6")
	)
	(segment
		(start 85.286596 -133.71957)
		(end 85.286596 -135.579612)
		(width 0.127)
		(layer "In2.Cu")
		(net "LED_POSTCODE_6")
	)
	(segment
		(start 58.8772 -130.0734)
		(end 58.5343 -130.4163)
		(width 0.127)
		(layer "In2.Cu")
		(net "LED_POSTCODE_6")
	)
	(segment
		(start 85.2678 -137.169906)
		(end 85.956394 -137.8585)
		(width 0.127)
		(layer "In2.Cu")
		(net "LED_POSTCODE_6")
	)
	(segment
		(start 85.956394 -137.8585)
		(end 86.092538 -137.8585)
		(width 0.127)
		(layer "In2.Cu")
		(net "LED_POSTCODE_6")
	)
	(segment
		(start 85.2678 -135.598408)
		(end 85.2678 -137.169906)
		(width 0.127)
		(layer "In2.Cu")
		(net "LED_POSTCODE_6")
	)
	(segment
		(start 86.664038 -138.43)
		(end 86.694264 -138.43)
		(width 0.127)
		(layer "In2.Cu")
		(net "LED_POSTCODE_6")
	)
	(segment
		(start 86.092538 -137.8585)
		(end 86.664038 -138.43)
		(width 0.127)
		(layer "In2.Cu")
		(net "LED_POSTCODE_6")
	)
	(segment
		(start 66.296794 -129.882392)
		(end 64.917574 -129.882392)
		(width 0.127)
		(layer "In5.Cu")
		(net "LED_POSTCODE_6")
	)
	(segment
		(start 61.805566 -130.3401)
		(end 61.297566 -130.8481)
		(width 0.127)
		(layer "In5.Cu")
		(net "LED_POSTCODE_6")
	)
	(segment
		(start 64.459866 -130.3401)
		(end 61.805566 -130.3401)
		(width 0.127)
		(layer "In5.Cu")
		(net "LED_POSTCODE_6")
	)
	(segment
		(start 72.844406 -129.4003)
		(end 71.904606 -130.3401)
		(width 0.127)
		(layer "In5.Cu")
		(net "LED_POSTCODE_6")
	)
	(segment
		(start 66.754502 -130.3401)
		(end 66.296794 -129.882392)
		(width 0.127)
		(layer "In5.Cu")
		(net "LED_POSTCODE_6")
	)
	(segment
		(start 82.637376 -129.6924)
		(end 79.232506 -129.6924)
		(width 0.127)
		(layer "In5.Cu")
		(net "LED_POSTCODE_6")
	)
	(segment
		(start 71.904606 -130.3401)
		(end 66.754502 -130.3401)
		(width 0.127)
		(layer "In5.Cu")
		(net "LED_POSTCODE_6")
	)
	(segment
		(start 64.917574 -129.882392)
		(end 64.459866 -130.3401)
		(width 0.127)
		(layer "In5.Cu")
		(net "LED_POSTCODE_6")
	)
	(segment
		(start 79.232506 -129.6924)
		(end 78.940406 -129.4003)
		(width 0.127)
		(layer "In5.Cu")
		(net "LED_POSTCODE_6")
	)
	(segment
		(start 59.6519 -130.8481)
		(end 58.8772 -130.0734)
		(width 0.127)
		(layer "In5.Cu")
		(net "LED_POSTCODE_6")
	)
	(segment
		(start 84.072476 -129.312924)
		(end 83.016852 -129.312924)
		(width 0.127)
		(layer "In5.Cu")
		(net "LED_POSTCODE_6")
	)
	(segment
		(start 84.1248 -129.2606)
		(end 84.072476 -129.312924)
		(width 0.127)
		(layer "In5.Cu")
		(net "LED_POSTCODE_6")
	)
	(segment
		(start 61.297566 -130.8481)
		(end 59.6519 -130.8481)
		(width 0.127)
		(layer "In5.Cu")
		(net "LED_POSTCODE_6")
	)
	(segment
		(start 78.940406 -129.4003)
		(end 72.844406 -129.4003)
		(width 0.127)
		(layer "In5.Cu")
		(net "LED_POSTCODE_6")
	)
	(segment
		(start 83.016852 -129.312924)
		(end 82.637376 -129.6924)
		(width 0.127)
		(layer "In5.Cu")
		(net "LED_POSTCODE_6")
	)
	(segment
		(start 85.685884 -138.4554)
		(end 85.7123 -138.4554)
		(width 0.127)
		(layer "F.Cu")
		(net "LED_POSTCODE_5")
	)
	(segment
		(start 57.3532 -138.4554)
		(end 57.3532 -139.600178)
		(width 0.127)
		(layer "F.Cu")
		(net "LED_POSTCODE_5")
	)
	(segment
		(start 86.80323 -139.54633)
		(end 87.699596 -139.54633)
		(width 0.127)
		(layer "F.Cu")
		(net "LED_POSTCODE_5")
	)
	(segment
		(start 58.1152 -137.6934)
		(end 57.3532 -138.4554)
		(width 0.127)
		(layer "F.Cu")
		(net "LED_POSTCODE_5")
	)
	(segment
		(start 87.699596 -139.54633)
		(end 89.181432 -141.028166)
		(width 0.127)
		(layer "F.Cu")
		(net "LED_POSTCODE_5")
	)
	(segment
		(start 89.181432 -141.028166)
		(end 90.357706 -141.028166)
		(width 0.127)
		(layer "F.Cu")
		(net "LED_POSTCODE_5")
	)
	(segment
		(start 55.666386 -140.2334)
		(end 55.299864 -140.599922)
		(width 0.127)
		(layer "F.Cu")
		(net "LED_POSTCODE_5")
	)
	(segment
		(start 56.719978 -140.2334)
		(end 55.666386 -140.2334)
		(width 0.127)
		(layer "F.Cu")
		(net "LED_POSTCODE_5")
	)
	(segment
		(start 57.3532 -139.600178)
		(end 56.719978 -140.2334)
		(width 0.127)
		(layer "F.Cu")
		(net "LED_POSTCODE_5")
	)
	(segment
		(start 85.7123 -138.4554)
		(end 86.80323 -139.54633)
		(width 0.127)
		(layer "F.Cu")
		(net "LED_POSTCODE_5")
	)
	(via
		(at 58.1152 -137.6934)
		(size 0.508)
		(drill 0.254)
		(layers "F.Cu" "B.Cu")
		(net "LED_POSTCODE_5")
	)
	(via
		(at 57.382156 -132.854954)
		(size 0.508)
		(drill 0.254)
		(layers "F.Cu" "B.Cu")
		(net "LED_POSTCODE_5")
	)
	(via
		(at 85.685884 -138.4554)
		(size 0.508)
		(drill 0.254)
		(layers "F.Cu" "B.Cu")
		(net "LED_POSTCODE_5")
	)
	(via
		(at 83.3628 -129.9464)
		(size 0.508)
		(drill 0.254)
		(layers "F.Cu" "B.Cu")
		(net "LED_POSTCODE_5")
	)
	(segment
		(start 58.1152 -137.6934)
		(end 57.4802 -137.0584)
		(width 0.127)
		(layer "In2.Cu")
		(net "LED_POSTCODE_5")
	)
	(segment
		(start 57.4802 -137.0584)
		(end 57.4802 -132.952998)
		(width 0.127)
		(layer "In2.Cu")
		(net "LED_POSTCODE_5")
	)
	(segment
		(start 84.15401 -131.764278)
		(end 83.6549 -131.265168)
		(width 0.127)
		(layer "In2.Cu")
		(net "LED_POSTCODE_5")
	)
	(segment
		(start 85.685884 -138.421872)
		(end 84.15401 -136.889998)
		(width 0.127)
		(layer "In2.Cu")
		(net "LED_POSTCODE_5")
	)
	(segment
		(start 83.6549 -130.1877)
		(end 83.4136 -129.9464)
		(width 0.127)
		(layer "In2.Cu")
		(net "LED_POSTCODE_5")
	)
	(segment
		(start 57.4802 -132.952998)
		(end 57.382156 -132.854954)
		(width 0.127)
		(layer "In2.Cu")
		(net "LED_POSTCODE_5")
	)
	(segment
		(start 84.15401 -136.889998)
		(end 84.15401 -131.764278)
		(width 0.127)
		(layer "In2.Cu")
		(net "LED_POSTCODE_5")
	)
	(segment
		(start 83.4136 -129.9464)
		(end 83.3628 -129.9464)
		(width 0.127)
		(layer "In2.Cu")
		(net "LED_POSTCODE_5")
	)
	(segment
		(start 85.685884 -138.4554)
		(end 85.685884 -138.421872)
		(width 0.127)
		(layer "In2.Cu")
		(net "LED_POSTCODE_5")
	)
	(segment
		(start 83.6549 -131.265168)
		(end 83.6549 -130.1877)
		(width 0.127)
		(layer "In2.Cu")
		(net "LED_POSTCODE_5")
	)
	(segment
		(start 65.980818 -130.644392)
		(end 65.240408 -130.644392)
		(width 0.127)
		(layer "In5.Cu")
		(net "LED_POSTCODE_5")
	)
	(segment
		(start 72.65162 -130.726688)
		(end 72.221852 -131.156456)
		(width 0.127)
		(layer "In5.Cu")
		(net "LED_POSTCODE_5")
	)
	(segment
		(start 76.838556 -129.7813)
		(end 76.279756 -130.3401)
		(width 0.127)
		(layer "In5.Cu")
		(net "LED_POSTCODE_5")
	)
	(segment
		(start 73.04278 -130.3401)
		(end 72.656192 -130.726688)
		(width 0.127)
		(layer "In5.Cu")
		(net "LED_POSTCODE_5")
	)
	(segment
		(start 66.492882 -131.156456)
		(end 65.980818 -130.644392)
		(width 0.127)
		(layer "In5.Cu")
		(net "LED_POSTCODE_5")
	)
	(segment
		(start 76.279756 -130.3401)
		(end 73.04278 -130.3401)
		(width 0.127)
		(layer "In5.Cu")
		(net "LED_POSTCODE_5")
	)
	(segment
		(start 57.492646 -132.854954)
		(end 57.382156 -132.854954)
		(width 0.127)
		(layer "In5.Cu")
		(net "LED_POSTCODE_5")
	)
	(segment
		(start 83.3628 -129.9464)
		(end 83.2358 -130.0734)
		(width 0.127)
		(layer "In5.Cu")
		(net "LED_POSTCODE_5")
	)
	(segment
		(start 65.240408 -130.644392)
		(end 63.8048 -132.08)
		(width 0.127)
		(layer "In5.Cu")
		(net "LED_POSTCODE_5")
	)
	(segment
		(start 72.656192 -130.726688)
		(end 72.65162 -130.726688)
		(width 0.127)
		(layer "In5.Cu")
		(net "LED_POSTCODE_5")
	)
	(segment
		(start 78.782418 -129.7813)
		(end 76.838556 -129.7813)
		(width 0.127)
		(layer "In5.Cu")
		(net "LED_POSTCODE_5")
	)
	(segment
		(start 79.074518 -130.0734)
		(end 78.782418 -129.7813)
		(width 0.127)
		(layer "In5.Cu")
		(net "LED_POSTCODE_5")
	)
	(segment
		(start 72.221852 -131.156456)
		(end 66.492882 -131.156456)
		(width 0.127)
		(layer "In5.Cu")
		(net "LED_POSTCODE_5")
	)
	(segment
		(start 83.2358 -130.0734)
		(end 79.074518 -130.0734)
		(width 0.127)
		(layer "In5.Cu")
		(net "LED_POSTCODE_5")
	)
	(segment
		(start 58.2676 -132.08)
		(end 57.492646 -132.854954)
		(width 0.127)
		(layer "In5.Cu")
		(net "LED_POSTCODE_5")
	)
	(segment
		(start 63.8048 -132.08)
		(end 58.2676 -132.08)
		(width 0.127)
		(layer "In5.Cu")
		(net "LED_POSTCODE_5")
	)
	(segment
		(start 57.9374 -138.557)
		(end 57.9374 -139.33932)
		(width 0.127)
		(layer "F.Cu")
		(net "LED_POSTCODE_4")
	)
	(segment
		(start 85.49386 -139.128246)
		(end 84.539836 -138.174222)
		(width 0.127)
		(layer "F.Cu")
		(net "LED_POSTCODE_4")
	)
	(segment
		(start 87.93226 -140.87983)
		(end 87.93226 -140.317982)
		(width 0.127)
		(layer "F.Cu")
		(net "LED_POSTCODE_4")
	)
	(segment
		(start 86.694518 -139.976606)
		(end 85.846158 -139.128246)
		(width 0.127)
		(layer "F.Cu")
		(net "LED_POSTCODE_4")
	)
	(segment
		(start 87.590884 -139.976606)
		(end 86.694518 -139.976606)
		(width 0.127)
		(layer "F.Cu")
		(net "LED_POSTCODE_4")
	)
	(segment
		(start 57.9374 -139.33932)
		(end 56.676798 -140.599922)
		(width 0.127)
		(layer "F.Cu")
		(net "LED_POSTCODE_4")
	)
	(segment
		(start 88.730836 -141.678406)
		(end 87.93226 -140.87983)
		(width 0.127)
		(layer "F.Cu")
		(net "LED_POSTCODE_4")
	)
	(segment
		(start 85.846158 -139.128246)
		(end 85.49386 -139.128246)
		(width 0.127)
		(layer "F.Cu")
		(net "LED_POSTCODE_4")
	)
	(segment
		(start 90.357706 -141.678406)
		(end 88.730836 -141.678406)
		(width 0.127)
		(layer "F.Cu")
		(net "LED_POSTCODE_4")
	)
	(segment
		(start 56.676798 -140.599922)
		(end 56.099964 -140.599922)
		(width 0.127)
		(layer "F.Cu")
		(net "LED_POSTCODE_4")
	)
	(segment
		(start 87.93226 -140.317982)
		(end 87.590884 -139.976606)
		(width 0.127)
		(layer "F.Cu")
		(net "LED_POSTCODE_4")
	)
	(via
		(at 84.539836 -138.174222)
		(size 0.508)
		(drill 0.254)
		(layers "F.Cu" "B.Cu")
		(net "LED_POSTCODE_4")
	)
	(via
		(at 88.730836 -141.678406)
		(size 0.6604)
		(drill 0.3302)
		(layers "F.Cu" "B.Cu")
		(net "LED_POSTCODE_4")
	)
	(via
		(at 57.9374 -138.557)
		(size 0.508)
		(drill 0.254)
		(layers "F.Cu" "B.Cu")
		(net "LED_POSTCODE_4")
	)
	(segment
		(start 73.146412 -138.2776)
		(end 73.46569 -137.958322)
		(width 0.127)
		(layer "In5.Cu")
		(net "LED_POSTCODE_4")
	)
	(segment
		(start 66.565526 -137.315702)
		(end 67.527424 -138.2776)
		(width 0.127)
		(layer "In5.Cu")
		(net "LED_POSTCODE_4")
	)
	(segment
		(start 77.702156 -137.958322)
		(end 77.918056 -138.174222)
		(width 0.127)
		(layer "In5.Cu")
		(net "LED_POSTCODE_4")
	)
	(segment
		(start 77.918056 -138.174222)
		(end 84.539836 -138.174222)
		(width 0.127)
		(layer "In5.Cu")
		(net "LED_POSTCODE_4")
	)
	(segment
		(start 58.283602 -138.557)
		(end 59.119008 -137.721594)
		(width 0.127)
		(layer "In5.Cu")
		(net "LED_POSTCODE_4")
	)
	(segment
		(start 59.119008 -137.721594)
		(end 61.219842 -137.721594)
		(width 0.127)
		(layer "In5.Cu")
		(net "LED_POSTCODE_4")
	)
	(segment
		(start 61.219842 -137.721594)
		(end 61.625734 -137.315702)
		(width 0.127)
		(layer "In5.Cu")
		(net "LED_POSTCODE_4")
	)
	(segment
		(start 61.625734 -137.315702)
		(end 66.565526 -137.315702)
		(width 0.127)
		(layer "In5.Cu")
		(net "LED_POSTCODE_4")
	)
	(segment
		(start 73.46569 -137.958322)
		(end 77.702156 -137.958322)
		(width 0.127)
		(layer "In5.Cu")
		(net "LED_POSTCODE_4")
	)
	(segment
		(start 67.527424 -138.2776)
		(end 73.146412 -138.2776)
		(width 0.127)
		(layer "In5.Cu")
		(net "LED_POSTCODE_4")
	)
	(segment
		(start 57.9374 -138.557)
		(end 58.283602 -138.557)
		(width 0.127)
		(layer "In5.Cu")
		(net "LED_POSTCODE_4")
	)
	(segment
		(start 92.284804 -143.222472)
		(end 92.284804 -143.186404)
		(width 0.127)
		(layer "F.Cu")
		(net "LED_POSTCODE_3")
	)
	(segment
		(start 93.344746 -148.903944)
		(end 93.344746 -146.676618)
		(width 0.127)
		(layer "F.Cu")
		(net "LED_POSTCODE_3")
	)
	(segment
		(start 93.344746 -146.676618)
		(end 93.600016 -146.421348)
		(width 0.127)
		(layer "F.Cu")
		(net "LED_POSTCODE_3")
	)
	(segment
		(start 91.427046 -142.328646)
		(end 90.357706 -142.328646)
		(width 0.127)
		(layer "F.Cu")
		(net "LED_POSTCODE_3")
	)
	(segment
		(start 54.500272 -140.599922)
		(end 54.500018 -140.599922)
		(width 0.127)
		(layer "F.Cu")
		(net "LED_POSTCODE_3")
	)
	(segment
		(start 93.600016 -146.421348)
		(end 93.600016 -144.501616)
		(width 0.127)
		(layer "F.Cu")
		(net "LED_POSTCODE_3")
	)
	(segment
		(start 92.700856 -149.547834)
		(end 93.344746 -148.903944)
		(width 0.127)
		(layer "F.Cu")
		(net "LED_POSTCODE_3")
	)
	(segment
		(start 93.600016 -144.501616)
		(end 92.595954 -143.497554)
		(width 0.127)
		(layer "F.Cu")
		(net "LED_POSTCODE_3")
	)
	(segment
		(start 92.559886 -143.497554)
		(end 92.284804 -143.222472)
		(width 0.127)
		(layer "F.Cu")
		(net "LED_POSTCODE_3")
	)
	(segment
		(start 54.899814 -140.20038)
		(end 54.500272 -140.599922)
		(width 0.127)
		(layer "F.Cu")
		(net "LED_POSTCODE_3")
	)
	(segment
		(start 92.284804 -143.186404)
		(end 91.427046 -142.328646)
		(width 0.127)
		(layer "F.Cu")
		(net "LED_POSTCODE_3")
	)
	(segment
		(start 92.595954 -143.497554)
		(end 92.559886 -143.497554)
		(width 0.127)
		(layer "F.Cu")
		(net "LED_POSTCODE_3")
	)
	(via
		(at 54.899814 -140.20038)
		(size 0.4572)
		(drill 0.2032)
		(layers "F.Cu" "B.Cu")
		(net "LED_POSTCODE_3")
	)
	(via
		(at 59.247532 -151.306022)
		(size 0.508)
		(drill 0.254)
		(layers "F.Cu" "B.Cu")
		(net "LED_POSTCODE_3")
	)
	(via
		(at 92.700856 -149.547834)
		(size 0.508)
		(drill 0.254)
		(layers "F.Cu" "B.Cu")
		(net "LED_POSTCODE_3")
	)
	(segment
		(start 55.535322 -140.20038)
		(end 54.899814 -140.20038)
		(width 0.127)
		(layer "In2.Cu")
		(net "LED_POSTCODE_3")
	)
	(segment
		(start 59.247532 -151.306022)
		(end 59.247532 -149.925532)
		(width 0.127)
		(layer "In2.Cu")
		(net "LED_POSTCODE_3")
	)
	(segment
		(start 59.247532 -149.925532)
		(end 58.22061 -148.89861)
		(width 0.127)
		(layer "In2.Cu")
		(net "LED_POSTCODE_3")
	)
	(segment
		(start 58.22061 -142.885668)
		(end 55.535322 -140.20038)
		(width 0.127)
		(layer "In2.Cu")
		(net "LED_POSTCODE_3")
	)
	(segment
		(start 58.22061 -148.89861)
		(end 58.22061 -142.885668)
		(width 0.127)
		(layer "In2.Cu")
		(net "LED_POSTCODE_3")
	)
	(segment
		(start 77.676248 -151.58974)
		(end 77.09662 -151.010112)
		(width 0.127)
		(layer "In5.Cu")
		(net "LED_POSTCODE_3")
	)
	(segment
		(start 87.06104 -150.559008)
		(end 84.0105 -150.559008)
		(width 0.127)
		(layer "In5.Cu")
		(net "LED_POSTCODE_3")
	)
	(segment
		(start 70.645274 -151.010112)
		(end 70.307962 -150.6728)
		(width 0.127)
		(layer "In5.Cu")
		(net "LED_POSTCODE_3")
	)
	(segment
		(start 83.849972 -150.719536)
		(end 80.38465 -150.719536)
		(width 0.127)
		(layer "In5.Cu")
		(net "LED_POSTCODE_3")
	)
	(segment
		(start 61.737748 -150.3807)
		(end 60.812426 -151.306022)
		(width 0.127)
		(layer "In5.Cu")
		(net "LED_POSTCODE_3")
	)
	(segment
		(start 91.971876 -149.547834)
		(end 91.65971 -149.86)
		(width 0.127)
		(layer "In5.Cu")
		(net "LED_POSTCODE_3")
	)
	(segment
		(start 84.0105 -150.559008)
		(end 83.849972 -150.719536)
		(width 0.127)
		(layer "In5.Cu")
		(net "LED_POSTCODE_3")
	)
	(segment
		(start 77.09662 -151.010112)
		(end 70.645274 -151.010112)
		(width 0.127)
		(layer "In5.Cu")
		(net "LED_POSTCODE_3")
	)
	(segment
		(start 91.65971 -149.86)
		(end 87.760048 -149.86)
		(width 0.127)
		(layer "In5.Cu")
		(net "LED_POSTCODE_3")
	)
	(segment
		(start 66.332862 -150.6728)
		(end 66.040762 -150.3807)
		(width 0.127)
		(layer "In5.Cu")
		(net "LED_POSTCODE_3")
	)
	(segment
		(start 87.760048 -149.86)
		(end 87.06104 -150.559008)
		(width 0.127)
		(layer "In5.Cu")
		(net "LED_POSTCODE_3")
	)
	(segment
		(start 66.040762 -150.3807)
		(end 61.737748 -150.3807)
		(width 0.127)
		(layer "In5.Cu")
		(net "LED_POSTCODE_3")
	)
	(segment
		(start 70.307962 -150.6728)
		(end 66.332862 -150.6728)
		(width 0.127)
		(layer "In5.Cu")
		(net "LED_POSTCODE_3")
	)
	(segment
		(start 92.700856 -149.547834)
		(end 91.971876 -149.547834)
		(width 0.127)
		(layer "In5.Cu")
		(net "LED_POSTCODE_3")
	)
	(segment
		(start 60.812426 -151.306022)
		(end 59.247532 -151.306022)
		(width 0.127)
		(layer "In5.Cu")
		(net "LED_POSTCODE_3")
	)
	(segment
		(start 80.38465 -150.719536)
		(end 79.514446 -151.58974)
		(width 0.127)
		(layer "In5.Cu")
		(net "LED_POSTCODE_3")
	)
	(segment
		(start 79.514446 -151.58974)
		(end 77.676248 -151.58974)
		(width 0.127)
		(layer "In5.Cu")
		(net "LED_POSTCODE_3")
	)
	(segment
		(start 54.099968 -140.200126)
		(end 53.700172 -140.599922)
		(width 0.127)
		(layer "F.Cu")
		(net "LED_POSTCODE_2")
	)
	(segment
		(start 92.6846 -148.633434)
		(end 92.68587 -148.633434)
		(width 0.127)
		(layer "F.Cu")
		(net "LED_POSTCODE_2")
	)
	(segment
		(start 92.77858 -146.703796)
		(end 92.77858 -147.5232)
		(width 0.127)
		(layer "F.Cu")
		(net "LED_POSTCODE_2")
	)
	(segment
		(start 93.219016 -146.26336)
		(end 92.77858 -146.703796)
		(width 0.127)
		(layer "F.Cu")
		(net "LED_POSTCODE_2")
	)
	(segment
		(start 53.700172 -140.599922)
		(end 53.699918 -140.599922)
		(width 0.127)
		(layer "F.Cu")
		(net "LED_POSTCODE_2")
	)
	(segment
		(start 93.219016 -144.831816)
		(end 93.219016 -146.26336)
		(width 0.127)
		(layer "F.Cu")
		(net "LED_POSTCODE_2")
	)
	(segment
		(start 92.68587 -148.633434)
		(end 92.77858 -148.540724)
		(width 0.127)
		(layer "F.Cu")
		(net "LED_POSTCODE_2")
	)
	(segment
		(start 90.357706 -142.978886)
		(end 91.366086 -142.978886)
		(width 0.127)
		(layer "F.Cu")
		(net "LED_POSTCODE_2")
	)
	(segment
		(start 92.77858 -148.540724)
		(end 92.77858 -147.5232)
		(width 0.127)
		(layer "F.Cu")
		(net "LED_POSTCODE_2")
	)
	(segment
		(start 91.366086 -142.978886)
		(end 93.219016 -144.831816)
		(width 0.127)
		(layer "F.Cu")
		(net "LED_POSTCODE_2")
	)
	(via
		(at 54.099968 -140.200126)
		(size 0.4572)
		(drill 0.2032)
		(layers "F.Cu" "B.Cu")
		(net "LED_POSTCODE_2")
	)
	(via
		(at 59.48807 -152.080722)
		(size 0.508)
		(drill 0.254)
		(layers "F.Cu" "B.Cu")
		(net "LED_POSTCODE_2")
	)
	(via
		(at 92.6846 -148.633434)
		(size 0.508)
		(drill 0.254)
		(layers "F.Cu" "B.Cu")
		(net "LED_POSTCODE_2")
	)
	(via
		(at 92.77858 -147.5232)
		(size 0.6604)
		(drill 0.3302)
		(layers "F.Cu" "B.Cu")
		(net "LED_POSTCODE_2")
	)
	(segment
		(start 57.99201 -143.453866)
		(end 55.144924 -140.60678)
		(width 0.127)
		(layer "In2.Cu")
		(net "LED_POSTCODE_2")
	)
	(segment
		(start 57.99201 -148.993352)
		(end 57.99201 -143.453866)
		(width 0.127)
		(layer "In2.Cu")
		(net "LED_POSTCODE_2")
	)
	(segment
		(start 58.79973 -149.801072)
		(end 57.99201 -148.993352)
		(width 0.127)
		(layer "In2.Cu")
		(net "LED_POSTCODE_2")
	)
	(segment
		(start 54.506622 -140.60678)
		(end 54.099968 -140.200126)
		(width 0.127)
		(layer "In2.Cu")
		(net "LED_POSTCODE_2")
	)
	(segment
		(start 59.345322 -152.080722)
		(end 58.79973 -151.53513)
		(width 0.127)
		(layer "In2.Cu")
		(net "LED_POSTCODE_2")
	)
	(segment
		(start 58.79973 -151.53513)
		(end 58.79973 -149.801072)
		(width 0.127)
		(layer "In2.Cu")
		(net "LED_POSTCODE_2")
	)
	(segment
		(start 59.48807 -152.080722)
		(end 59.345322 -152.080722)
		(width 0.127)
		(layer "In2.Cu")
		(net "LED_POSTCODE_2")
	)
	(segment
		(start 55.144924 -140.60678)
		(end 54.506622 -140.60678)
		(width 0.127)
		(layer "In2.Cu")
		(net "LED_POSTCODE_2")
	)
	(segment
		(start 93.2307 -149.179534)
		(end 92.6846 -148.633434)
		(width 0.127)
		(layer "In5.Cu")
		(net "LED_POSTCODE_2")
	)
	(segment
		(start 84.00796 -151.100536)
		(end 84.168488 -150.940008)
		(width 0.127)
		(layer "In5.Cu")
		(net "LED_POSTCODE_2")
	)
	(segment
		(start 80.663034 -151.100536)
		(end 84.00796 -151.100536)
		(width 0.127)
		(layer "In5.Cu")
		(net "LED_POSTCODE_2")
	)
	(segment
		(start 78.110334 -153.653236)
		(end 80.663034 -151.100536)
		(width 0.127)
		(layer "In5.Cu")
		(net "LED_POSTCODE_2")
	)
	(segment
		(start 74.296778 -151.391112)
		(end 76.558902 -153.653236)
		(width 0.127)
		(layer "In5.Cu")
		(net "LED_POSTCODE_2")
	)
	(segment
		(start 91.732354 -150.632668)
		(end 92.18549 -150.179532)
		(width 0.127)
		(layer "In5.Cu")
		(net "LED_POSTCODE_2")
	)
	(segment
		(start 93.2307 -150.052532)
		(end 93.2307 -149.179534)
		(width 0.127)
		(layer "In5.Cu")
		(net "LED_POSTCODE_2")
	)
	(segment
		(start 92.18549 -150.179532)
		(end 93.1037 -150.179532)
		(width 0.127)
		(layer "In5.Cu")
		(net "LED_POSTCODE_2")
	)
	(segment
		(start 76.558902 -153.653236)
		(end 78.110334 -153.653236)
		(width 0.127)
		(layer "In5.Cu")
		(net "LED_POSTCODE_2")
	)
	(segment
		(start 70.487286 -151.391112)
		(end 74.296778 -151.391112)
		(width 0.127)
		(layer "In5.Cu")
		(net "LED_POSTCODE_2")
	)
	(segment
		(start 61.975492 -150.773384)
		(end 65.811908 -150.773384)
		(width 0.127)
		(layer "In5.Cu")
		(net "LED_POSTCODE_2")
	)
	(segment
		(start 84.168488 -150.940008)
		(end 88.429592 -150.940008)
		(width 0.127)
		(layer "In5.Cu")
		(net "LED_POSTCODE_2")
	)
	(segment
		(start 70.149974 -151.0538)
		(end 70.487286 -151.391112)
		(width 0.127)
		(layer "In5.Cu")
		(net "LED_POSTCODE_2")
	)
	(segment
		(start 60.668154 -152.080722)
		(end 61.975492 -150.773384)
		(width 0.127)
		(layer "In5.Cu")
		(net "LED_POSTCODE_2")
	)
	(segment
		(start 88.429592 -150.940008)
		(end 88.736932 -150.632668)
		(width 0.127)
		(layer "In5.Cu")
		(net "LED_POSTCODE_2")
	)
	(segment
		(start 93.1037 -150.179532)
		(end 93.2307 -150.052532)
		(width 0.127)
		(layer "In5.Cu")
		(net "LED_POSTCODE_2")
	)
	(segment
		(start 65.811908 -150.773384)
		(end 66.092324 -151.0538)
		(width 0.127)
		(layer "In5.Cu")
		(net "LED_POSTCODE_2")
	)
	(segment
		(start 59.48807 -152.080722)
		(end 60.668154 -152.080722)
		(width 0.127)
		(layer "In5.Cu")
		(net "LED_POSTCODE_2")
	)
	(segment
		(start 88.736932 -150.632668)
		(end 91.732354 -150.632668)
		(width 0.127)
		(layer "In5.Cu")
		(net "LED_POSTCODE_2")
	)
	(segment
		(start 66.092324 -151.0538)
		(end 70.149974 -151.0538)
		(width 0.127)
		(layer "In5.Cu")
		(net "LED_POSTCODE_2")
	)
	(segment
		(start 55.699914 -139.40028)
		(end 55.300118 -139.800076)
		(width 0.127)
		(layer "F.Cu")
		(net "LED_POSTCODE_1")
	)
	(segment
		(start 88.4682 -143.6116)
		(end 88.485726 -143.629126)
		(width 0.127)
		(layer "F.Cu")
		(net "LED_POSTCODE_1")
	)
	(segment
		(start 88.485726 -143.629126)
		(end 90.357706 -143.629126)
		(width 0.127)
		(layer "F.Cu")
		(net "LED_POSTCODE_1")
	)
	(segment
		(start 55.300118 -139.800076)
		(end 55.299864 -139.800076)
		(width 0.127)
		(layer "F.Cu")
		(net "LED_POSTCODE_1")
	)
	(via
		(at 88.4682 -143.6116)
		(size 0.508)
		(drill 0.254)
		(layers "F.Cu" "B.Cu")
		(net "LED_POSTCODE_1")
	)
	(via
		(at 84.533232 -139.08405)
		(size 0.508)
		(drill 0.254)
		(layers "F.Cu" "B.Cu")
		(net "LED_POSTCODE_1")
	)
	(via
		(at 85.9028 -141.732)
		(size 0.6096)
		(drill 0.3048)
		(layers "F.Cu" "B.Cu")
		(net "LED_POSTCODE_1")
	)
	(via
		(at 55.699914 -139.40028)
		(size 0.4572)
		(drill 0.2032)
		(layers "F.Cu" "B.Cu")
		(net "LED_POSTCODE_1")
	)
	(segment
		(start 85.9028 -141.111478)
		(end 85.9028 -141.732)
		(width 0.127)
		(layer "B.Cu")
		(net "LED_POSTCODE_1")
	)
	(segment
		(start 84.951824 -140.160502)
		(end 85.9028 -141.111478)
		(width 0.127)
		(layer "B.Cu")
		(net "LED_POSTCODE_1")
	)
	(segment
		(start 88.34628 -143.6116)
		(end 88.4682 -143.6116)
		(width 0.127)
		(layer "B.Cu")
		(net "LED_POSTCODE_1")
	)
	(segment
		(start 84.951824 -139.502642)
		(end 84.951824 -140.160502)
		(width 0.127)
		(layer "B.Cu")
		(net "LED_POSTCODE_1")
	)
	(segment
		(start 85.9028 -141.732)
		(end 86.46668 -141.732)
		(width 0.127)
		(layer "B.Cu")
		(net "LED_POSTCODE_1")
	)
	(segment
		(start 84.533232 -139.08405)
		(end 84.951824 -139.502642)
		(width 0.127)
		(layer "B.Cu")
		(net "LED_POSTCODE_1")
	)
	(segment
		(start 86.46668 -141.732)
		(end 88.34628 -143.6116)
		(width 0.127)
		(layer "B.Cu")
		(net "LED_POSTCODE_1")
	)
	(segment
		(start 73.3044 -138.6586)
		(end 73.623678 -138.339322)
		(width 0.127)
		(layer "In5.Cu")
		(net "LED_POSTCODE_1")
	)
	(segment
		(start 84.018882 -138.5697)
		(end 84.533232 -139.08405)
		(width 0.127)
		(layer "In5.Cu")
		(net "LED_POSTCODE_1")
	)
	(segment
		(start 77.774546 -138.5697)
		(end 84.018882 -138.5697)
		(width 0.127)
		(layer "In5.Cu")
		(net "LED_POSTCODE_1")
	)
	(segment
		(start 73.623678 -138.339322)
		(end 77.544168 -138.339322)
		(width 0.127)
		(layer "In5.Cu")
		(net "LED_POSTCODE_1")
	)
	(segment
		(start 61.37783 -138.102594)
		(end 61.783722 -137.696702)
		(width 0.127)
		(layer "In5.Cu")
		(net "LED_POSTCODE_1")
	)
	(segment
		(start 58.37301 -139.00658)
		(end 59.276996 -138.102594)
		(width 0.127)
		(layer "In5.Cu")
		(net "LED_POSTCODE_1")
	)
	(segment
		(start 65.414398 -137.696702)
		(end 66.376296 -138.6586)
		(width 0.127)
		(layer "In5.Cu")
		(net "LED_POSTCODE_1")
	)
	(segment
		(start 77.544168 -138.339322)
		(end 77.774546 -138.5697)
		(width 0.127)
		(layer "In5.Cu")
		(net "LED_POSTCODE_1")
	)
	(segment
		(start 59.276996 -138.102594)
		(end 61.37783 -138.102594)
		(width 0.127)
		(layer "In5.Cu")
		(net "LED_POSTCODE_1")
	)
	(segment
		(start 55.84952 -139.40028)
		(end 56.24322 -139.00658)
		(width 0.127)
		(layer "In5.Cu")
		(net "LED_POSTCODE_1")
	)
	(segment
		(start 61.783722 -137.696702)
		(end 65.414398 -137.696702)
		(width 0.127)
		(layer "In5.Cu")
		(net "LED_POSTCODE_1")
	)
	(segment
		(start 66.376296 -138.6586)
		(end 73.3044 -138.6586)
		(width 0.127)
		(layer "In5.Cu")
		(net "LED_POSTCODE_1")
	)
	(segment
		(start 55.699914 -139.40028)
		(end 55.84952 -139.40028)
		(width 0.127)
		(layer "In5.Cu")
		(net "LED_POSTCODE_1")
	)
	(segment
		(start 56.24322 -139.00658)
		(end 58.37301 -139.00658)
		(width 0.127)
		(layer "In5.Cu")
		(net "LED_POSTCODE_1")
	)
	(segment
		(start 90.357706 -144.279366)
		(end 87.738966 -144.279366)
		(width 0.127)
		(layer "F.Cu")
		(net "LED_POSTCODE_0")
	)
	(segment
		(start 87.738966 -144.279366)
		(end 87.33536 -143.87576)
		(width 0.127)
		(layer "F.Cu")
		(net "LED_POSTCODE_0")
	)
	(segment
		(start 56.500014 -139.40028)
		(end 56.100218 -139.800076)
		(width 0.127)
		(layer "F.Cu")
		(net "LED_POSTCODE_0")
	)
	(segment
		(start 56.100218 -139.800076)
		(end 56.099964 -139.800076)
		(width 0.127)
		(layer "F.Cu")
		(net "LED_POSTCODE_0")
	)
	(via
		(at 87.33536 -143.87576)
		(size 0.508)
		(drill 0.254)
		(layers "F.Cu" "B.Cu")
		(net "LED_POSTCODE_0")
	)
	(via
		(at 83.507834 -139.45489)
		(size 0.508)
		(drill 0.254)
		(layers "F.Cu" "B.Cu")
		(net "LED_POSTCODE_0")
	)
	(via
		(at 56.500014 -139.40028)
		(size 0.4572)
		(drill 0.2032)
		(layers "F.Cu" "B.Cu")
		(net "LED_POSTCODE_0")
	)
	(via
		(at 86.496652 -143.24838)
		(size 0.6096)
		(drill 0.3048)
		(layers "F.Cu" "B.Cu")
		(net "LED_POSTCODE_0")
	)
	(segment
		(start 86.396576 -143.24838)
		(end 86.496652 -143.24838)
		(width 0.127)
		(layer "B.Cu")
		(net "LED_POSTCODE_0")
	)
	(segment
		(start 83.507834 -139.45489)
		(end 83.507834 -140.359638)
		(width 0.127)
		(layer "B.Cu")
		(net "LED_POSTCODE_0")
	)
	(segment
		(start 86.70798 -143.24838)
		(end 86.496652 -143.24838)
		(width 0.127)
		(layer "B.Cu")
		(net "LED_POSTCODE_0")
	)
	(segment
		(start 83.507834 -140.359638)
		(end 86.396576 -143.24838)
		(width 0.127)
		(layer "B.Cu")
		(net "LED_POSTCODE_0")
	)
	(segment
		(start 87.33536 -143.87576)
		(end 86.70798 -143.24838)
		(width 0.127)
		(layer "B.Cu")
		(net "LED_POSTCODE_0")
	)
	(segment
		(start 81.292954 -139.009374)
		(end 76.890626 -139.009374)
		(width 0.127)
		(layer "In5.Cu")
		(net "LED_POSTCODE_0")
	)
	(segment
		(start 76.890626 -139.009374)
		(end 76.515722 -139.384278)
		(width 0.127)
		(layer "In5.Cu")
		(net "LED_POSTCODE_0")
	)
	(segment
		(start 58.518298 -139.40028)
		(end 56.500014 -139.40028)
		(width 0.127)
		(layer "In5.Cu")
		(net "LED_POSTCODE_0")
	)
	(segment
		(start 76.126086 -139.384278)
		(end 75.781408 -139.0396)
		(width 0.127)
		(layer "In5.Cu")
		(net "LED_POSTCODE_0")
	)
	(segment
		(start 81.801208 -139.517628)
		(end 81.292954 -139.009374)
		(width 0.127)
		(layer "In5.Cu")
		(net "LED_POSTCODE_0")
	)
	(segment
		(start 61.535818 -138.483594)
		(end 59.434984 -138.483594)
		(width 0.127)
		(layer "In5.Cu")
		(net "LED_POSTCODE_0")
	)
	(segment
		(start 83.507834 -139.45489)
		(end 83.445096 -139.517628)
		(width 0.127)
		(layer "In5.Cu")
		(net "LED_POSTCODE_0")
	)
	(segment
		(start 75.781408 -139.0396)
		(end 66.218308 -139.0396)
		(width 0.127)
		(layer "In5.Cu")
		(net "LED_POSTCODE_0")
	)
	(segment
		(start 66.218308 -139.0396)
		(end 65.25641 -138.077702)
		(width 0.127)
		(layer "In5.Cu")
		(net "LED_POSTCODE_0")
	)
	(segment
		(start 76.515722 -139.384278)
		(end 76.126086 -139.384278)
		(width 0.127)
		(layer "In5.Cu")
		(net "LED_POSTCODE_0")
	)
	(segment
		(start 59.434984 -138.483594)
		(end 58.518298 -139.40028)
		(width 0.127)
		(layer "In5.Cu")
		(net "LED_POSTCODE_0")
	)
	(segment
		(start 65.25641 -138.077702)
		(end 61.94171 -138.077702)
		(width 0.127)
		(layer "In5.Cu")
		(net "LED_POSTCODE_0")
	)
	(segment
		(start 83.445096 -139.517628)
		(end 81.801208 -139.517628)
		(width 0.127)
		(layer "In5.Cu")
		(net "LED_POSTCODE_0")
	)
	(segment
		(start 61.94171 -138.077702)
		(end 61.535818 -138.483594)
		(width 0.127)
		(layer "In5.Cu")
		(net "LED_POSTCODE_0")
	)
	(segment
		(start 95.945706 -130.76555)
		(end 95.945706 -130.506216)
		(width 0.127)
		(layer "F.Cu")
		(net "DEBUG_UART_IOM_TX")
	)
	(segment
		(start 95.415608 -131.295648)
		(end 95.945706 -130.76555)
		(width 0.127)
		(layer "F.Cu")
		(net "DEBUG_UART_IOM_TX")
	)
	(segment
		(start 95.1992 -131.295648)
		(end 95.415608 -131.295648)
		(width 0.127)
		(layer "F.Cu")
		(net "DEBUG_UART_IOM_TX")
	)
	(via
		(at 95.1992 -131.295648)
		(size 0.508)
		(drill 0.254)
		(layers "F.Cu" "B.Cu")
		(net "DEBUG_UART_IOM_TX")
	)
	(via
		(at 94.839282 -129.908046)
		(size 0.6096)
		(drill 0.3048)
		(layers "F.Cu" "B.Cu")
		(net "DEBUG_UART_IOM_TX")
	)
	(segment
		(start 94.839282 -130.93573)
		(end 95.1992 -131.295648)
		(width 0.127)
		(layer "B.Cu")
		(net "DEBUG_UART_IOM_TX")
	)
	(segment
		(start 95.094552 -131.295648)
		(end 95.1992 -131.295648)
		(width 0.127)
		(layer "B.Cu")
		(net "DEBUG_UART_IOM_TX")
	)
	(segment
		(start 94.3356 -132.0546)
		(end 95.094552 -131.295648)
		(width 0.127)
		(layer "B.Cu")
		(net "DEBUG_UART_IOM_TX")
	)
	(segment
		(start 93.8149 -132.0546)
		(end 94.3356 -132.0546)
		(width 0.127)
		(layer "B.Cu")
		(net "DEBUG_UART_IOM_TX")
	)
	(segment
		(start 94.839282 -129.908046)
		(end 94.839282 -130.93573)
		(width 0.127)
		(layer "B.Cu")
		(net "DEBUG_UART_IOM_TX")
	)
	(segment
		(start 93.740986 -127.8128)
		(end 91.2114 -127.8128)
		(width 0.127)
		(layer "F.Cu")
		(net "DEBUG_UART_IOM_RX")
	)
	(segment
		(start 95.945706 -128.507236)
		(end 94.435422 -128.507236)
		(width 0.127)
		(layer "F.Cu")
		(net "DEBUG_UART_IOM_RX")
	)
	(segment
		(start 94.435422 -128.507236)
		(end 93.740986 -127.8128)
		(width 0.127)
		(layer "F.Cu")
		(net "DEBUG_UART_IOM_RX")
	)
	(via
		(at 89.436194 -131.505198)
		(size 0.6096)
		(drill 0.3048)
		(layers "F.Cu" "B.Cu")
		(net "DEBUG_UART_IOM_RX")
	)
	(via
		(at 91.2114 -127.8128)
		(size 0.508)
		(drill 0.254)
		(layers "F.Cu" "B.Cu")
		(net "DEBUG_UART_IOM_RX")
	)
	(segment
		(start 88.925654 -135.2169)
		(end 88.5571 -134.848346)
		(width 0.127)
		(layer "B.Cu")
		(net "DEBUG_UART_IOM_RX")
	)
	(segment
		(start 90.90279 -128.12141)
		(end 91.2114 -127.8128)
		(width 0.127)
		(layer "B.Cu")
		(net "DEBUG_UART_IOM_RX")
	)
	(segment
		(start 89.3826 -135.2169)
		(end 88.925654 -135.2169)
		(width 0.127)
		(layer "B.Cu")
		(net "DEBUG_UART_IOM_RX")
	)
	(segment
		(start 90.869516 -134.751064)
		(end 90.141552 -134.751064)
		(width 0.127)
		(layer "B.Cu")
		(net "DEBUG_UART_IOM_RX")
	)
	(segment
		(start 90.424 -131.1148)
		(end 90.90279 -130.635756)
		(width 0.127)
		(layer "B.Cu")
		(net "DEBUG_UART_IOM_RX")
	)
	(segment
		(start 89.675716 -135.2169)
		(end 89.3826 -135.2169)
		(width 0.127)
		(layer "B.Cu")
		(net "DEBUG_UART_IOM_RX")
	)
	(segment
		(start 91.04122 -134.57936)
		(end 90.869516 -134.751064)
		(width 0.127)
		(layer "B.Cu")
		(net "DEBUG_UART_IOM_RX")
	)
	(segment
		(start 89.02573 -131.915662)
		(end 89.436194 -131.505198)
		(width 0.127)
		(layer "B.Cu")
		(net "DEBUG_UART_IOM_RX")
	)
	(segment
		(start 88.5571 -133.577584)
		(end 89.02573 -133.108954)
		(width 0.127)
		(layer "B.Cu")
		(net "DEBUG_UART_IOM_RX")
	)
	(segment
		(start 88.5571 -134.848346)
		(end 88.5571 -133.577584)
		(width 0.127)
		(layer "B.Cu")
		(net "DEBUG_UART_IOM_RX")
	)
	(segment
		(start 89.826592 -131.1148)
		(end 90.424 -131.1148)
		(width 0.127)
		(layer "B.Cu")
		(net "DEBUG_UART_IOM_RX")
	)
	(segment
		(start 89.02573 -133.108954)
		(end 89.02573 -131.915662)
		(width 0.127)
		(layer "B.Cu")
		(net "DEBUG_UART_IOM_RX")
	)
	(segment
		(start 90.141552 -134.751064)
		(end 89.675716 -135.2169)
		(width 0.127)
		(layer "B.Cu")
		(net "DEBUG_UART_IOM_RX")
	)
	(segment
		(start 89.436194 -131.505198)
		(end 89.826592 -131.1148)
		(width 0.127)
		(layer "B.Cu")
		(net "DEBUG_UART_IOM_RX")
	)
	(segment
		(start 90.90279 -130.635756)
		(end 90.90279 -128.12141)
		(width 0.127)
		(layer "B.Cu")
		(net "DEBUG_UART_IOM_RX")
	)
	(segment
		(start 96.86671 -131.938014)
		(end 97.594166 -131.210558)
		(width 0.127)
		(layer "F.Cu")
		(net "DEBUG_CARD_PRSNT")
	)
	(segment
		(start 94.3864 -117.3988)
		(end 93.5736 -117.3988)
		(width 0.127)
		(layer "F.Cu")
		(net "DEBUG_CARD_PRSNT")
	)
	(segment
		(start 93.5736 -117.3988)
		(end 93.3196 -117.1448)
		(width 0.127)
		(layer "F.Cu")
		(net "DEBUG_CARD_PRSNT")
	)
	(segment
		(start 96.585786 -123.01982)
		(end 95.6818 -122.115834)
		(width 0.127)
		(layer "F.Cu")
		(net "DEBUG_CARD_PRSNT")
	)
	(segment
		(start 86.560406 -132.038598)
		(end 86.597998 -132.038598)
		(width 0.127)
		(layer "F.Cu")
		(net "DEBUG_CARD_PRSNT")
	)
	(segment
		(start 86.597998 -132.038598)
		(end 86.741 -132.1816)
		(width 0.127)
		(layer "F.Cu")
		(net "DEBUG_CARD_PRSNT")
	)
	(segment
		(start 85.958172 -131.436364)
		(end 86.560406 -132.038598)
		(width 0.127)
		(layer "F.Cu")
		(net "DEBUG_CARD_PRSNT")
	)
	(segment
		(start 97.594166 -131.210558)
		(end 97.594166 -127.526288)
		(width 0.127)
		(layer "F.Cu")
		(net "DEBUG_CARD_PRSNT")
	)
	(segment
		(start 94.919546 -132.37464)
		(end 94.986602 -132.37464)
		(width 0.127)
		(layer "F.Cu")
		(net "DEBUG_CARD_PRSNT")
	)
	(segment
		(start 94.986602 -132.37464)
		(end 95.423228 -131.938014)
		(width 0.127)
		(layer "F.Cu")
		(net "DEBUG_CARD_PRSNT")
	)
	(segment
		(start 97.594166 -127.526288)
		(end 96.585786 -126.517908)
		(width 0.127)
		(layer "F.Cu")
		(net "DEBUG_CARD_PRSNT")
	)
	(segment
		(start 95.6818 -122.115834)
		(end 95.6818 -121.9962)
		(width 0.127)
		(layer "F.Cu")
		(net "DEBUG_CARD_PRSNT")
	)
	(segment
		(start 95.6818 -118.6942)
		(end 94.3864 -117.3988)
		(width 0.127)
		(layer "F.Cu")
		(net "DEBUG_CARD_PRSNT")
	)
	(segment
		(start 95.6818 -121.9962)
		(end 95.6818 -118.6942)
		(width 0.127)
		(layer "F.Cu")
		(net "DEBUG_CARD_PRSNT")
	)
	(segment
		(start 96.585786 -126.517908)
		(end 96.585786 -123.01982)
		(width 0.127)
		(layer "F.Cu")
		(net "DEBUG_CARD_PRSNT")
	)
	(segment
		(start 78.90129 -132.702554)
		(end 80.16748 -131.436364)
		(width 0.127)
		(layer "F.Cu")
		(net "DEBUG_CARD_PRSNT")
	)
	(segment
		(start 77.48778 -132.702554)
		(end 78.90129 -132.702554)
		(width 0.127)
		(layer "F.Cu")
		(net "DEBUG_CARD_PRSNT")
	)
	(segment
		(start 95.423228 -131.938014)
		(end 96.86671 -131.938014)
		(width 0.127)
		(layer "F.Cu")
		(net "DEBUG_CARD_PRSNT")
	)
	(segment
		(start 80.16748 -131.436364)
		(end 85.958172 -131.436364)
		(width 0.127)
		(layer "F.Cu")
		(net "DEBUG_CARD_PRSNT")
	)
	(via
		(at 95.6818 -121.9962)
		(size 0.6604)
		(drill 0.3302)
		(layers "F.Cu" "B.Cu")
		(net "DEBUG_CARD_PRSNT")
	)
	(via
		(at 86.741 -132.1816)
		(size 0.508)
		(drill 0.254)
		(layers "F.Cu" "B.Cu")
		(net "DEBUG_CARD_PRSNT")
	)
	(via
		(at 93.3196 -117.1448)
		(size 0.508)
		(drill 0.254)
		(layers "F.Cu" "B.Cu")
		(net "DEBUG_CARD_PRSNT")
	)
	(via
		(at 94.919546 -132.37464)
		(size 0.508)
		(drill 0.254)
		(layers "F.Cu" "B.Cu")
		(net "DEBUG_CARD_PRSNT")
	)
	(segment
		(start 93.2307 -137.3124)
		(end 93.2307 -138.92022)
		(width 0.127)
		(layer "B.Cu")
		(net "DEBUG_CARD_PRSNT")
	)
	(segment
		(start 93.566742 -139.256262)
		(end 93.566742 -140.546836)
		(width 0.127)
		(layer "B.Cu")
		(net "DEBUG_CARD_PRSNT")
	)
	(segment
		(start 93.735906 -140.716)
		(end 93.735906 -141.66596)
		(width 0.127)
		(layer "B.Cu")
		(net "DEBUG_CARD_PRSNT")
	)
	(segment
		(start 92.69222 -135.87984)
		(end 92.69222 -136.77392)
		(width 0.127)
		(layer "B.Cu")
		(net "DEBUG_CARD_PRSNT")
	)
	(segment
		(start 93.8149 -132.70484)
		(end 94.3864 -133.27634)
		(width 0.127)
		(layer "B.Cu")
		(net "DEBUG_CARD_PRSNT")
	)
	(segment
		(start 94.3864 -135.0645)
		(end 93.57106 -135.87984)
		(width 0.127)
		(layer "B.Cu")
		(net "DEBUG_CARD_PRSNT")
	)
	(segment
		(start 93.8149 -132.70484)
		(end 94.589346 -132.70484)
		(width 0.127)
		(layer "B.Cu")
		(net "DEBUG_CARD_PRSNT")
	)
	(segment
		(start 93.57106 -135.87984)
		(end 92.69222 -135.87984)
		(width 0.127)
		(layer "B.Cu")
		(net "DEBUG_CARD_PRSNT")
	)
	(segment
		(start 93.298264 -142.103602)
		(end 93.0529 -142.103602)
		(width 0.127)
		(layer "B.Cu")
		(net "DEBUG_CARD_PRSNT")
	)
	(segment
		(start 94.3864 -133.27634)
		(end 94.3864 -135.0645)
		(width 0.127)
		(layer "B.Cu")
		(net "DEBUG_CARD_PRSNT")
	)
	(segment
		(start 94.589346 -132.70484)
		(end 94.919546 -132.37464)
		(width 0.127)
		(layer "B.Cu")
		(net "DEBUG_CARD_PRSNT")
	)
	(segment
		(start 93.735906 -141.66596)
		(end 93.298264 -142.103602)
		(width 0.127)
		(layer "B.Cu")
		(net "DEBUG_CARD_PRSNT")
	)
	(segment
		(start 92.69222 -136.77392)
		(end 93.2307 -137.3124)
		(width 0.127)
		(layer "B.Cu")
		(net "DEBUG_CARD_PRSNT")
	)
	(segment
		(start 93.2307 -138.92022)
		(end 93.566742 -139.256262)
		(width 0.127)
		(layer "B.Cu")
		(net "DEBUG_CARD_PRSNT")
	)
	(segment
		(start 93.566742 -140.546836)
		(end 93.735906 -140.716)
		(width 0.127)
		(layer "B.Cu")
		(net "DEBUG_CARD_PRSNT")
	)
	(segment
		(start 82.92084 -21.820632)
		(end 82.92084 -40.472868)
		(width 0.127)
		(layer "In5.Cu")
		(net "DEBUG_CARD_PRSNT")
	)
	(segment
		(start 88.1888 -20.2184)
		(end 84.523072 -20.2184)
		(width 0.127)
		(layer "In5.Cu")
		(net "DEBUG_CARD_PRSNT")
	)
	(segment
		(start 90.69324 -132.37464)
		(end 90.17 -131.8514)
		(width 0.127)
		(layer "In5.Cu")
		(net "DEBUG_CARD_PRSNT")
	)
	(segment
		(start 80.098138 -59.59983)
		(end 82.279236 -61.780928)
		(width 0.127)
		(layer "In5.Cu")
		(net "DEBUG_CARD_PRSNT")
	)
	(segment
		(start 81.446878 -96.959166)
		(end 83.566 -99.078288)
		(width 0.127)
		(layer "In5.Cu")
		(net "DEBUG_CARD_PRSNT")
	)
	(segment
		(start 81.114138 -96.150938)
		(end 81.446878 -96.483678)
		(width 0.127)
		(layer "In5.Cu")
		(net "DEBUG_CARD_PRSNT")
	)
	(segment
		(start 81.446878 -96.483678)
		(end 81.446878 -96.959166)
		(width 0.127)
		(layer "In5.Cu")
		(net "DEBUG_CARD_PRSNT")
	)
	(segment
		(start 90.17 -131.8514)
		(end 87.0712 -131.8514)
		(width 0.127)
		(layer "In5.Cu")
		(net "DEBUG_CARD_PRSNT")
	)
	(segment
		(start 82.279236 -68.27139)
		(end 81.114138 -69.436488)
		(width 0.127)
		(layer "In5.Cu")
		(net "DEBUG_CARD_PRSNT")
	)
	(segment
		(start 84.523072 -20.2184)
		(end 82.92084 -21.820632)
		(width 0.127)
		(layer "In5.Cu")
		(net "DEBUG_CARD_PRSNT")
	)
	(segment
		(start 94.919546 -132.37464)
		(end 90.69324 -132.37464)
		(width 0.127)
		(layer "In5.Cu")
		(net "DEBUG_CARD_PRSNT")
	)
	(segment
		(start 87.0712 -131.8514)
		(end 86.741 -132.1816)
		(width 0.127)
		(layer "In5.Cu")
		(net "DEBUG_CARD_PRSNT")
	)
	(segment
		(start 82.279236 -61.780928)
		(end 82.279236 -68.27139)
		(width 0.127)
		(layer "In5.Cu")
		(net "DEBUG_CARD_PRSNT")
	)
	(segment
		(start 89.799922 -18.607278)
		(end 88.1888 -20.2184)
		(width 0.127)
		(layer "In5.Cu")
		(net "DEBUG_CARD_PRSNT")
	)
	(segment
		(start 93.1926 -109.03585)
		(end 93.1926 -117.0178)
		(width 0.127)
		(layer "In5.Cu")
		(net "DEBUG_CARD_PRSNT")
	)
	(segment
		(start 82.92084 -40.472868)
		(end 80.098138 -43.29557)
		(width 0.127)
		(layer "In5.Cu")
		(net "DEBUG_CARD_PRSNT")
	)
	(segment
		(start 83.566 -99.40925)
		(end 93.1926 -109.03585)
		(width 0.127)
		(layer "In5.Cu")
		(net "DEBUG_CARD_PRSNT")
	)
	(segment
		(start 89.799922 -17.979898)
		(end 89.799922 -18.607278)
		(width 0.127)
		(layer "In5.Cu")
		(net "DEBUG_CARD_PRSNT")
	)
	(segment
		(start 80.098138 -43.29557)
		(end 80.098138 -59.59983)
		(width 0.127)
		(layer "In5.Cu")
		(net "DEBUG_CARD_PRSNT")
	)
	(segment
		(start 93.1926 -117.0178)
		(end 93.3196 -117.1448)
		(width 0.127)
		(layer "In5.Cu")
		(net "DEBUG_CARD_PRSNT")
	)
	(segment
		(start 83.566 -99.078288)
		(end 83.566 -99.40925)
		(width 0.127)
		(layer "In5.Cu")
		(net "DEBUG_CARD_PRSNT")
	)
	(segment
		(start 81.114138 -69.436488)
		(end 81.114138 -96.150938)
		(width 0.127)
		(layer "In5.Cu")
		(net "DEBUG_CARD_PRSNT")
	)
	(segment
		(start 50.500026 -139.799822)
		(end 50.500026 -139.800076)
		(width 0.127)
		(layer "F.Cu")
		(net "SCC_RMT_TYPE_0_R")
	)
	(segment
		(start 50.899822 -139.400026)
		(end 50.500026 -139.799822)
		(width 0.127)
		(layer "F.Cu")
		(net "SCC_RMT_TYPE_0_R")
	)
	(via
		(at 53.848 -137.0584)
		(size 0.6096)
		(drill 0.3048)
		(layers "F.Cu" "B.Cu")
		(net "SCC_RMT_TYPE_0_R")
	)
	(via
		(at 50.899822 -139.400026)
		(size 0.4572)
		(drill 0.2032)
		(layers "F.Cu" "B.Cu")
		(net "SCC_RMT_TYPE_0_R")
	)
	(segment
		(start 53.67909 -138.777726)
		(end 53.6829 -138.777726)
		(width 0.127)
		(layer "B.Cu")
		(net "SCC_RMT_TYPE_0_R")
	)
	(segment
		(start 50.899822 -139.400026)
		(end 51.305714 -138.994134)
		(width 0.127)
		(layer "B.Cu")
		(net "SCC_RMT_TYPE_0_R")
	)
	(segment
		(start 53.382926 -138.993626)
		(end 53.46319 -138.993626)
		(width 0.127)
		(layer "B.Cu")
		(net "SCC_RMT_TYPE_0_R")
	)
	(segment
		(start 53.706014 -137.200386)
		(end 53.848 -137.0584)
		(width 0.127)
		(layer "B.Cu")
		(net "SCC_RMT_TYPE_0_R")
	)
	(segment
		(start 55.6768 -136.2837)
		(end 55.3212 -136.6393)
		(width 0.127)
		(layer "B.Cu")
		(net "SCC_RMT_TYPE_0_R")
	)
	(segment
		(start 55.3212 -136.6393)
		(end 54.2671 -136.6393)
		(width 0.127)
		(layer "B.Cu")
		(net "SCC_RMT_TYPE_0_R")
	)
	(segment
		(start 53.6829 -138.777726)
		(end 53.706268 -138.754358)
		(width 0.127)
		(layer "B.Cu")
		(net "SCC_RMT_TYPE_0_R")
	)
	(segment
		(start 53.706268 -137.963402)
		(end 53.706014 -137.963148)
		(width 0.127)
		(layer "B.Cu")
		(net "SCC_RMT_TYPE_0_R")
	)
	(segment
		(start 54.2671 -136.6393)
		(end 53.848 -137.0584)
		(width 0.127)
		(layer "B.Cu")
		(net "SCC_RMT_TYPE_0_R")
	)
	(segment
		(start 51.305714 -138.994134)
		(end 53.382418 -138.994134)
		(width 0.127)
		(layer "B.Cu")
		(net "SCC_RMT_TYPE_0_R")
	)
	(segment
		(start 53.46319 -138.993626)
		(end 53.67909 -138.777726)
		(width 0.127)
		(layer "B.Cu")
		(net "SCC_RMT_TYPE_0_R")
	)
	(segment
		(start 53.382418 -138.994134)
		(end 53.382926 -138.993626)
		(width 0.127)
		(layer "B.Cu")
		(net "SCC_RMT_TYPE_0_R")
	)
	(segment
		(start 53.706014 -137.963148)
		(end 53.706014 -137.200386)
		(width 0.127)
		(layer "B.Cu")
		(net "SCC_RMT_TYPE_0_R")
	)
	(segment
		(start 53.706268 -138.754358)
		(end 53.706268 -137.963402)
		(width 0.127)
		(layer "B.Cu")
		(net "SCC_RMT_TYPE_0_R")
	)
	(via
		(at 56.8706 -134.9248)
		(size 0.508)
		(drill 0.254)
		(layers "F.Cu" "B.Cu")
		(net "SCC_RMT_TYPE_0")
	)
	(via
		(at 99.118166 -129.080006)
		(size 0.508)
		(drill 0.254)
		(layers "F.Cu" "B.Cu")
		(net "SCC_RMT_TYPE_0")
	)
	(segment
		(start 56.8706 -134.9248)
		(end 56.4007 -135.3947)
		(width 0.127)
		(layer "B.Cu")
		(net "SCC_RMT_TYPE_0")
	)
	(segment
		(start 56.4007 -135.3947)
		(end 55.6768 -135.3947)
		(width 0.127)
		(layer "B.Cu")
		(net "SCC_RMT_TYPE_0")
	)
	(segment
		(start 99.423474 -113.63325)
		(end 99.423474 -123.006866)
		(width 0.127)
		(layer "In2.Cu")
		(net "SCC_RMT_TYPE_0")
	)
	(segment
		(start 106.51109 -29.185616)
		(end 104.1908 -31.505906)
		(width 0.127)
		(layer "In2.Cu")
		(net "SCC_RMT_TYPE_0")
	)
	(segment
		(start 104.1908 -31.505906)
		(end 104.1908 -40.691816)
		(width 0.127)
		(layer "In2.Cu")
		(net "SCC_RMT_TYPE_0")
	)
	(segment
		(start 98.977958 -45.904658)
		(end 98.977958 -83.52536)
		(width 0.127)
		(layer "In2.Cu")
		(net "SCC_RMT_TYPE_0")
	)
	(segment
		(start 98.631502 -112.841278)
		(end 99.423474 -113.63325)
		(width 0.127)
		(layer "In2.Cu")
		(net "SCC_RMT_TYPE_0")
	)
	(segment
		(start 112.132618 -29.185616)
		(end 106.51109 -29.185616)
		(width 0.127)
		(layer "In2.Cu")
		(net "SCC_RMT_TYPE_0")
	)
	(segment
		(start 98.864166 -123.566174)
		(end 98.864166 -128.826006)
		(width 0.127)
		(layer "In2.Cu")
		(net "SCC_RMT_TYPE_0")
	)
	(segment
		(start 113.596928 -39.696898)
		(end 113.596928 -30.649926)
		(width 0.127)
		(layer "In2.Cu")
		(net "SCC_RMT_TYPE_0")
	)
	(segment
		(start 104.1908 -40.691816)
		(end 98.977958 -45.904658)
		(width 0.127)
		(layer "In2.Cu")
		(net "SCC_RMT_TYPE_0")
	)
	(segment
		(start 98.631502 -83.871816)
		(end 98.631502 -112.841278)
		(width 0.127)
		(layer "In2.Cu")
		(net "SCC_RMT_TYPE_0")
	)
	(segment
		(start 114.3 -40.39997)
		(end 113.596928 -39.696898)
		(width 0.127)
		(layer "In2.Cu")
		(net "SCC_RMT_TYPE_0")
	)
	(segment
		(start 99.423474 -123.006866)
		(end 98.864166 -123.566174)
		(width 0.127)
		(layer "In2.Cu")
		(net "SCC_RMT_TYPE_0")
	)
	(segment
		(start 113.596928 -30.649926)
		(end 112.132618 -29.185616)
		(width 0.127)
		(layer "In2.Cu")
		(net "SCC_RMT_TYPE_0")
	)
	(segment
		(start 98.977958 -83.52536)
		(end 98.631502 -83.871816)
		(width 0.127)
		(layer "In2.Cu")
		(net "SCC_RMT_TYPE_0")
	)
	(segment
		(start 98.864166 -128.826006)
		(end 99.118166 -129.080006)
		(width 0.127)
		(layer "In2.Cu")
		(net "SCC_RMT_TYPE_0")
	)
	(segment
		(start 63.063882 -133.4262)
		(end 64.521588 -133.4262)
		(width 0.127)
		(layer "In5.Cu")
		(net "SCC_RMT_TYPE_0")
	)
	(segment
		(start 74.158856 -133.37032)
		(end 79.686658 -133.37032)
		(width 0.127)
		(layer "In5.Cu")
		(net "SCC_RMT_TYPE_0")
	)
	(segment
		(start 86.913212 -131.4704)
		(end 90.327988 -131.4704)
		(width 0.127)
		(layer "In5.Cu")
		(net "SCC_RMT_TYPE_0")
	)
	(segment
		(start 86.130892 -131.547108)
		(end 86.836504 -131.547108)
		(width 0.127)
		(layer "In5.Cu")
		(net "SCC_RMT_TYPE_0")
	)
	(segment
		(start 63.051182 -133.4389)
		(end 63.063882 -133.4262)
		(width 0.127)
		(layer "In5.Cu")
		(net "SCC_RMT_TYPE_0")
	)
	(segment
		(start 57.880758 -134.9248)
		(end 59.366658 -133.4389)
		(width 0.127)
		(layer "In5.Cu")
		(net "SCC_RMT_TYPE_0")
	)
	(segment
		(start 66.068194 -132.3975)
		(end 66.13652 -132.329174)
		(width 0.127)
		(layer "In5.Cu")
		(net "SCC_RMT_TYPE_0")
	)
	(segment
		(start 56.8706 -134.9248)
		(end 57.880758 -134.9248)
		(width 0.127)
		(layer "In5.Cu")
		(net "SCC_RMT_TYPE_0")
	)
	(segment
		(start 94.189804 -131.547108)
		(end 96.59493 -129.141982)
		(width 0.127)
		(layer "In5.Cu")
		(net "SCC_RMT_TYPE_0")
	)
	(segment
		(start 73.11771 -132.329174)
		(end 74.158856 -133.37032)
		(width 0.127)
		(layer "In5.Cu")
		(net "SCC_RMT_TYPE_0")
	)
	(segment
		(start 59.366658 -133.4389)
		(end 63.051182 -133.4389)
		(width 0.127)
		(layer "In5.Cu")
		(net "SCC_RMT_TYPE_0")
	)
	(segment
		(start 99.05619 -129.141982)
		(end 99.118166 -129.080006)
		(width 0.127)
		(layer "In5.Cu")
		(net "SCC_RMT_TYPE_0")
	)
	(segment
		(start 80.275684 -132.781294)
		(end 84.896706 -132.781294)
		(width 0.127)
		(layer "In5.Cu")
		(net "SCC_RMT_TYPE_0")
	)
	(segment
		(start 66.13652 -132.329174)
		(end 73.11771 -132.329174)
		(width 0.127)
		(layer "In5.Cu")
		(net "SCC_RMT_TYPE_0")
	)
	(segment
		(start 90.404696 -131.547108)
		(end 94.189804 -131.547108)
		(width 0.127)
		(layer "In5.Cu")
		(net "SCC_RMT_TYPE_0")
	)
	(segment
		(start 96.59493 -129.141982)
		(end 99.05619 -129.141982)
		(width 0.127)
		(layer "In5.Cu")
		(net "SCC_RMT_TYPE_0")
	)
	(segment
		(start 84.896706 -132.781294)
		(end 86.130892 -131.547108)
		(width 0.127)
		(layer "In5.Cu")
		(net "SCC_RMT_TYPE_0")
	)
	(segment
		(start 65.550288 -132.3975)
		(end 66.068194 -132.3975)
		(width 0.127)
		(layer "In5.Cu")
		(net "SCC_RMT_TYPE_0")
	)
	(segment
		(start 79.686658 -133.37032)
		(end 80.275684 -132.781294)
		(width 0.127)
		(layer "In5.Cu")
		(net "SCC_RMT_TYPE_0")
	)
	(segment
		(start 64.521588 -133.4262)
		(end 65.550288 -132.3975)
		(width 0.127)
		(layer "In5.Cu")
		(net "SCC_RMT_TYPE_0")
	)
	(segment
		(start 90.327988 -131.4704)
		(end 90.404696 -131.547108)
		(width 0.127)
		(layer "In5.Cu")
		(net "SCC_RMT_TYPE_0")
	)
	(segment
		(start 86.836504 -131.547108)
		(end 86.913212 -131.4704)
		(width 0.127)
		(layer "In5.Cu")
		(net "SCC_RMT_TYPE_0")
	)
	(segment
		(start 97.256346 -145.579846)
		(end 98.1075 -146.431)
		(width 0.127)
		(layer "F.Cu")
		(net "I2C_DEBUG_SDA_R")
	)
	(segment
		(start 95.996506 -145.579846)
		(end 97.256346 -145.579846)
		(width 0.127)
		(layer "F.Cu")
		(net "I2C_DEBUG_SDA_R")
	)
	(segment
		(start 92.077032 -14.986508)
		(end 90.793316 -14.986508)
		(width 0.127)
		(layer "F.Cu")
		(net "I2C_DEBUG_SDA")
	)
	(segment
		(start 90.793316 -14.986508)
		(end 89.799922 -15.979902)
		(width 0.127)
		(layer "F.Cu")
		(net "I2C_DEBUG_SDA")
	)
	(segment
		(start 94.365572 -13.671042)
		(end 93.392498 -13.671042)
		(width 0.127)
		(layer "F.Cu")
		(net "I2C_DEBUG_SDA")
	)
	(segment
		(start 80.73898 -134.653274)
		(end 81.485994 -134.653274)
		(width 0.127)
		(layer "F.Cu")
		(net "I2C_DEBUG_SDA")
	)
	(segment
		(start 81.485994 -134.653274)
		(end 81.80324 -134.97052)
		(width 0.127)
		(layer "F.Cu")
		(net "I2C_DEBUG_SDA")
	)
	(segment
		(start 93.392498 -13.671042)
		(end 92.077032 -14.986508)
		(width 0.127)
		(layer "F.Cu")
		(net "I2C_DEBUG_SDA")
	)
	(segment
		(start 82.513424 -135.446516)
		(end 82.002122 -135.446516)
		(width 0.127)
		(layer "F.Cu")
		(net "I2C_DEBUG_SDA")
	)
	(segment
		(start 94.365572 -13.671042)
		(end 94.365572 -13.7922)
		(width 0.127)
		(layer "F.Cu")
		(net "I2C_DEBUG_SDA")
	)
	(segment
		(start 94.365572 -13.7922)
		(end 93.486986 -14.670786)
		(width 0.127)
		(layer "F.Cu")
		(net "I2C_DEBUG_SDA")
	)
	(segment
		(start 81.80324 -134.97052)
		(end 82.98942 -134.97052)
		(width 0.127)
		(layer "F.Cu")
		(net "I2C_DEBUG_SDA")
	)
	(segment
		(start 82.98942 -134.97052)
		(end 82.513424 -135.446516)
		(width 0.127)
		(layer "F.Cu")
		(net "I2C_DEBUG_SDA")
	)
	(via
		(at 71.034656 -136.010142)
		(size 0.508)
		(drill 0.254)
		(layers "F.Cu" "B.Cu")
		(net "I2C_DEBUG_SDA")
	)
	(via
		(at 86.3346 -115.3668)
		(size 0.6096)
		(drill 0.3048)
		(layers "F.Cu" "B.Cu")
		(net "I2C_DEBUG_SDA")
	)
	(via
		(at 92.583 -115.2398)
		(size 0.508)
		(drill 0.254)
		(layers "F.Cu" "B.Cu")
		(net "I2C_DEBUG_SDA")
	)
	(via
		(at 82.002122 -135.446516)
		(size 0.508)
		(drill 0.254)
		(layers "F.Cu" "B.Cu")
		(net "I2C_DEBUG_SDA")
	)
	(via
		(at 71.7296 -119.4308)
		(size 0.508)
		(drill 0.254)
		(layers "F.Cu" "B.Cu")
		(net "I2C_DEBUG_SDA")
	)
	(via
		(at 93.486986 -14.670786)
		(size 0.508)
		(drill 0.254)
		(layers "F.Cu" "B.Cu")
		(net "I2C_DEBUG_SDA")
	)
	(segment
		(start 86.7156 -115.7478)
		(end 92.075 -115.7478)
		(width 0.127)
		(layer "B.Cu")
		(net "I2C_DEBUG_SDA")
	)
	(segment
		(start 92.075 -115.7478)
		(end 92.583 -115.2398)
		(width 0.127)
		(layer "B.Cu")
		(net "I2C_DEBUG_SDA")
	)
	(segment
		(start 77.353414 -113.611914)
		(end 84.579714 -113.611914)
		(width 0.127)
		(layer "B.Cu")
		(net "I2C_DEBUG_SDA")
	)
	(segment
		(start 71.7296 -119.4308)
		(end 72.673972 -118.486428)
		(width 0.127)
		(layer "B.Cu")
		(net "I2C_DEBUG_SDA")
	)
	(segment
		(start 77.274928 -113.6904)
		(end 77.353414 -113.611914)
		(width 0.127)
		(layer "B.Cu")
		(net "I2C_DEBUG_SDA")
	)
	(segment
		(start 72.673972 -118.486428)
		(end 72.673972 -118.283736)
		(width 0.127)
		(layer "B.Cu")
		(net "I2C_DEBUG_SDA")
	)
	(segment
		(start 72.673972 -118.283736)
		(end 77.267308 -113.6904)
		(width 0.127)
		(layer "B.Cu")
		(net "I2C_DEBUG_SDA")
	)
	(segment
		(start 84.579714 -113.611914)
		(end 86.3346 -115.3668)
		(width 0.127)
		(layer "B.Cu")
		(net "I2C_DEBUG_SDA")
	)
	(segment
		(start 77.267308 -113.6904)
		(end 77.274928 -113.6904)
		(width 0.127)
		(layer "B.Cu")
		(net "I2C_DEBUG_SDA")
	)
	(segment
		(start 86.3346 -115.3668)
		(end 86.7156 -115.7478)
		(width 0.127)
		(layer "B.Cu")
		(net "I2C_DEBUG_SDA")
	)
	(segment
		(start 71.112888 -120.047512)
		(end 71.7296 -119.4308)
		(width 0.127)
		(layer "In2.Cu")
		(net "I2C_DEBUG_SDA")
	)
	(segment
		(start 71.828406 -129.095754)
		(end 71.828406 -126.452122)
		(width 0.127)
		(layer "In2.Cu")
		(net "I2C_DEBUG_SDA")
	)
	(segment
		(start 70.604126 -130.320034)
		(end 71.828406 -129.095754)
		(width 0.127)
		(layer "In2.Cu")
		(net "I2C_DEBUG_SDA")
	)
	(segment
		(start 71.112888 -125.736604)
		(end 71.112888 -120.047512)
		(width 0.127)
		(layer "In2.Cu")
		(net "I2C_DEBUG_SDA")
	)
	(segment
		(start 71.034656 -136.010142)
		(end 71.034656 -135.931656)
		(width 0.127)
		(layer "In2.Cu")
		(net "I2C_DEBUG_SDA")
	)
	(segment
		(start 71.828406 -126.452122)
		(end 71.112888 -125.736604)
		(width 0.127)
		(layer "In2.Cu")
		(net "I2C_DEBUG_SDA")
	)
	(segment
		(start 71.034656 -135.931656)
		(end 70.8406 -135.7376)
		(width 0.127)
		(layer "In2.Cu")
		(net "I2C_DEBUG_SDA")
	)
	(segment
		(start 70.604126 -135.447024)
		(end 70.604126 -130.320034)
		(width 0.127)
		(layer "In2.Cu")
		(net "I2C_DEBUG_SDA")
	)
	(segment
		(start 70.8406 -135.683498)
		(end 70.604126 -135.447024)
		(width 0.127)
		(layer "In2.Cu")
		(net "I2C_DEBUG_SDA")
	)
	(segment
		(start 70.8406 -135.7376)
		(end 70.8406 -135.683498)
		(width 0.127)
		(layer "In2.Cu")
		(net "I2C_DEBUG_SDA")
	)
	(segment
		(start 79.585058 -97.578926)
		(end 79.585058 -43.090084)
		(width 0.127)
		(layer "In5.Cu")
		(net "I2C_DEBUG_SDA")
	)
	(segment
		(start 81.482184 -99.476052)
		(end 79.585058 -97.578926)
		(width 0.127)
		(layer "In5.Cu")
		(net "I2C_DEBUG_SDA")
	)
	(segment
		(start 92.6846 -115.1382)
		(end 92.6846 -109.761782)
		(width 0.127)
		(layer "In5.Cu")
		(net "I2C_DEBUG_SDA")
	)
	(segment
		(start 81.192116 -136.256522)
		(end 82.002122 -135.446516)
		(width 0.127)
		(layer "In5.Cu")
		(net "I2C_DEBUG_SDA")
	)
	(segment
		(start 82.39887 -99.476052)
		(end 81.482184 -99.476052)
		(width 0.127)
		(layer "In5.Cu")
		(net "I2C_DEBUG_SDA")
	)
	(segment
		(start 79.585058 -43.090084)
		(end 82.327242 -40.3479)
		(width 0.127)
		(layer "In5.Cu")
		(net "I2C_DEBUG_SDA")
	)
	(segment
		(start 73.0377 -135.846058)
		(end 73.448164 -136.256522)
		(width 0.127)
		(layer "In5.Cu")
		(net "I2C_DEBUG_SDA")
	)
	(segment
		(start 85.092032 -10.0457)
		(end 92.4941 -10.0457)
		(width 0.127)
		(layer "In5.Cu")
		(net "I2C_DEBUG_SDA")
	)
	(segment
		(start 92.583 -115.2398)
		(end 92.6846 -115.1382)
		(width 0.127)
		(layer "In5.Cu")
		(net "I2C_DEBUG_SDA")
	)
	(segment
		(start 92.4941 -10.0457)
		(end 93.486986 -11.038586)
		(width 0.127)
		(layer "In5.Cu")
		(net "I2C_DEBUG_SDA")
	)
	(segment
		(start 73.448164 -136.256522)
		(end 81.192116 -136.256522)
		(width 0.127)
		(layer "In5.Cu")
		(net "I2C_DEBUG_SDA")
	)
	(segment
		(start 93.486986 -11.038586)
		(end 93.486986 -14.670786)
		(width 0.127)
		(layer "In5.Cu")
		(net "I2C_DEBUG_SDA")
	)
	(segment
		(start 92.6846 -109.761782)
		(end 82.39887 -99.476052)
		(width 0.127)
		(layer "In5.Cu")
		(net "I2C_DEBUG_SDA")
	)
	(segment
		(start 71.19874 -135.846058)
		(end 73.0377 -135.846058)
		(width 0.127)
		(layer "In5.Cu")
		(net "I2C_DEBUG_SDA")
	)
	(segment
		(start 71.034656 -136.010142)
		(end 71.19874 -135.846058)
		(width 0.127)
		(layer "In5.Cu")
		(net "I2C_DEBUG_SDA")
	)
	(segment
		(start 82.327242 -12.81049)
		(end 85.092032 -10.0457)
		(width 0.127)
		(layer "In5.Cu")
		(net "I2C_DEBUG_SDA")
	)
	(segment
		(start 82.327242 -40.3479)
		(end 82.327242 -12.81049)
		(width 0.127)
		(layer "In5.Cu")
		(net "I2C_DEBUG_SDA")
	)
	(segment
		(start 95.996506 -144.929606)
		(end 97.622106 -144.929606)
		(width 0.127)
		(layer "F.Cu")
		(net "I2C_DEBUG_SCL_R")
	)
	(segment
		(start 97.622106 -144.929606)
		(end 98.1075 -145.415)
		(width 0.127)
		(layer "F.Cu")
		(net "I2C_DEBUG_SCL_R")
	)
	(segment
		(start 82.296 -134.46252)
		(end 82.013806 -134.46252)
		(width 0.127)
		(layer "F.Cu")
		(net "I2C_DEBUG_SCL")
	)
	(segment
		(start 94.365572 -11.748262)
		(end 94.20098 -11.58367)
		(width 0.127)
		(layer "F.Cu")
		(net "I2C_DEBUG_SCL")
	)
	(segment
		(start 81.577942 -133.934454)
		(end 81.509362 -134.003034)
		(width 0.127)
		(layer "F.Cu")
		(net "I2C_DEBUG_SCL")
	)
	(segment
		(start 83.076034 -133.682486)
		(end 82.296 -134.46252)
		(width 0.127)
		(layer "F.Cu")
		(net "I2C_DEBUG_SCL")
	)
	(segment
		(start 83.076034 -133.682486)
		(end 82.136996 -133.682486)
		(width 0.127)
		(layer "F.Cu")
		(net "I2C_DEBUG_SCL")
	)
	(segment
		(start 92.163392 -13.979906)
		(end 89.799922 -13.979906)
		(width 0.127)
		(layer "F.Cu")
		(net "I2C_DEBUG_SCL")
	)
	(segment
		(start 81.509362 -134.003034)
		(end 80.73898 -134.003034)
		(width 0.127)
		(layer "F.Cu")
		(net "I2C_DEBUG_SCL")
	)
	(segment
		(start 94.365572 -12.502642)
		(end 93.640656 -12.502642)
		(width 0.127)
		(layer "F.Cu")
		(net "I2C_DEBUG_SCL")
	)
	(segment
		(start 93.640656 -12.502642)
		(end 92.163392 -13.979906)
		(width 0.127)
		(layer "F.Cu")
		(net "I2C_DEBUG_SCL")
	)
	(segment
		(start 94.365572 -12.502642)
		(end 94.365572 -11.748262)
		(width 0.127)
		(layer "F.Cu")
		(net "I2C_DEBUG_SCL")
	)
	(segment
		(start 82.136996 -133.682486)
		(end 81.885028 -133.934454)
		(width 0.127)
		(layer "F.Cu")
		(net "I2C_DEBUG_SCL")
	)
	(segment
		(start 81.885028 -133.934454)
		(end 81.577942 -133.934454)
		(width 0.127)
		(layer "F.Cu")
		(net "I2C_DEBUG_SCL")
	)
	(via
		(at 71.1454 -135.1534)
		(size 0.508)
		(drill 0.254)
		(layers "F.Cu" "B.Cu")
		(net "I2C_DEBUG_SCL")
	)
	(via
		(at 82.013806 -134.46252)
		(size 0.508)
		(drill 0.254)
		(layers "F.Cu" "B.Cu")
		(net "I2C_DEBUG_SCL")
	)
	(via
		(at 71.730362 -120.523)
		(size 0.508)
		(drill 0.254)
		(layers "F.Cu" "B.Cu")
		(net "I2C_DEBUG_SCL")
	)
	(via
		(at 94.20098 -11.58367)
		(size 0.508)
		(drill 0.254)
		(layers "F.Cu" "B.Cu")
		(net "I2C_DEBUG_SCL")
	)
	(via
		(at 93.2053 -118.0338)
		(size 0.508)
		(drill 0.254)
		(layers "F.Cu" "B.Cu")
		(net "I2C_DEBUG_SCL")
	)
	(segment
		(start 73.253346 -118.851172)
		(end 73.2536 -118.851426)
		(width 0.127)
		(layer "B.Cu")
		(net "I2C_DEBUG_SCL")
	)
	(segment
		(start 93.2053 -118.0338)
		(end 93.2053 -118.2751)
		(width 0.127)
		(layer "B.Cu")
		(net "I2C_DEBUG_SCL")
	)
	(segment
		(start 71.762874 -120.523)
		(end 71.730362 -120.523)
		(width 0.127)
		(layer "B.Cu")
		(net "I2C_DEBUG_SCL")
	)
	(segment
		(start 73.2536 -118.422674)
		(end 73.2536 -118.430294)
		(width 0.127)
		(layer "B.Cu")
		(net "I2C_DEBUG_SCL")
	)
	(segment
		(start 92.6592 -118.8212)
		(end 88.5444 -118.8212)
		(width 0.127)
		(layer "B.Cu")
		(net "I2C_DEBUG_SCL")
	)
	(segment
		(start 93.2053 -118.2751)
		(end 92.6592 -118.8212)
		(width 0.127)
		(layer "B.Cu")
		(net "I2C_DEBUG_SCL")
	)
	(segment
		(start 73.253346 -118.430548)
		(end 73.253346 -118.851172)
		(width 0.127)
		(layer "B.Cu")
		(net "I2C_DEBUG_SCL")
	)
	(segment
		(start 77.56398 -114.119914)
		(end 77.485494 -114.1984)
		(width 0.127)
		(layer "B.Cu")
		(net "I2C_DEBUG_SCL")
	)
	(segment
		(start 73.2536 -118.430294)
		(end 73.253346 -118.430548)
		(width 0.127)
		(layer "B.Cu")
		(net "I2C_DEBUG_SCL")
	)
	(segment
		(start 73.2536 -119.032274)
		(end 71.762874 -120.523)
		(width 0.127)
		(layer "B.Cu")
		(net "I2C_DEBUG_SCL")
	)
	(segment
		(start 83.843114 -114.119914)
		(end 77.56398 -114.119914)
		(width 0.127)
		(layer "B.Cu")
		(net "I2C_DEBUG_SCL")
	)
	(segment
		(start 77.477874 -114.1984)
		(end 73.2536 -118.422674)
		(width 0.127)
		(layer "B.Cu")
		(net "I2C_DEBUG_SCL")
	)
	(segment
		(start 88.5444 -118.8212)
		(end 83.843114 -114.119914)
		(width 0.127)
		(layer "B.Cu")
		(net "I2C_DEBUG_SCL")
	)
	(segment
		(start 73.2536 -118.851426)
		(end 73.2536 -119.032274)
		(width 0.127)
		(layer "B.Cu")
		(net "I2C_DEBUG_SCL")
	)
	(segment
		(start 77.485494 -114.1984)
		(end 77.477874 -114.1984)
		(width 0.127)
		(layer "B.Cu")
		(net "I2C_DEBUG_SCL")
	)
	(segment
		(start 71.112126 -135.120126)
		(end 71.112126 -130.5306)
		(width 0.127)
		(layer "In2.Cu")
		(net "I2C_DEBUG_SCL")
	)
	(segment
		(start 71.621142 -120.63222)
		(end 71.730362 -120.523)
		(width 0.127)
		(layer "In2.Cu")
		(net "I2C_DEBUG_SCL")
	)
	(segment
		(start 71.112126 -130.5306)
		(end 72.336406 -129.30632)
		(width 0.127)
		(layer "In2.Cu")
		(net "I2C_DEBUG_SCL")
	)
	(segment
		(start 72.336406 -129.30632)
		(end 72.336406 -126.241556)
		(width 0.127)
		(layer "In2.Cu")
		(net "I2C_DEBUG_SCL")
	)
	(segment
		(start 72.336406 -126.241556)
		(end 71.621142 -125.526292)
		(width 0.127)
		(layer "In2.Cu")
		(net "I2C_DEBUG_SCL")
	)
	(segment
		(start 71.621142 -125.526292)
		(end 71.621142 -120.63222)
		(width 0.127)
		(layer "In2.Cu")
		(net "I2C_DEBUG_SCL")
	)
	(segment
		(start 71.1454 -135.1534)
		(end 71.112126 -135.120126)
		(width 0.127)
		(layer "In2.Cu")
		(net "I2C_DEBUG_SCL")
	)
	(segment
		(start 79.077058 -42.879518)
		(end 81.819242 -40.137334)
		(width 0.127)
		(layer "In5.Cu")
		(net "I2C_DEBUG_SCL")
	)
	(segment
		(start 92.0496 -116.8781)
		(end 92.0496 -109.845348)
		(width 0.127)
		(layer "In5.Cu")
		(net "I2C_DEBUG_SCL")
	)
	(segment
		(start 81.922366 -134.46252)
		(end 80.636364 -135.748522)
		(width 0.127)
		(layer "In5.Cu")
		(net "I2C_DEBUG_SCL")
	)
	(segment
		(start 73.65873 -135.748522)
		(end 73.231248 -135.32104)
		(width 0.127)
		(layer "In5.Cu")
		(net "I2C_DEBUG_SCL")
	)
	(segment
		(start 81.819242 -40.137334)
		(end 81.819242 -12.599924)
		(width 0.127)
		(layer "In5.Cu")
		(net "I2C_DEBUG_SCL")
	)
	(segment
		(start 92.0496 -109.845348)
		(end 82.188304 -99.984052)
		(width 0.127)
		(layer "In5.Cu")
		(net "I2C_DEBUG_SCL")
	)
	(segment
		(start 82.188304 -99.984052)
		(end 81.271618 -99.984052)
		(width 0.127)
		(layer "In5.Cu")
		(net "I2C_DEBUG_SCL")
	)
	(segment
		(start 81.819242 -12.599924)
		(end 84.881466 -9.5377)
		(width 0.127)
		(layer "In5.Cu")
		(net "I2C_DEBUG_SCL")
	)
	(segment
		(start 71.31304 -135.32104)
		(end 71.1454 -135.1534)
		(width 0.127)
		(layer "In5.Cu")
		(net "I2C_DEBUG_SCL")
	)
	(segment
		(start 82.013806 -134.46252)
		(end 81.922366 -134.46252)
		(width 0.127)
		(layer "In5.Cu")
		(net "I2C_DEBUG_SCL")
	)
	(segment
		(start 79.077058 -97.789492)
		(end 79.077058 -42.879518)
		(width 0.127)
		(layer "In5.Cu")
		(net "I2C_DEBUG_SCL")
	)
	(segment
		(start 81.271618 -99.984052)
		(end 79.077058 -97.789492)
		(width 0.127)
		(layer "In5.Cu")
		(net "I2C_DEBUG_SCL")
	)
	(segment
		(start 84.881466 -9.5377)
		(end 92.8243 -9.5377)
		(width 0.127)
		(layer "In5.Cu")
		(net "I2C_DEBUG_SCL")
	)
	(segment
		(start 93.2053 -118.0338)
		(end 92.0496 -116.8781)
		(width 0.127)
		(layer "In5.Cu")
		(net "I2C_DEBUG_SCL")
	)
	(segment
		(start 73.231248 -135.32104)
		(end 71.31304 -135.32104)
		(width 0.127)
		(layer "In5.Cu")
		(net "I2C_DEBUG_SCL")
	)
	(segment
		(start 80.636364 -135.748522)
		(end 73.65873 -135.748522)
		(width 0.127)
		(layer "In5.Cu")
		(net "I2C_DEBUG_SCL")
	)
	(segment
		(start 94.20098 -10.91438)
		(end 94.20098 -11.58367)
		(width 0.127)
		(layer "In5.Cu")
		(net "I2C_DEBUG_SCL")
	)
	(segment
		(start 92.8243 -9.5377)
		(end 94.20098 -10.91438)
		(width 0.127)
		(layer "In5.Cu")
		(net "I2C_DEBUG_SCL")
	)
	(via
		(at 83.1342 -166.4462)
		(size 0.6096)
		(drill 0.3048)
		(layers "F.Cu" "B.Cu")
		(net "UART_SDB_TX")
	)
	(via
		(at 84.256372 -166.581328)
		(size 0.508)
		(drill 0.254)
		(layers "F.Cu" "B.Cu")
		(net "UART_SDB_TX")
	)
	(segment
		(start 80.146144 -166.925244)
		(end 80.146144 -165.816788)
		(width 0.127)
		(layer "B.Cu")
		(net "UART_SDB_TX")
	)
	(segment
		(start 82.508344 -165.816788)
		(end 82.508344 -165.820344)
		(width 0.127)
		(layer "B.Cu")
		(net "UART_SDB_TX")
	)
	(segment
		(start 83.269328 -166.581328)
		(end 84.256372 -166.581328)
		(width 0.127)
		(layer "B.Cu")
		(net "UART_SDB_TX")
	)
	(segment
		(start 82.508344 -165.820344)
		(end 83.1342 -166.4462)
		(width 0.127)
		(layer "B.Cu")
		(net "UART_SDB_TX")
	)
	(segment
		(start 80.480916 -165.482016)
		(end 82.173572 -165.482016)
		(width 0.127)
		(layer "B.Cu")
		(net "UART_SDB_TX")
	)
	(segment
		(start 82.173572 -165.482016)
		(end 82.508344 -165.816788)
		(width 0.127)
		(layer "B.Cu")
		(net "UART_SDB_TX")
	)
	(segment
		(start 80.3783 -167.1574)
		(end 80.146144 -166.925244)
		(width 0.127)
		(layer "B.Cu")
		(net "UART_SDB_TX")
	)
	(segment
		(start 80.146144 -165.816788)
		(end 80.480916 -165.482016)
		(width 0.127)
		(layer "B.Cu")
		(net "UART_SDB_TX")
	)
	(segment
		(start 83.1342 -166.4462)
		(end 83.269328 -166.581328)
		(width 0.127)
		(layer "B.Cu")
		(net "UART_SDB_TX")
	)
	(segment
		(start 95.675958 -52.660042)
		(end 94.638114 -53.697886)
		(width 0.127)
		(layer "In2.Cu")
		(net "UART_SDB_TX")
	)
	(segment
		(start 92.877132 -96.181418)
		(end 92.877132 -114.132868)
		(width 0.127)
		(layer "In2.Cu")
		(net "UART_SDB_TX")
	)
	(segment
		(start 91.7702 -127.43688)
		(end 91.7702 -127.918718)
		(width 0.127)
		(layer "In2.Cu")
		(net "UART_SDB_TX")
	)
	(segment
		(start 90.62466 -140.553694)
		(end 90.62466 -143.736568)
		(width 0.127)
		(layer "In2.Cu")
		(net "UART_SDB_TX")
	)
	(segment
		(start 94.638114 -53.697886)
		(end 94.638114 -94.420436)
		(width 0.127)
		(layer "In2.Cu")
		(net "UART_SDB_TX")
	)
	(segment
		(start 130.499866 -39.200074)
		(end 129.928366 -38.628574)
		(width 0.127)
		(layer "In2.Cu")
		(net "UART_SDB_TX")
	)
	(segment
		(start 91.4273 -128.261618)
		(end 91.4273 -138.191494)
		(width 0.127)
		(layer "In2.Cu")
		(net "UART_SDB_TX")
	)
	(segment
		(start 91.375992 -122.02414)
		(end 91.375992 -127.042672)
		(width 0.127)
		(layer "In2.Cu")
		(net "UART_SDB_TX")
	)
	(segment
		(start 91.4273 -138.191494)
		(end 90.962226 -138.656568)
		(width 0.127)
		(layer "In2.Cu")
		(net "UART_SDB_TX")
	)
	(segment
		(start 91.215718 -119.638318)
		(end 91.68384 -120.10644)
		(width 0.127)
		(layer "In2.Cu")
		(net "UART_SDB_TX")
	)
	(segment
		(start 91.68384 -120.10644)
		(end 91.68384 -121.716292)
		(width 0.127)
		(layer "In2.Cu")
		(net "UART_SDB_TX")
	)
	(segment
		(start 90.962226 -138.656568)
		(end 90.962226 -140.216128)
		(width 0.127)
		(layer "In2.Cu")
		(net "UART_SDB_TX")
	)
	(segment
		(start 91.9734 -115.6208)
		(end 91.215718 -116.378482)
		(width 0.127)
		(layer "In2.Cu")
		(net "UART_SDB_TX")
	)
	(segment
		(start 84.684616 -166.581328)
		(end 84.256372 -166.581328)
		(width 0.127)
		(layer "In2.Cu")
		(net "UART_SDB_TX")
	)
	(segment
		(start 116.694458 -22.563836)
		(end 110.892844 -22.563836)
		(width 0.127)
		(layer "In2.Cu")
		(net "UART_SDB_TX")
	)
	(segment
		(start 88.8619 -159.621474)
		(end 86.9823 -161.501074)
		(width 0.127)
		(layer "In2.Cu")
		(net "UART_SDB_TX")
	)
	(segment
		(start 91.375992 -127.042672)
		(end 91.7702 -127.43688)
		(width 0.127)
		(layer "In2.Cu")
		(net "UART_SDB_TX")
	)
	(segment
		(start 90.62466 -143.736568)
		(end 89.940638 -144.42059)
		(width 0.127)
		(layer "In2.Cu")
		(net "UART_SDB_TX")
	)
	(segment
		(start 86.3473 -163.085526)
		(end 86.2076 -163.225226)
		(width 0.127)
		(layer "In2.Cu")
		(net "UART_SDB_TX")
	)
	(segment
		(start 102.894638 -23.806658)
		(end 102.894638 -23.806912)
		(width 0.127)
		(layer "In2.Cu")
		(net "UART_SDB_TX")
	)
	(segment
		(start 86.9823 -161.997644)
		(end 86.3473 -162.632644)
		(width 0.127)
		(layer "In2.Cu")
		(net "UART_SDB_TX")
	)
	(segment
		(start 110.256574 -23.200106)
		(end 103.50119 -23.200106)
		(width 0.127)
		(layer "In2.Cu")
		(net "UART_SDB_TX")
	)
	(segment
		(start 129.928366 -31.621984)
		(end 125.177804 -26.871422)
		(width 0.127)
		(layer "In2.Cu")
		(net "UART_SDB_TX")
	)
	(segment
		(start 121.002044 -26.871422)
		(end 116.694458 -22.563836)
		(width 0.127)
		(layer "In2.Cu")
		(net "UART_SDB_TX")
	)
	(segment
		(start 88.001856 -147.471638)
		(end 88.001856 -149.187408)
		(width 0.127)
		(layer "In2.Cu")
		(net "UART_SDB_TX")
	)
	(segment
		(start 92.877132 -114.132868)
		(end 91.9734 -115.0366)
		(width 0.127)
		(layer "In2.Cu")
		(net "UART_SDB_TX")
	)
	(segment
		(start 88.8619 -150.047452)
		(end 88.8619 -159.621474)
		(width 0.127)
		(layer "In2.Cu")
		(net "UART_SDB_TX")
	)
	(segment
		(start 110.892844 -22.563836)
		(end 110.256574 -23.200106)
		(width 0.127)
		(layer "In2.Cu")
		(net "UART_SDB_TX")
	)
	(segment
		(start 96.069658 -41.837864)
		(end 95.675958 -42.231564)
		(width 0.127)
		(layer "In2.Cu")
		(net "UART_SDB_TX")
	)
	(segment
		(start 96.069658 -30.631892)
		(end 96.069658 -41.837864)
		(width 0.127)
		(layer "In2.Cu")
		(net "UART_SDB_TX")
	)
	(segment
		(start 103.50119 -23.200106)
		(end 102.894638 -23.806658)
		(width 0.127)
		(layer "In2.Cu")
		(net "UART_SDB_TX")
	)
	(segment
		(start 91.68384 -121.716292)
		(end 91.375992 -122.02414)
		(width 0.127)
		(layer "In2.Cu")
		(net "UART_SDB_TX")
	)
	(segment
		(start 91.9734 -115.0366)
		(end 91.9734 -115.6208)
		(width 0.127)
		(layer "In2.Cu")
		(net "UART_SDB_TX")
	)
	(segment
		(start 91.215718 -116.378482)
		(end 91.215718 -119.638318)
		(width 0.127)
		(layer "In2.Cu")
		(net "UART_SDB_TX")
	)
	(segment
		(start 91.7702 -127.918718)
		(end 91.4273 -128.261618)
		(width 0.127)
		(layer "In2.Cu")
		(net "UART_SDB_TX")
	)
	(segment
		(start 94.638114 -94.420436)
		(end 92.877132 -96.181418)
		(width 0.127)
		(layer "In2.Cu")
		(net "UART_SDB_TX")
	)
	(segment
		(start 129.928366 -38.628574)
		(end 129.928366 -31.621984)
		(width 0.127)
		(layer "In2.Cu")
		(net "UART_SDB_TX")
	)
	(segment
		(start 89.940638 -144.42059)
		(end 89.940638 -145.532856)
		(width 0.127)
		(layer "In2.Cu")
		(net "UART_SDB_TX")
	)
	(segment
		(start 86.3473 -162.632644)
		(end 86.3473 -163.085526)
		(width 0.127)
		(layer "In2.Cu")
		(net "UART_SDB_TX")
	)
	(segment
		(start 90.962226 -140.216128)
		(end 90.62466 -140.553694)
		(width 0.127)
		(layer "In2.Cu")
		(net "UART_SDB_TX")
	)
	(segment
		(start 125.177804 -26.871422)
		(end 121.002044 -26.871422)
		(width 0.127)
		(layer "In2.Cu")
		(net "UART_SDB_TX")
	)
	(segment
		(start 86.2076 -165.058344)
		(end 84.684616 -166.581328)
		(width 0.127)
		(layer "In2.Cu")
		(net "UART_SDB_TX")
	)
	(segment
		(start 89.940638 -145.532856)
		(end 88.001856 -147.471638)
		(width 0.127)
		(layer "In2.Cu")
		(net "UART_SDB_TX")
	)
	(segment
		(start 88.001856 -149.187408)
		(end 88.8619 -150.047452)
		(width 0.127)
		(layer "In2.Cu")
		(net "UART_SDB_TX")
	)
	(segment
		(start 86.9823 -161.501074)
		(end 86.9823 -161.997644)
		(width 0.127)
		(layer "In2.Cu")
		(net "UART_SDB_TX")
	)
	(segment
		(start 95.675958 -42.231564)
		(end 95.675958 -52.660042)
		(width 0.127)
		(layer "In2.Cu")
		(net "UART_SDB_TX")
	)
	(segment
		(start 102.894638 -23.806912)
		(end 96.069658 -30.631892)
		(width 0.127)
		(layer "In2.Cu")
		(net "UART_SDB_TX")
	)
	(segment
		(start 86.2076 -163.225226)
		(end 86.2076 -165.058344)
		(width 0.127)
		(layer "In2.Cu")
		(net "UART_SDB_TX")
	)
	(via
		(at 80.264 -170.6499)
		(size 0.6604)
		(drill 0.254)
		(layers "F.Cu" "B.Cu")
		(net "UART_SDB_RX")
	)
	(segment
		(start 80.264 -170.1546)
		(end 80.7212 -169.6974)
		(width 0.127)
		(layer "B.Cu")
		(net "UART_SDB_RX")
	)
	(segment
		(start 80.7212 -169.6974)
		(end 82.8802 -169.6974)
		(width 0.127)
		(layer "B.Cu")
		(net "UART_SDB_RX")
	)
	(segment
		(start 80.264 -170.6499)
		(end 80.264 -170.1546)
		(width 0.127)
		(layer "B.Cu")
		(net "UART_SDB_RX")
	)
	(segment
		(start 91.850718 -117.242082)
		(end 91.850718 -119.375174)
		(width 0.127)
		(layer "In2.Cu")
		(net "UART_SDB_RX")
	)
	(segment
		(start 120.7389 -27.506422)
		(end 117.067584 -23.835106)
		(width 0.127)
		(layer "In2.Cu")
		(net "UART_SDB_RX")
	)
	(segment
		(start 92.0623 -138.454638)
		(end 91.597226 -138.919712)
		(width 0.127)
		(layer "In2.Cu")
		(net "UART_SDB_RX")
	)
	(segment
		(start 85.457792 -169.8244)
		(end 80.983582 -169.8244)
		(width 0.127)
		(layer "In2.Cu")
		(net "UART_SDB_RX")
	)
	(segment
		(start 87.9983 -163.769802)
		(end 87.8586 -163.909502)
		(width 0.127)
		(layer "In2.Cu")
		(net "UART_SDB_RX")
	)
	(segment
		(start 87.8586 -163.909502)
		(end 87.8586 -166.3192)
		(width 0.127)
		(layer "In2.Cu")
		(net "UART_SDB_RX")
	)
	(segment
		(start 95.273114 -94.68358)
		(end 93.512132 -96.444562)
		(width 0.127)
		(layer "In2.Cu")
		(net "UART_SDB_RX")
	)
	(segment
		(start 92.4052 -128.181862)
		(end 92.0623 -128.524762)
		(width 0.127)
		(layer "In2.Cu")
		(net "UART_SDB_RX")
	)
	(segment
		(start 92.319094 -119.84355)
		(end 92.319094 -120.36933)
		(width 0.127)
		(layer "In2.Cu")
		(net "UART_SDB_RX")
	)
	(segment
		(start 117.067584 -23.835106)
		(end 103.764588 -23.835106)
		(width 0.127)
		(layer "In2.Cu")
		(net "UART_SDB_RX")
	)
	(segment
		(start 96.310958 -42.494708)
		(end 96.310958 -52.926996)
		(width 0.127)
		(layer "In2.Cu")
		(net "UART_SDB_RX")
	)
	(segment
		(start 92.31884 -121.979436)
		(end 92.010992 -122.287284)
		(width 0.127)
		(layer "In2.Cu")
		(net "UART_SDB_RX")
	)
	(segment
		(start 96.310958 -52.926996)
		(end 95.273114 -53.96484)
		(width 0.127)
		(layer "In2.Cu")
		(net "UART_SDB_RX")
	)
	(segment
		(start 93.512132 -115.580668)
		(end 91.850718 -117.242082)
		(width 0.127)
		(layer "In2.Cu")
		(net "UART_SDB_RX")
	)
	(segment
		(start 86.381336 -168.900856)
		(end 85.457792 -169.8244)
		(width 0.127)
		(layer "In2.Cu")
		(net "UART_SDB_RX")
	)
	(segment
		(start 93.512132 -96.444562)
		(end 93.512132 -115.580668)
		(width 0.127)
		(layer "In2.Cu")
		(net "UART_SDB_RX")
	)
	(segment
		(start 87.9983 -163.31692)
		(end 87.9983 -163.769802)
		(width 0.127)
		(layer "In2.Cu")
		(net "UART_SDB_RX")
	)
	(segment
		(start 96.704658 -30.895036)
		(end 96.704658 -42.101008)
		(width 0.127)
		(layer "In2.Cu")
		(net "UART_SDB_RX")
	)
	(segment
		(start 129.293366 -31.885128)
		(end 124.91466 -27.506422)
		(width 0.127)
		(layer "In2.Cu")
		(net "UART_SDB_RX")
	)
	(segment
		(start 87.8586 -166.3192)
		(end 86.381336 -167.796464)
		(width 0.127)
		(layer "In2.Cu")
		(net "UART_SDB_RX")
	)
	(segment
		(start 92.319094 -120.36933)
		(end 92.31884 -120.369584)
		(width 0.127)
		(layer "In2.Cu")
		(net "UART_SDB_RX")
	)
	(segment
		(start 95.273114 -53.96484)
		(end 95.273114 -94.68358)
		(width 0.127)
		(layer "In2.Cu")
		(net "UART_SDB_RX")
	)
	(segment
		(start 91.721432 -151.343614)
		(end 91.721432 -159.097218)
		(width 0.127)
		(layer "In2.Cu")
		(net "UART_SDB_RX")
	)
	(segment
		(start 103.764588 -23.835106)
		(end 96.704658 -30.895036)
		(width 0.127)
		(layer "In2.Cu")
		(net "UART_SDB_RX")
	)
	(segment
		(start 92.31884 -120.369584)
		(end 92.31884 -121.979436)
		(width 0.127)
		(layer "In2.Cu")
		(net "UART_SDB_RX")
	)
	(segment
		(start 129.293366 -39.393622)
		(end 129.293366 -31.885128)
		(width 0.127)
		(layer "In2.Cu")
		(net "UART_SDB_RX")
	)
	(segment
		(start 92.010992 -126.779274)
		(end 92.4052 -127.173482)
		(width 0.127)
		(layer "In2.Cu")
		(net "UART_SDB_RX")
	)
	(segment
		(start 80.7085 -170.099482)
		(end 80.7085 -170.2054)
		(width 0.127)
		(layer "In2.Cu")
		(net "UART_SDB_RX")
	)
	(segment
		(start 92.010992 -122.287284)
		(end 92.010992 -126.779274)
		(width 0.127)
		(layer "In2.Cu")
		(net "UART_SDB_RX")
	)
	(segment
		(start 90.659966 -144.599406)
		(end 90.659966 -150.282148)
		(width 0.127)
		(layer "In2.Cu")
		(net "UART_SDB_RX")
	)
	(segment
		(start 124.91466 -27.506422)
		(end 120.7389 -27.506422)
		(width 0.127)
		(layer "In2.Cu")
		(net "UART_SDB_RX")
	)
	(segment
		(start 92.0623 -128.524762)
		(end 92.0623 -138.454638)
		(width 0.127)
		(layer "In2.Cu")
		(net "UART_SDB_RX")
	)
	(segment
		(start 96.704658 -42.101008)
		(end 96.310958 -42.494708)
		(width 0.127)
		(layer "In2.Cu")
		(net "UART_SDB_RX")
	)
	(segment
		(start 80.983582 -169.8244)
		(end 80.7085 -170.099482)
		(width 0.127)
		(layer "In2.Cu")
		(net "UART_SDB_RX")
	)
	(segment
		(start 92.4052 -127.173482)
		(end 92.4052 -128.181862)
		(width 0.127)
		(layer "In2.Cu")
		(net "UART_SDB_RX")
	)
	(segment
		(start 88.6333 -162.68192)
		(end 87.9983 -163.31692)
		(width 0.127)
		(layer "In2.Cu")
		(net "UART_SDB_RX")
	)
	(segment
		(start 91.850718 -119.375174)
		(end 92.319094 -119.84355)
		(width 0.127)
		(layer "In2.Cu")
		(net "UART_SDB_RX")
	)
	(segment
		(start 91.721432 -159.097218)
		(end 88.6333 -162.18535)
		(width 0.127)
		(layer "In2.Cu")
		(net "UART_SDB_RX")
	)
	(segment
		(start 86.381336 -167.796464)
		(end 86.381336 -168.900856)
		(width 0.127)
		(layer "In2.Cu")
		(net "UART_SDB_RX")
	)
	(segment
		(start 80.7085 -170.2054)
		(end 80.264 -170.6499)
		(width 0.127)
		(layer "In2.Cu")
		(net "UART_SDB_RX")
	)
	(segment
		(start 88.6333 -162.18535)
		(end 88.6333 -162.68192)
		(width 0.127)
		(layer "In2.Cu")
		(net "UART_SDB_RX")
	)
	(segment
		(start 91.597226 -138.919712)
		(end 91.597226 -140.479272)
		(width 0.127)
		(layer "In2.Cu")
		(net "UART_SDB_RX")
	)
	(segment
		(start 91.597226 -140.479272)
		(end 91.25966 -140.816838)
		(width 0.127)
		(layer "In2.Cu")
		(net "UART_SDB_RX")
	)
	(segment
		(start 91.25966 -140.816838)
		(end 91.25966 -143.999712)
		(width 0.127)
		(layer "In2.Cu")
		(net "UART_SDB_RX")
	)
	(segment
		(start 91.25966 -143.999712)
		(end 90.659966 -144.599406)
		(width 0.127)
		(layer "In2.Cu")
		(net "UART_SDB_RX")
	)
	(segment
		(start 130.499866 -40.600122)
		(end 129.293366 -39.393622)
		(width 0.127)
		(layer "In2.Cu")
		(net "UART_SDB_RX")
	)
	(segment
		(start 90.659966 -150.282148)
		(end 91.721432 -151.343614)
		(width 0.127)
		(layer "In2.Cu")
		(net "UART_SDB_RX")
	)
	(segment
		(start 41.278302 -153.996898)
		(end 41.699942 -153.575258)
		(width 0.127)
		(layer "F.Cu")
		(net "UART_COMP_OUT_TX_R")
	)
	(segment
		(start 39.090854 -156.920184)
		(end 39.090854 -155.634182)
		(width 0.127)
		(layer "F.Cu")
		(net "UART_COMP_OUT_TX_R")
	)
	(segment
		(start 39.090854 -155.634182)
		(end 40.728138 -153.996898)
		(width 0.127)
		(layer "F.Cu")
		(net "UART_COMP_OUT_TX_R")
	)
	(segment
		(start 40.728138 -153.996898)
		(end 41.278302 -153.996898)
		(width 0.127)
		(layer "F.Cu")
		(net "UART_COMP_OUT_TX_R")
	)
	(segment
		(start 39.090854 -157.341316)
		(end 39.090854 -156.920184)
		(width 0.127)
		(layer "F.Cu")
		(net "UART_COMP_OUT_TX_R")
	)
	(segment
		(start 39.0398 -157.39237)
		(end 39.090854 -157.341316)
		(width 0.127)
		(layer "F.Cu")
		(net "UART_COMP_OUT_TX_R")
	)
	(segment
		(start 41.699942 -153.575258)
		(end 41.699942 -153.399998)
		(width 0.127)
		(layer "F.Cu")
		(net "UART_COMP_OUT_TX_R")
	)
	(segment
		(start 39.0398 -158.1785)
		(end 39.0398 -157.39237)
		(width 0.127)
		(layer "F.Cu")
		(net "UART_COMP_OUT_TX_R")
	)
	(via
		(at 39.090854 -156.920184)
		(size 0.6604)
		(drill 0.3302)
		(layers "F.Cu" "B.Cu")
		(net "UART_COMP_OUT_TX_R")
	)
	(segment
		(start 46.11116 -162.8902)
		(end 45.8978 -162.67684)
		(width 0.127)
		(layer "F.Cu")
		(net "TP_BMC_GPIOL5")
	)
	(segment
		(start 45.300138 -152.200102)
		(end 45.699934 -151.800306)
		(width 0.127)
		(layer "F.Cu")
		(net "TP_BMC_GPIOL5")
	)
	(segment
		(start 46.11116 -163.6903)
		(end 46.11116 -162.8902)
		(width 0.127)
		(layer "F.Cu")
		(net "TP_BMC_GPIOL5")
	)
	(segment
		(start 45.699934 -151.800306)
		(end 45.699934 -151.800052)
		(width 0.127)
		(layer "F.Cu")
		(net "TP_BMC_GPIOL5")
	)
	(via
		(at 45.300138 -152.200102)
		(size 0.4572)
		(drill 0.2032)
		(layers "F.Cu" "B.Cu")
		(net "TP_BMC_GPIOL5")
	)
	(via
		(at 45.8978 -162.67684)
		(size 0.508)
		(drill 0.254)
		(layers "F.Cu" "B.Cu")
		(net "TP_BMC_GPIOL5")
	)
	(segment
		(start 45.8978 -162.67684)
		(end 44.1833 -160.96234)
		(width 0.127)
		(layer "In2.Cu")
		(net "TP_BMC_GPIOL5")
	)
	(segment
		(start 44.1833 -160.96234)
		(end 44.1833 -158.570676)
		(width 0.127)
		(layer "In2.Cu")
		(net "TP_BMC_GPIOL5")
	)
	(segment
		(start 44.1833 -158.570676)
		(end 45.300138 -157.453838)
		(width 0.127)
		(layer "In2.Cu")
		(net "TP_BMC_GPIOL5")
	)
	(segment
		(start 45.300138 -157.453838)
		(end 45.300138 -152.200102)
		(width 0.127)
		(layer "In2.Cu")
		(net "TP_BMC_GPIOL5")
	)
	(segment
		(start 45.699934 -151.000206)
		(end 45.699934 -150.999952)
		(width 0.127)
		(layer "F.Cu")
		(net "TP_BMC_GPIOL4")
	)
	(segment
		(start 45.299884 -151.400256)
		(end 45.699934 -151.000206)
		(width 0.127)
		(layer "F.Cu")
		(net "TP_BMC_GPIOL4")
	)
	(via
		(at 45.299884 -151.400256)
		(size 0.4572)
		(drill 0.2032)
		(layers "F.Cu" "B.Cu")
		(net "TP_BMC_GPIOL4")
	)
	(segment
		(start 45.1485 -153.2255)
		(end 45.6946 -152.6794)
		(width 0.127)
		(layer "B.Cu")
		(net "TP_BMC_GPIOL4")
	)
	(segment
		(start 45.6946 -151.794972)
		(end 45.299884 -151.400256)
		(width 0.127)
		(layer "B.Cu")
		(net "TP_BMC_GPIOL4")
	)
	(segment
		(start 45.6946 -152.6794)
		(end 45.6946 -151.794972)
		(width 0.127)
		(layer "B.Cu")
		(net "TP_BMC_GPIOL4")
	)
	(segment
		(start 41.8719 -155.131516)
		(end 41.8719 -154.51328)
		(width 0.127)
		(layer "F.Cu")
		(net "TP_BMC_GPIOL3")
	)
	(segment
		(start 42.852848 -153.5684)
		(end 42.852848 -153.046938)
		(width 0.127)
		(layer "F.Cu")
		(net "TP_BMC_GPIOL3")
	)
	(segment
		(start 40.995092 -156.008324)
		(end 41.8719 -155.131516)
		(width 0.127)
		(layer "F.Cu")
		(net "TP_BMC_GPIOL3")
	)
	(segment
		(start 41.8719 -154.51328)
		(end 42.81678 -153.5684)
		(width 0.127)
		(layer "F.Cu")
		(net "TP_BMC_GPIOL3")
	)
	(segment
		(start 42.81678 -153.5684)
		(end 42.852848 -153.5684)
		(width 0.127)
		(layer "F.Cu")
		(net "TP_BMC_GPIOL3")
	)
	(segment
		(start 40.995092 -157.31236)
		(end 40.995092 -156.008324)
		(width 0.127)
		(layer "F.Cu")
		(net "TP_BMC_GPIOL3")
	)
	(segment
		(start 40.4368 -158.30296)
		(end 40.4368 -157.870652)
		(width 0.127)
		(layer "F.Cu")
		(net "TP_BMC_GPIOL3")
	)
	(segment
		(start 40.4368 -157.870652)
		(end 40.995092 -157.31236)
		(width 0.127)
		(layer "F.Cu")
		(net "TP_BMC_GPIOL3")
	)
	(segment
		(start 42.852848 -153.046938)
		(end 43.299888 -152.599898)
		(width 0.127)
		(layer "F.Cu")
		(net "TP_BMC_GPIOL3")
	)
	(segment
		(start 42.2402 -154.667458)
		(end 42.2402 -154.638248)
		(width 0.127)
		(layer "F.Cu")
		(net "TP_BMC_GPIOL2")
	)
	(segment
		(start 41.376092 -157.597348)
		(end 41.376092 -156.118306)
		(width 0.127)
		(layer "F.Cu")
		(net "TP_BMC_GPIOL2")
	)
	(segment
		(start 40.98798 -158.64078)
		(end 40.98798 -157.98546)
		(width 0.127)
		(layer "F.Cu")
		(net "TP_BMC_GPIOL2")
	)
	(segment
		(start 42.2402 -154.638248)
		(end 43.081448 -153.797)
		(width 0.127)
		(layer "F.Cu")
		(net "TP_BMC_GPIOL2")
	)
	(segment
		(start 40.3098 -159.31896)
		(end 40.98798 -158.64078)
		(width 0.127)
		(layer "F.Cu")
		(net "TP_BMC_GPIOL2")
	)
	(segment
		(start 41.528492 -155.965652)
		(end 41.662096 -155.832048)
		(width 0.127)
		(layer "F.Cu")
		(net "TP_BMC_GPIOL2")
	)
	(segment
		(start 43.081448 -153.797)
		(end 43.081448 -153.618438)
		(width 0.127)
		(layer "F.Cu")
		(net "TP_BMC_GPIOL2")
	)
	(segment
		(start 40.3098 -159.68726)
		(end 40.3098 -159.31896)
		(width 0.127)
		(layer "F.Cu")
		(net "TP_BMC_GPIOL2")
	)
	(segment
		(start 41.528492 -155.965906)
		(end 41.528492 -155.965652)
		(width 0.127)
		(layer "F.Cu")
		(net "TP_BMC_GPIOL2")
	)
	(segment
		(start 41.376092 -156.118306)
		(end 41.528492 -155.965906)
		(width 0.127)
		(layer "F.Cu")
		(net "TP_BMC_GPIOL2")
	)
	(segment
		(start 42.11574 -155.378658)
		(end 42.11574 -154.791918)
		(width 0.127)
		(layer "F.Cu")
		(net "TP_BMC_GPIOL2")
	)
	(segment
		(start 40.2209 -159.77616)
		(end 40.3098 -159.68726)
		(width 0.127)
		(layer "F.Cu")
		(net "TP_BMC_GPIOL2")
	)
	(segment
		(start 40.98798 -157.98546)
		(end 41.376092 -157.597348)
		(width 0.127)
		(layer "F.Cu")
		(net "TP_BMC_GPIOL2")
	)
	(segment
		(start 41.66235 -155.832048)
		(end 42.11574 -155.378658)
		(width 0.127)
		(layer "F.Cu")
		(net "TP_BMC_GPIOL2")
	)
	(segment
		(start 41.662096 -155.832048)
		(end 41.66235 -155.832048)
		(width 0.127)
		(layer "F.Cu")
		(net "TP_BMC_GPIOL2")
	)
	(segment
		(start 43.081448 -153.618438)
		(end 43.299888 -153.399998)
		(width 0.127)
		(layer "F.Cu")
		(net "TP_BMC_GPIOL2")
	)
	(segment
		(start 42.11574 -154.791918)
		(end 42.2402 -154.667458)
		(width 0.127)
		(layer "F.Cu")
		(net "TP_BMC_GPIOL2")
	)
	(segment
		(start 42.81932 -154.735022)
		(end 43.9166 -153.637742)
		(width 0.127)
		(layer "F.Cu")
		(net "TP_BMC_GPIOL1")
	)
	(segment
		(start 42.7482 -157.9626)
		(end 42.81932 -157.89148)
		(width 0.127)
		(layer "F.Cu")
		(net "TP_BMC_GPIOL1")
	)
	(segment
		(start 43.9166 -153.637742)
		(end 43.9166 -153.583386)
		(width 0.127)
		(layer "F.Cu")
		(net "TP_BMC_GPIOL1")
	)
	(segment
		(start 43.9166 -153.583386)
		(end 44.099988 -153.399998)
		(width 0.127)
		(layer "F.Cu")
		(net "TP_BMC_GPIOL1")
	)
	(segment
		(start 42.81932 -157.89148)
		(end 42.81932 -154.735022)
		(width 0.127)
		(layer "F.Cu")
		(net "TP_BMC_GPIOL1")
	)
	(segment
		(start 43.688 -153.011886)
		(end 43.688 -153.543)
		(width 0.127)
		(layer "F.Cu")
		(net "TP_BMC_GPIOL0")
	)
	(segment
		(start 42.34434 -155.4734)
		(end 41.757092 -156.060648)
		(width 0.127)
		(layer "F.Cu")
		(net "TP_BMC_GPIOL0")
	)
	(segment
		(start 41.757092 -156.060648)
		(end 41.757092 -158.821628)
		(width 0.127)
		(layer "F.Cu")
		(net "TP_BMC_GPIOL0")
	)
	(segment
		(start 44.099988 -152.599898)
		(end 43.688 -153.011886)
		(width 0.127)
		(layer "F.Cu")
		(net "TP_BMC_GPIOL0")
	)
	(segment
		(start 41.757092 -158.821628)
		(end 41.68902 -158.8897)
		(width 0.127)
		(layer "F.Cu")
		(net "TP_BMC_GPIOL0")
	)
	(segment
		(start 42.34434 -154.88666)
		(end 42.34434 -155.4734)
		(width 0.127)
		(layer "F.Cu")
		(net "TP_BMC_GPIOL0")
	)
	(segment
		(start 43.688 -153.543)
		(end 42.34434 -154.88666)
		(width 0.127)
		(layer "F.Cu")
		(net "TP_BMC_GPIOL0")
	)
	(segment
		(start 52.899818 -143.800068)
		(end 53.299868 -143.400018)
		(width 0.127)
		(layer "F.Cu")
		(net "SYS_PWR_LED")
	)
	(via
		(at 80.958944 -139.623038)
		(size 0.508)
		(drill 0.254)
		(layers "F.Cu" "B.Cu")
		(net "SYS_PWR_LED")
	)
	(via
		(at 53.299868 -143.400018)
		(size 0.4572)
		(drill 0.2032)
		(layers "F.Cu" "B.Cu")
		(net "SYS_PWR_LED")
	)
	(via
		(at 60.39485 -138.6586)
		(size 0.6096)
		(drill 0.3048)
		(layers "F.Cu" "B.Cu")
		(net "SYS_PWR_LED")
	)
	(segment
		(start 53.674518 -142.495524)
		(end 53.674518 -143.025368)
		(width 0.0889)
		(layer "B.Cu")
		(net "SYS_PWR_LED")
	)
	(segment
		(start 60.5663 -138.83005)
		(end 60.39485 -138.6586)
		(width 0.127)
		(layer "B.Cu")
		(net "SYS_PWR_LED")
	)
	(segment
		(start 56.006238 -142.088362)
		(end 55.343806 -142.088362)
		(width 0.0889)
		(layer "B.Cu")
		(net "SYS_PWR_LED")
	)
	(segment
		(start 56.4388 -141.6558)
		(end 56.211216 -141.883384)
		(width 0.127)
		(layer "B.Cu")
		(net "SYS_PWR_LED")
	)
	(segment
		(start 55.217568 -142.2146)
		(end 53.955442 -142.2146)
		(width 0.0889)
		(layer "B.Cu")
		(net "SYS_PWR_LED")
	)
	(segment
		(start 60.5663 -139.8016)
		(end 60.5663 -138.83005)
		(width 0.127)
		(layer "B.Cu")
		(net "SYS_PWR_LED")
	)
	(segment
		(start 60.204604 -138.6586)
		(end 59.8932 -138.970004)
		(width 0.127)
		(layer "B.Cu")
		(net "SYS_PWR_LED")
	)
	(segment
		(start 60.5663 -140.8176)
		(end 60.5663 -139.8016)
		(width 0.127)
		(layer "B.Cu")
		(net "SYS_PWR_LED")
	)
	(segment
		(start 59.8932 -139.93749)
		(end 59.416442 -140.414248)
		(width 0.127)
		(layer "B.Cu")
		(net "SYS_PWR_LED")
	)
	(segment
		(start 56.4388 -141.402308)
		(end 56.4388 -141.6558)
		(width 0.127)
		(layer "B.Cu")
		(net "SYS_PWR_LED")
	)
	(segment
		(start 56.211216 -141.883384)
		(end 56.006238 -142.088362)
		(width 0.0889)
		(layer "B.Cu")
		(net "SYS_PWR_LED")
	)
	(segment
		(start 53.674518 -143.025368)
		(end 53.299868 -143.400018)
		(width 0.0889)
		(layer "B.Cu")
		(net "SYS_PWR_LED")
	)
	(segment
		(start 55.343806 -142.088362)
		(end 55.217568 -142.2146)
		(width 0.0889)
		(layer "B.Cu")
		(net "SYS_PWR_LED")
	)
	(segment
		(start 58.073036 -140.9446)
		(end 56.896508 -140.9446)
		(width 0.127)
		(layer "B.Cu")
		(net "SYS_PWR_LED")
	)
	(segment
		(start 56.896508 -140.9446)
		(end 56.4388 -141.402308)
		(width 0.127)
		(layer "B.Cu")
		(net "SYS_PWR_LED")
	)
	(segment
		(start 59.8932 -138.970004)
		(end 59.8932 -139.93749)
		(width 0.127)
		(layer "B.Cu")
		(net "SYS_PWR_LED")
	)
	(segment
		(start 59.416442 -140.414248)
		(end 58.603388 -140.414248)
		(width 0.127)
		(layer "B.Cu")
		(net "SYS_PWR_LED")
	)
	(segment
		(start 53.955442 -142.2146)
		(end 53.674518 -142.495524)
		(width 0.0889)
		(layer "B.Cu")
		(net "SYS_PWR_LED")
	)
	(segment
		(start 58.603388 -140.414248)
		(end 58.073036 -140.9446)
		(width 0.127)
		(layer "B.Cu")
		(net "SYS_PWR_LED")
	)
	(segment
		(start 60.39485 -138.6586)
		(end 60.204604 -138.6586)
		(width 0.127)
		(layer "B.Cu")
		(net "SYS_PWR_LED")
	)
	(segment
		(start 93.543882 -7.885938)
		(end 82.847688 -7.885938)
		(width 0.127)
		(layer "In2.Cu")
		(net "SYS_PWR_LED")
	)
	(segment
		(start 85.987128 -64.369696)
		(end 87.962232 -66.3448)
		(width 0.127)
		(layer "In2.Cu")
		(net "SYS_PWR_LED")
	)
	(segment
		(start 86.596728 -100.351082)
		(end 87.566246 -101.3206)
		(width 0.127)
		(layer "In2.Cu")
		(net "SYS_PWR_LED")
	)
	(segment
		(start 87.85733 -37.02431)
		(end 87.85733 -42.47134)
		(width 0.127)
		(layer "In2.Cu")
		(net "SYS_PWR_LED")
	)
	(segment
		(start 96.751648 -13.185648)
		(end 96.330262 -12.764262)
		(width 0.127)
		(layer "In2.Cu")
		(net "SYS_PWR_LED")
	)
	(segment
		(start 135.899906 -41.800018)
		(end 136.852406 -40.847518)
		(width 0.127)
		(layer "In2.Cu")
		(net "SYS_PWR_LED")
	)
	(segment
		(start 131.990338 -26.3652)
		(end 130.061208 -26.3652)
		(width 0.127)
		(layer "In2.Cu")
		(net "SYS_PWR_LED")
	)
	(segment
		(start 118.274084 -18.753836)
		(end 102.697788 -18.753836)
		(width 0.127)
		(layer "In2.Cu")
		(net "SYS_PWR_LED")
	)
	(segment
		(start 121.329704 -20.18157)
		(end 119.701818 -20.18157)
		(width 0.127)
		(layer "In2.Cu")
		(net "SYS_PWR_LED")
	)
	(segment
		(start 102.697788 -18.753836)
		(end 97.1296 -13.185648)
		(width 0.127)
		(layer "In2.Cu")
		(net "SYS_PWR_LED")
	)
	(segment
		(start 80.958944 -129.514092)
		(end 80.958944 -139.623038)
		(width 0.127)
		(layer "In2.Cu")
		(net "SYS_PWR_LED")
	)
	(segment
		(start 119.701818 -20.18157)
		(end 118.274084 -18.753836)
		(width 0.127)
		(layer "In2.Cu")
		(net "SYS_PWR_LED")
	)
	(segment
		(start 85.5726 -112.0902)
		(end 83.82 -113.8428)
		(width 0.127)
		(layer "In2.Cu")
		(net "SYS_PWR_LED")
	)
	(segment
		(start 81.39938 -9.334246)
		(end 81.39938 -30.56636)
		(width 0.127)
		(layer "In2.Cu")
		(net "SYS_PWR_LED")
	)
	(segment
		(start 81.2419 -129.231136)
		(end 80.958944 -129.514092)
		(width 0.127)
		(layer "In2.Cu")
		(net "SYS_PWR_LED")
	)
	(segment
		(start 83.82 -116.98605)
		(end 84.934044 -118.100348)
		(width 0.127)
		(layer "In2.Cu")
		(net "SYS_PWR_LED")
	)
	(segment
		(start 96.330262 -12.764262)
		(end 96.330262 -10.672318)
		(width 0.127)
		(layer "In2.Cu")
		(net "SYS_PWR_LED")
	)
	(segment
		(start 86.596728 -91.017852)
		(end 86.596728 -100.351082)
		(width 0.127)
		(layer "In2.Cu")
		(net "SYS_PWR_LED")
	)
	(segment
		(start 85.987128 -44.341542)
		(end 85.987128 -64.369696)
		(width 0.127)
		(layer "In2.Cu")
		(net "SYS_PWR_LED")
	)
	(segment
		(start 123.698508 -22.550374)
		(end 121.329704 -20.18157)
		(width 0.127)
		(layer "In2.Cu")
		(net "SYS_PWR_LED")
	)
	(segment
		(start 83.82 -113.8428)
		(end 83.82 -116.98605)
		(width 0.127)
		(layer "In2.Cu")
		(net "SYS_PWR_LED")
	)
	(segment
		(start 136.852406 -31.227268)
		(end 131.990338 -26.3652)
		(width 0.127)
		(layer "In2.Cu")
		(net "SYS_PWR_LED")
	)
	(segment
		(start 136.852406 -40.847518)
		(end 136.852406 -31.227268)
		(width 0.127)
		(layer "In2.Cu")
		(net "SYS_PWR_LED")
	)
	(segment
		(start 87.85733 -42.47134)
		(end 85.987128 -44.341542)
		(width 0.127)
		(layer "In2.Cu")
		(net "SYS_PWR_LED")
	)
	(segment
		(start 85.5726 -110.298992)
		(end 85.5726 -112.0902)
		(width 0.127)
		(layer "In2.Cu")
		(net "SYS_PWR_LED")
	)
	(segment
		(start 87.566246 -101.3206)
		(end 87.566246 -108.305346)
		(width 0.127)
		(layer "In2.Cu")
		(net "SYS_PWR_LED")
	)
	(segment
		(start 97.1296 -13.185648)
		(end 96.751648 -13.185648)
		(width 0.127)
		(layer "In2.Cu")
		(net "SYS_PWR_LED")
	)
	(segment
		(start 81.2419 -126.292864)
		(end 81.2419 -129.231136)
		(width 0.127)
		(layer "In2.Cu")
		(net "SYS_PWR_LED")
	)
	(segment
		(start 84.934044 -122.60072)
		(end 81.2419 -126.292864)
		(width 0.127)
		(layer "In2.Cu")
		(net "SYS_PWR_LED")
	)
	(segment
		(start 96.330262 -10.672318)
		(end 93.543882 -7.885938)
		(width 0.127)
		(layer "In2.Cu")
		(net "SYS_PWR_LED")
	)
	(segment
		(start 81.39938 -30.56636)
		(end 87.85733 -37.02431)
		(width 0.127)
		(layer "In2.Cu")
		(net "SYS_PWR_LED")
	)
	(segment
		(start 84.934044 -118.100348)
		(end 84.934044 -122.60072)
		(width 0.127)
		(layer "In2.Cu")
		(net "SYS_PWR_LED")
	)
	(segment
		(start 82.847688 -7.885938)
		(end 81.39938 -9.334246)
		(width 0.127)
		(layer "In2.Cu")
		(net "SYS_PWR_LED")
	)
	(segment
		(start 87.962232 -89.652348)
		(end 86.596728 -91.017852)
		(width 0.127)
		(layer "In2.Cu")
		(net "SYS_PWR_LED")
	)
	(segment
		(start 130.061208 -26.3652)
		(end 126.246382 -22.550374)
		(width 0.127)
		(layer "In2.Cu")
		(net "SYS_PWR_LED")
	)
	(segment
		(start 87.962232 -66.3448)
		(end 87.962232 -89.652348)
		(width 0.127)
		(layer "In2.Cu")
		(net "SYS_PWR_LED")
	)
	(segment
		(start 126.246382 -22.550374)
		(end 123.698508 -22.550374)
		(width 0.127)
		(layer "In2.Cu")
		(net "SYS_PWR_LED")
	)
	(segment
		(start 87.566246 -108.305346)
		(end 85.5726 -110.298992)
		(width 0.127)
		(layer "In2.Cu")
		(net "SYS_PWR_LED")
	)
	(segment
		(start 75.6412 -140.363194)
		(end 78.429358 -140.363194)
		(width 0.127)
		(layer "In5.Cu")
		(net "SYS_PWR_LED")
	)
	(segment
		(start 62.300612 -141.178534)
		(end 63.343282 -140.135864)
		(width 0.127)
		(layer "In5.Cu")
		(net "SYS_PWR_LED")
	)
	(segment
		(start 67.589146 -139.877546)
		(end 68.252086 -139.877546)
		(width 0.127)
		(layer "In5.Cu")
		(net "SYS_PWR_LED")
	)
	(segment
		(start 53.706268 -142.993618)
		(end 54.26329 -142.993618)
		(width 0.127)
		(layer "In5.Cu")
		(net "SYS_PWR_LED")
	)
	(segment
		(start 78.429358 -140.363194)
		(end 79.185008 -139.607544)
		(width 0.127)
		(layer "In5.Cu")
		(net "SYS_PWR_LED")
	)
	(segment
		(start 75.293982 -140.015976)
		(end 75.6412 -140.363194)
		(width 0.127)
		(layer "In5.Cu")
		(net "SYS_PWR_LED")
	)
	(segment
		(start 63.343282 -140.135864)
		(end 64.924432 -140.135864)
		(width 0.127)
		(layer "In5.Cu")
		(net "SYS_PWR_LED")
	)
	(segment
		(start 57.474612 -141.178534)
		(end 62.300612 -141.178534)
		(width 0.127)
		(layer "In5.Cu")
		(net "SYS_PWR_LED")
	)
	(segment
		(start 54.26329 -142.993618)
		(end 54.506114 -142.750794)
		(width 0.127)
		(layer "In5.Cu")
		(net "SYS_PWR_LED")
	)
	(segment
		(start 54.506114 -142.437104)
		(end 54.749192 -142.194026)
		(width 0.127)
		(layer "In5.Cu")
		(net "SYS_PWR_LED")
	)
	(segment
		(start 80.94345 -139.607544)
		(end 80.958944 -139.623038)
		(width 0.127)
		(layer "In5.Cu")
		(net "SYS_PWR_LED")
	)
	(segment
		(start 56.45912 -142.194026)
		(end 57.474612 -141.178534)
		(width 0.127)
		(layer "In5.Cu")
		(net "SYS_PWR_LED")
	)
	(segment
		(start 54.506114 -142.750794)
		(end 54.506114 -142.437104)
		(width 0.127)
		(layer "In5.Cu")
		(net "SYS_PWR_LED")
	)
	(segment
		(start 65.183004 -139.877292)
		(end 65.603628 -139.877292)
		(width 0.127)
		(layer "In5.Cu")
		(net "SYS_PWR_LED")
	)
	(segment
		(start 65.603628 -139.877292)
		(end 67.589146 -139.877546)
		(width 0.127)
		(layer "In5.Cu")
		(net "SYS_PWR_LED")
	)
	(segment
		(start 79.185008 -139.607544)
		(end 80.94345 -139.607544)
		(width 0.127)
		(layer "In5.Cu")
		(net "SYS_PWR_LED")
	)
	(segment
		(start 54.749192 -142.194026)
		(end 56.45912 -142.194026)
		(width 0.127)
		(layer "In5.Cu")
		(net "SYS_PWR_LED")
	)
	(segment
		(start 53.299868 -143.400018)
		(end 53.706268 -142.993618)
		(width 0.127)
		(layer "In5.Cu")
		(net "SYS_PWR_LED")
	)
	(segment
		(start 68.390516 -140.015976)
		(end 75.293982 -140.015976)
		(width 0.127)
		(layer "In5.Cu")
		(net "SYS_PWR_LED")
	)
	(segment
		(start 68.252086 -139.877546)
		(end 68.390516 -140.015976)
		(width 0.127)
		(layer "In5.Cu")
		(net "SYS_PWR_LED")
	)
	(segment
		(start 64.924432 -140.135864)
		(end 65.183004 -139.877292)
		(width 0.127)
		(layer "In5.Cu")
		(net "SYS_PWR_LED")
	)
	(segment
		(start 36.454334 -159.0675)
		(end 36.9062 -159.0675)
		(width 0.127)
		(layer "F.Cu")
		(net "PWM_OUT_ZONE_D")
	)
	(segment
		(start 36.060634 -158.6738)
		(end 36.454334 -159.0675)
		(width 0.127)
		(layer "F.Cu")
		(net "PWM_OUT_ZONE_D")
	)
	(via
		(at 36.060634 -158.6738)
		(size 0.508)
		(drill 0.254)
		(layers "F.Cu" "B.Cu")
		(net "PWM_OUT_ZONE_D")
	)
	(segment
		(start 48.29937 -166.175182)
		(end 49.141888 -167.0177)
		(width 0.127)
		(layer "In5.Cu")
		(net "PWM_OUT_ZONE_D")
	)
	(segment
		(start 38.14318 -161.5948)
		(end 39.192454 -161.5948)
		(width 0.127)
		(layer "In5.Cu")
		(net "PWM_OUT_ZONE_D")
	)
	(segment
		(start 46.733206 -166.175182)
		(end 48.29937 -166.175182)
		(width 0.127)
		(layer "In5.Cu")
		(net "PWM_OUT_ZONE_D")
	)
	(segment
		(start 98.577146 -174.9552)
		(end 101.81336 -174.9552)
		(width 0.127)
		(layer "In5.Cu")
		(net "PWM_OUT_ZONE_D")
	)
	(segment
		(start 98.208846 -175.3235)
		(end 98.577146 -174.9552)
		(width 0.127)
		(layer "In5.Cu")
		(net "PWM_OUT_ZONE_D")
	)
	(segment
		(start 69.6722 -173.8122)
		(end 69.9897 -173.4947)
		(width 0.127)
		(layer "In5.Cu")
		(net "PWM_OUT_ZONE_D")
	)
	(segment
		(start 86.697058 -173.757844)
		(end 86.940644 -173.757844)
		(width 0.127)
		(layer "In5.Cu")
		(net "PWM_OUT_ZONE_D")
	)
	(segment
		(start 59.521852 -173.8122)
		(end 69.6722 -173.8122)
		(width 0.127)
		(layer "In5.Cu")
		(net "PWM_OUT_ZONE_D")
	)
	(segment
		(start 41.306496 -163.708842)
		(end 44.266866 -163.708842)
		(width 0.127)
		(layer "In5.Cu")
		(net "PWM_OUT_ZONE_D")
	)
	(segment
		(start 86.940644 -173.757844)
		(end 88.4428 -175.26)
		(width 0.127)
		(layer "In5.Cu")
		(net "PWM_OUT_ZONE_D")
	)
	(segment
		(start 95.102934 -175.3235)
		(end 98.208846 -175.3235)
		(width 0.127)
		(layer "In5.Cu")
		(net "PWM_OUT_ZONE_D")
	)
	(segment
		(start 83.444334 -174.2567)
		(end 84.434934 -173.2661)
		(width 0.127)
		(layer "In5.Cu")
		(net "PWM_OUT_ZONE_D")
	)
	(segment
		(start 101.81336 -174.9552)
		(end 102.093776 -174.674784)
		(width 0.127)
		(layer "In5.Cu")
		(net "PWM_OUT_ZONE_D")
	)
	(segment
		(start 105.6005 -43.484038)
		(end 105.6005 -41.899332)
		(width 0.127)
		(layer "In5.Cu")
		(net "PWM_OUT_ZONE_D")
	)
	(segment
		(start 36.1442 -158.757366)
		(end 36.1442 -159.59582)
		(width 0.127)
		(layer "In5.Cu")
		(net "PWM_OUT_ZONE_D")
	)
	(segment
		(start 52.727352 -167.0177)
		(end 59.521852 -173.8122)
		(width 0.127)
		(layer "In5.Cu")
		(net "PWM_OUT_ZONE_D")
	)
	(segment
		(start 36.060634 -158.6738)
		(end 36.1442 -158.757366)
		(width 0.127)
		(layer "In5.Cu")
		(net "PWM_OUT_ZONE_D")
	)
	(segment
		(start 39.192454 -161.5948)
		(end 41.306496 -163.708842)
		(width 0.127)
		(layer "In5.Cu")
		(net "PWM_OUT_ZONE_D")
	)
	(segment
		(start 105.6005 -41.899332)
		(end 107.099862 -40.39997)
		(width 0.127)
		(layer "In5.Cu")
		(net "PWM_OUT_ZONE_D")
	)
	(segment
		(start 69.9897 -173.4947)
		(end 72.912986 -173.4947)
		(width 0.127)
		(layer "In5.Cu")
		(net "PWM_OUT_ZONE_D")
	)
	(segment
		(start 84.434934 -173.2661)
		(end 85.360002 -173.2661)
		(width 0.127)
		(layer "In5.Cu")
		(net "PWM_OUT_ZONE_D")
	)
	(segment
		(start 44.266866 -163.708842)
		(end 46.733206 -166.175182)
		(width 0.127)
		(layer "In5.Cu")
		(net "PWM_OUT_ZONE_D")
	)
	(segment
		(start 86.644734 -173.70552)
		(end 86.697058 -173.757844)
		(width 0.127)
		(layer "In5.Cu")
		(net "PWM_OUT_ZONE_D")
	)
	(segment
		(start 49.141888 -167.0177)
		(end 52.727352 -167.0177)
		(width 0.127)
		(layer "In5.Cu")
		(net "PWM_OUT_ZONE_D")
	)
	(segment
		(start 102.093776 -46.990762)
		(end 105.6005 -43.484038)
		(width 0.127)
		(layer "In5.Cu")
		(net "PWM_OUT_ZONE_D")
	)
	(segment
		(start 72.912986 -173.4947)
		(end 73.674986 -174.2567)
		(width 0.127)
		(layer "In5.Cu")
		(net "PWM_OUT_ZONE_D")
	)
	(segment
		(start 73.674986 -174.2567)
		(end 83.444334 -174.2567)
		(width 0.127)
		(layer "In5.Cu")
		(net "PWM_OUT_ZONE_D")
	)
	(segment
		(start 95.039434 -175.26)
		(end 95.102934 -175.3235)
		(width 0.127)
		(layer "In5.Cu")
		(net "PWM_OUT_ZONE_D")
	)
	(segment
		(start 88.4428 -175.26)
		(end 95.039434 -175.26)
		(width 0.127)
		(layer "In5.Cu")
		(net "PWM_OUT_ZONE_D")
	)
	(segment
		(start 85.360002 -173.2661)
		(end 85.799422 -173.70552)
		(width 0.127)
		(layer "In5.Cu")
		(net "PWM_OUT_ZONE_D")
	)
	(segment
		(start 85.799422 -173.70552)
		(end 86.644734 -173.70552)
		(width 0.127)
		(layer "In5.Cu")
		(net "PWM_OUT_ZONE_D")
	)
	(segment
		(start 36.1442 -159.59582)
		(end 38.14318 -161.5948)
		(width 0.127)
		(layer "In5.Cu")
		(net "PWM_OUT_ZONE_D")
	)
	(segment
		(start 102.093776 -174.674784)
		(end 102.093776 -46.990762)
		(width 0.127)
		(layer "In5.Cu")
		(net "PWM_OUT_ZONE_D")
	)
	(segment
		(start 37.5158 -159.766)
		(end 37.5158 -159.4993)
		(width 0.127)
		(layer "F.Cu")
		(net "PWM_OUT_ZONE_C")
	)
	(segment
		(start 37.5158 -159.4993)
		(end 37.9476 -159.0675)
		(width 0.127)
		(layer "F.Cu")
		(net "PWM_OUT_ZONE_C")
	)
	(segment
		(start 37.2872 -159.9946)
		(end 37.5158 -159.766)
		(width 0.127)
		(layer "F.Cu")
		(net "PWM_OUT_ZONE_C")
	)
	(via
		(at 100.690426 -174.392844)
		(size 0.508)
		(drill 0.254)
		(layers "F.Cu" "B.Cu")
		(net "PWM_OUT_ZONE_C")
	)
	(via
		(at 37.2872 -159.9946)
		(size 0.508)
		(drill 0.254)
		(layers "F.Cu" "B.Cu")
		(net "PWM_OUT_ZONE_C")
	)
	(segment
		(start 101.328474 -123.796806)
		(end 100.769166 -124.356114)
		(width 0.127)
		(layer "In2.Cu")
		(net "PWM_OUT_ZONE_C")
	)
	(segment
		(start 102.112318 -173.8376)
		(end 101.557074 -174.392844)
		(width 0.127)
		(layer "In2.Cu")
		(net "PWM_OUT_ZONE_C")
	)
	(segment
		(start 100.769166 -127.609092)
		(end 101.150166 -127.990092)
		(width 0.127)
		(layer "In2.Cu")
		(net "PWM_OUT_ZONE_C")
	)
	(segment
		(start 100.769166 -124.356114)
		(end 100.769166 -127.609092)
		(width 0.127)
		(layer "In2.Cu")
		(net "PWM_OUT_ZONE_C")
	)
	(segment
		(start 101.150166 -136.471914)
		(end 102.112318 -137.434066)
		(width 0.127)
		(layer "In2.Cu")
		(net "PWM_OUT_ZONE_C")
	)
	(segment
		(start 107.099862 -41.800018)
		(end 106.316526 -41.800018)
		(width 0.127)
		(layer "In2.Cu")
		(net "PWM_OUT_ZONE_C")
	)
	(segment
		(start 101.150166 -127.990092)
		(end 101.150166 -136.471914)
		(width 0.127)
		(layer "In2.Cu")
		(net "PWM_OUT_ZONE_C")
	)
	(segment
		(start 101.557074 -174.392844)
		(end 100.690426 -174.392844)
		(width 0.127)
		(layer "In2.Cu")
		(net "PWM_OUT_ZONE_C")
	)
	(segment
		(start 101.328474 -46.78807)
		(end 101.328474 -123.796806)
		(width 0.127)
		(layer "In2.Cu")
		(net "PWM_OUT_ZONE_C")
	)
	(segment
		(start 102.112318 -137.434066)
		(end 102.112318 -173.8376)
		(width 0.127)
		(layer "In2.Cu")
		(net "PWM_OUT_ZONE_C")
	)
	(segment
		(start 106.316526 -41.800018)
		(end 101.328474 -46.78807)
		(width 0.127)
		(layer "In2.Cu")
		(net "PWM_OUT_ZONE_C")
	)
	(segment
		(start 86.802722 -173.32452)
		(end 85.95741 -173.32452)
		(width 0.127)
		(layer "In5.Cu")
		(net "PWM_OUT_ZONE_C")
	)
	(segment
		(start 95.885 -172.7962)
		(end 91.1733 -172.7962)
		(width 0.127)
		(layer "In5.Cu")
		(net "PWM_OUT_ZONE_C")
	)
	(segment
		(start 39.391082 -161.2138)
		(end 38.301168 -161.2138)
		(width 0.127)
		(layer "In5.Cu")
		(net "PWM_OUT_ZONE_C")
	)
	(segment
		(start 100.690426 -174.392844)
		(end 100.185728 -174.392844)
		(width 0.127)
		(layer "In5.Cu")
		(net "PWM_OUT_ZONE_C")
	)
	(segment
		(start 99.211384 -173.4185)
		(end 96.5073 -173.4185)
		(width 0.127)
		(layer "In5.Cu")
		(net "PWM_OUT_ZONE_C")
	)
	(segment
		(start 88.208866 -173.4185)
		(end 88.107266 -173.3169)
		(width 0.127)
		(layer "In5.Cu")
		(net "PWM_OUT_ZONE_C")
	)
	(segment
		(start 85.51799 -172.8851)
		(end 84.276946 -172.8851)
		(width 0.127)
		(layer "In5.Cu")
		(net "PWM_OUT_ZONE_C")
	)
	(segment
		(start 84.276946 -172.8851)
		(end 83.286346 -173.8757)
		(width 0.127)
		(layer "In5.Cu")
		(net "PWM_OUT_ZONE_C")
	)
	(segment
		(start 37.477446 -160.390078)
		(end 37.477446 -160.184846)
		(width 0.127)
		(layer "In5.Cu")
		(net "PWM_OUT_ZONE_C")
	)
	(segment
		(start 49.299876 -166.6367)
		(end 48.457358 -165.794182)
		(width 0.127)
		(layer "In5.Cu")
		(net "PWM_OUT_ZONE_C")
	)
	(segment
		(start 69.3674 -173.4312)
		(end 61.342016 -173.4312)
		(width 0.127)
		(layer "In5.Cu")
		(net "PWM_OUT_ZONE_C")
	)
	(segment
		(start 37.477446 -160.184846)
		(end 37.2872 -159.9946)
		(width 0.127)
		(layer "In5.Cu")
		(net "PWM_OUT_ZONE_C")
	)
	(segment
		(start 87.560658 -173.376844)
		(end 86.855046 -173.376844)
		(width 0.127)
		(layer "In5.Cu")
		(net "PWM_OUT_ZONE_C")
	)
	(segment
		(start 73.070974 -173.1137)
		(end 69.6849 -173.1137)
		(width 0.127)
		(layer "In5.Cu")
		(net "PWM_OUT_ZONE_C")
	)
	(segment
		(start 83.286346 -173.8757)
		(end 73.832974 -173.8757)
		(width 0.127)
		(layer "In5.Cu")
		(net "PWM_OUT_ZONE_C")
	)
	(segment
		(start 88.107266 -173.3169)
		(end 87.620602 -173.3169)
		(width 0.127)
		(layer "In5.Cu")
		(net "PWM_OUT_ZONE_C")
	)
	(segment
		(start 44.607988 -163.327588)
		(end 41.50487 -163.327588)
		(width 0.127)
		(layer "In5.Cu")
		(net "PWM_OUT_ZONE_C")
	)
	(segment
		(start 47.074582 -165.794182)
		(end 44.607988 -163.327588)
		(width 0.127)
		(layer "In5.Cu")
		(net "PWM_OUT_ZONE_C")
	)
	(segment
		(start 87.620602 -173.3169)
		(end 87.560658 -173.376844)
		(width 0.127)
		(layer "In5.Cu")
		(net "PWM_OUT_ZONE_C")
	)
	(segment
		(start 73.832974 -173.8757)
		(end 73.070974 -173.1137)
		(width 0.127)
		(layer "In5.Cu")
		(net "PWM_OUT_ZONE_C")
	)
	(segment
		(start 90.551 -173.4185)
		(end 88.208866 -173.4185)
		(width 0.127)
		(layer "In5.Cu")
		(net "PWM_OUT_ZONE_C")
	)
	(segment
		(start 91.1733 -172.7962)
		(end 90.551 -173.4185)
		(width 0.127)
		(layer "In5.Cu")
		(net "PWM_OUT_ZONE_C")
	)
	(segment
		(start 85.95741 -173.32452)
		(end 85.51799 -172.8851)
		(width 0.127)
		(layer "In5.Cu")
		(net "PWM_OUT_ZONE_C")
	)
	(segment
		(start 53.164994 -166.6367)
		(end 49.299876 -166.6367)
		(width 0.127)
		(layer "In5.Cu")
		(net "PWM_OUT_ZONE_C")
	)
	(segment
		(start 60.14085 -172.230034)
		(end 58.758328 -172.230034)
		(width 0.127)
		(layer "In5.Cu")
		(net "PWM_OUT_ZONE_C")
	)
	(segment
		(start 69.6849 -173.1137)
		(end 69.3674 -173.4312)
		(width 0.127)
		(layer "In5.Cu")
		(net "PWM_OUT_ZONE_C")
	)
	(segment
		(start 86.855046 -173.376844)
		(end 86.802722 -173.32452)
		(width 0.127)
		(layer "In5.Cu")
		(net "PWM_OUT_ZONE_C")
	)
	(segment
		(start 100.185728 -174.392844)
		(end 99.211384 -173.4185)
		(width 0.127)
		(layer "In5.Cu")
		(net "PWM_OUT_ZONE_C")
	)
	(segment
		(start 61.342016 -173.4312)
		(end 60.14085 -172.230034)
		(width 0.127)
		(layer "In5.Cu")
		(net "PWM_OUT_ZONE_C")
	)
	(segment
		(start 41.50487 -163.327588)
		(end 39.391082 -161.2138)
		(width 0.127)
		(layer "In5.Cu")
		(net "PWM_OUT_ZONE_C")
	)
	(segment
		(start 38.301168 -161.2138)
		(end 37.477446 -160.390078)
		(width 0.127)
		(layer "In5.Cu")
		(net "PWM_OUT_ZONE_C")
	)
	(segment
		(start 96.5073 -173.4185)
		(end 95.885 -172.7962)
		(width 0.127)
		(layer "In5.Cu")
		(net "PWM_OUT_ZONE_C")
	)
	(segment
		(start 48.457358 -165.794182)
		(end 47.074582 -165.794182)
		(width 0.127)
		(layer "In5.Cu")
		(net "PWM_OUT_ZONE_C")
	)
	(segment
		(start 58.758328 -172.230034)
		(end 53.164994 -166.6367)
		(width 0.127)
		(layer "In5.Cu")
		(net "PWM_OUT_ZONE_C")
	)
	(segment
		(start 169.810684 -117.937534)
		(end 171.301664 -117.937534)
		(width 0.127)
		(layer "F.Cu")
		(net "PQ4_D")
	)
	(segment
		(start 173.482 -120.239536)
		(end 172.974254 -120.747282)
		(width 0.127)
		(layer "F.Cu")
		(net "PQ4_D")
	)
	(segment
		(start 171.301664 -117.937534)
		(end 171.494196 -118.130066)
		(width 0.127)
		(layer "F.Cu")
		(net "PQ4_D")
	)
	(segment
		(start 172.974254 -120.747282)
		(end 171.810172 -120.747282)
		(width 0.127)
		(layer "F.Cu")
		(net "PQ4_D")
	)
	(segment
		(start 171.494196 -119.40794)
		(end 171.3484 -119.553736)
		(width 0.127)
		(layer "F.Cu")
		(net "PQ4_D")
	)
	(segment
		(start 171.3484 -120.28551)
		(end 171.3484 -119.553736)
		(width 0.127)
		(layer "F.Cu")
		(net "PQ4_D")
	)
	(segment
		(start 171.494196 -118.130066)
		(end 171.494196 -119.40794)
		(width 0.127)
		(layer "F.Cu")
		(net "PQ4_D")
	)
	(segment
		(start 171.810172 -120.747282)
		(end 171.3484 -120.28551)
		(width 0.127)
		(layer "F.Cu")
		(net "PQ4_D")
	)
	(via
		(at 171.810172 -120.747282)
		(size 0.6604)
		(drill 0.3302)
		(layers "F.Cu" "B.Cu")
		(net "PQ4_D")
	)
	(segment
		(start 90.941906 -46.162976)
		(end 91.433904 -46.654974)
		(width 0.127)
		(layer "F.Cu")
		(net "PQ2_D")
	)
	(segment
		(start 91.433904 -49.209198)
		(end 92.070936 -49.84623)
		(width 0.127)
		(layer "F.Cu")
		(net "PQ2_D")
	)
	(segment
		(start 91.00947 -49.953926)
		(end 90.579194 -50.384202)
		(width 0.127)
		(layer "F.Cu")
		(net "PQ2_D")
	)
	(segment
		(start 89.622122 -46.396402)
		(end 89.855548 -46.162976)
		(width 0.127)
		(layer "F.Cu")
		(net "PQ2_D")
	)
	(segment
		(start 90.579194 -50.384202)
		(end 90.579194 -50.892456)
		(width 0.127)
		(layer "F.Cu")
		(net "PQ2_D")
	)
	(segment
		(start 92.070936 -49.84623)
		(end 92.070936 -49.953926)
		(width 0.127)
		(layer "F.Cu")
		(net "PQ2_D")
	)
	(segment
		(start 89.622122 -47.19701)
		(end 89.622122 -46.396402)
		(width 0.127)
		(layer "F.Cu")
		(net "PQ2_D")
	)
	(segment
		(start 89.908888 -47.483776)
		(end 89.622122 -47.19701)
		(width 0.127)
		(layer "F.Cu")
		(net "PQ2_D")
	)
	(segment
		(start 91.433904 -46.654974)
		(end 91.433904 -49.209198)
		(width 0.127)
		(layer "F.Cu")
		(net "PQ2_D")
	)
	(segment
		(start 92.070936 -49.953926)
		(end 91.00947 -49.953926)
		(width 0.127)
		(layer "F.Cu")
		(net "PQ2_D")
	)
	(segment
		(start 89.855548 -46.162976)
		(end 90.941906 -46.162976)
		(width 0.127)
		(layer "F.Cu")
		(net "PQ2_D")
	)
	(via
		(at 89.855548 -46.162976)
		(size 0.6604)
		(drill 0.3302)
		(layers "F.Cu" "B.Cu")
		(net "PQ2_D")
	)
	(via
		(at 208.035144 -122.275092)
		(size 0.6604)
		(drill 0.3302)
		(layers "F.Cu" "B.Cu")
		(net "P1V5_OUT")
	)
	(via
		(at 210.693 -122.301)
		(size 0.508)
		(drill 0.254)
		(layers "F.Cu" "B.Cu")
		(net "P1V5_OUT")
	)
	(segment
		(start 212.2424 -122.301)
		(end 210.693 -122.301)
		(width 1.016)
		(layer "B.Cu")
		(net "P1V5_OUT")
	)
	(segment
		(start 16.340582 -134.4676)
		(end 12.7127 -134.4676)
		(width 0.127)
		(layer "F.Cu")
		(net "MEM_PAR")
	)
	(segment
		(start 10.8331 -134.0231)
		(end 10.326624 -134.529576)
		(width 0.127)
		(layer "F.Cu")
		(net "MEM_PAR")
	)
	(segment
		(start 18.434558 -136.561576)
		(end 16.340582 -134.4676)
		(width 0.127)
		(layer "F.Cu")
		(net "MEM_PAR")
	)
	(segment
		(start 10.32256 -135.290052)
		(end 10.326624 -135.285988)
		(width 0.127)
		(layer "F.Cu")
		(net "MEM_PAR")
	)
	(segment
		(start 10.326624 -134.529576)
		(end 10.326624 -135.285988)
		(width 0.127)
		(layer "F.Cu")
		(net "MEM_PAR")
	)
	(segment
		(start 9.32561 -135.290052)
		(end 10.32256 -135.290052)
		(width 0.127)
		(layer "F.Cu")
		(net "MEM_PAR")
	)
	(segment
		(start 12.2682 -134.0231)
		(end 10.8331 -134.0231)
		(width 0.127)
		(layer "F.Cu")
		(net "MEM_PAR")
	)
	(segment
		(start 12.7127 -134.4676)
		(end 12.2682 -134.0231)
		(width 0.127)
		(layer "F.Cu")
		(net "MEM_PAR")
	)
	(via
		(at 12.7127 -134.4676)
		(size 0.6604)
		(drill 0.3302)
		(layers "F.Cu" "B.Cu")
		(net "MEM_PAR")
	)
	(segment
		(start 38.38448 -154.974544)
		(end 38.38448 -153.758646)
		(width 0.127)
		(layer "F.Cu")
		(net "FAN_PWM1_BMC")
	)
	(segment
		(start 38.38448 -153.758646)
		(end 39.174928 -152.968198)
		(width 0.127)
		(layer "F.Cu")
		(net "FAN_PWM1_BMC")
	)
	(segment
		(start 41.148 -152.968198)
		(end 41.5163 -152.599898)
		(width 0.127)
		(layer "F.Cu")
		(net "FAN_PWM1_BMC")
	)
	(segment
		(start 36.7157 -156.643324)
		(end 38.38448 -154.974544)
		(width 0.127)
		(layer "F.Cu")
		(net "FAN_PWM1_BMC")
	)
	(segment
		(start 41.5163 -152.599898)
		(end 41.699942 -152.599898)
		(width 0.127)
		(layer "F.Cu")
		(net "FAN_PWM1_BMC")
	)
	(segment
		(start 36.9062 -158.1785)
		(end 36.7157 -157.988)
		(width 0.127)
		(layer "F.Cu")
		(net "FAN_PWM1_BMC")
	)
	(segment
		(start 39.174928 -152.968198)
		(end 41.148 -152.968198)
		(width 0.127)
		(layer "F.Cu")
		(net "FAN_PWM1_BMC")
	)
	(segment
		(start 36.7157 -157.052264)
		(end 36.7157 -156.643324)
		(width 0.127)
		(layer "F.Cu")
		(net "FAN_PWM1_BMC")
	)
	(segment
		(start 36.7157 -157.988)
		(end 36.7157 -157.052264)
		(width 0.127)
		(layer "F.Cu")
		(net "FAN_PWM1_BMC")
	)
	(via
		(at 36.7157 -157.052264)
		(size 0.6604)
		(drill 0.3302)
		(layers "F.Cu" "B.Cu")
		(net "FAN_PWM1_BMC")
	)
	(segment
		(start 42.042842 -153.057098)
		(end 42.500042 -152.599898)
		(width 0.127)
		(layer "F.Cu")
		(net "FAN_PWM0_BMC")
	)
	(segment
		(start 40.338502 -153.768298)
		(end 41.052496 -153.768298)
		(width 0.127)
		(layer "F.Cu")
		(net "FAN_PWM0_BMC")
	)
	(segment
		(start 37.9095 -156.1973)
		(end 40.338502 -153.768298)
		(width 0.127)
		(layer "F.Cu")
		(net "FAN_PWM0_BMC")
	)
	(segment
		(start 41.557702 -153.057098)
		(end 42.042842 -153.057098)
		(width 0.127)
		(layer "F.Cu")
		(net "FAN_PWM0_BMC")
	)
	(segment
		(start 37.9095 -156.9847)
		(end 37.9095 -156.1973)
		(width 0.127)
		(layer "F.Cu")
		(net "FAN_PWM0_BMC")
	)
	(segment
		(start 41.268142 -153.552652)
		(end 41.268142 -153.346658)
		(width 0.127)
		(layer "F.Cu")
		(net "FAN_PWM0_BMC")
	)
	(segment
		(start 41.268142 -153.346658)
		(end 41.557702 -153.057098)
		(width 0.127)
		(layer "F.Cu")
		(net "FAN_PWM0_BMC")
	)
	(segment
		(start 37.9095 -156.9847)
		(end 37.9095 -158.1404)
		(width 0.127)
		(layer "F.Cu")
		(net "FAN_PWM0_BMC")
	)
	(segment
		(start 37.9095 -158.1404)
		(end 37.9476 -158.1785)
		(width 0.127)
		(layer "F.Cu")
		(net "FAN_PWM0_BMC")
	)
	(segment
		(start 41.052496 -153.768298)
		(end 41.268142 -153.552652)
		(width 0.127)
		(layer "F.Cu")
		(net "FAN_PWM0_BMC")
	)
	(via
		(at 37.9095 -156.9847)
		(size 0.6604)
		(drill 0.3302)
		(layers "F.Cu" "B.Cu")
		(net "FAN_PWM0_BMC")
	)
	(segment
		(start 75.175872 -137.922)
		(end 75.688444 -138.434572)
		(width 0.127)
		(layer "F.Cu")
		(net "DEBUG_HDR_UART_SEL")
	)
	(segment
		(start 75.688444 -138.434572)
		(end 76.505816 -138.434572)
		(width 0.127)
		(layer "F.Cu")
		(net "DEBUG_HDR_UART_SEL")
	)
	(segment
		(start 94.937326 -143.629126)
		(end 95.996506 -143.629126)
		(width 0.127)
		(layer "F.Cu")
		(net "DEBUG_HDR_UART_SEL")
	)
	(segment
		(start 74.7395 -137.033)
		(end 74.7395 -137.922)
		(width 0.127)
		(layer "F.Cu")
		(net "DEBUG_HDR_UART_SEL")
	)
	(segment
		(start 92.0242 -141.0208)
		(end 92.329 -141.0208)
		(width 0.127)
		(layer "F.Cu")
		(net "DEBUG_HDR_UART_SEL")
	)
	(segment
		(start 72.621648 -136.8425)
		(end 73.4187 -136.8425)
		(width 0.127)
		(layer "F.Cu")
		(net "DEBUG_HDR_UART_SEL")
	)
	(segment
		(start 76.837794 -138.76655)
		(end 77.737208 -138.76655)
		(width 0.127)
		(layer "F.Cu")
		(net "DEBUG_HDR_UART_SEL")
	)
	(segment
		(start 73.4187 -136.8425)
		(end 74.4601 -136.8425)
		(width 0.127)
		(layer "F.Cu")
		(net "DEBUG_HDR_UART_SEL")
	)
	(segment
		(start 74.7395 -137.922)
		(end 75.175872 -137.922)
		(width 0.127)
		(layer "F.Cu")
		(net "DEBUG_HDR_UART_SEL")
	)
	(segment
		(start 74.4601 -136.8425)
		(end 74.549 -136.8425)
		(width 0.127)
		(layer "F.Cu")
		(net "DEBUG_HDR_UART_SEL")
	)
	(segment
		(start 74.549 -136.8425)
		(end 74.7395 -137.033)
		(width 0.127)
		(layer "F.Cu")
		(net "DEBUG_HDR_UART_SEL")
	)
	(segment
		(start 92.329 -141.0208)
		(end 94.937326 -143.629126)
		(width 0.127)
		(layer "F.Cu")
		(net "DEBUG_HDR_UART_SEL")
	)
	(segment
		(start 76.505816 -138.434572)
		(end 76.837794 -138.76655)
		(width 0.127)
		(layer "F.Cu")
		(net "DEBUG_HDR_UART_SEL")
	)
	(via
		(at 92.0242 -141.0208)
		(size 0.508)
		(drill 0.254)
		(layers "F.Cu" "B.Cu")
		(net "DEBUG_HDR_UART_SEL")
	)
	(via
		(at 90.5002 -139.4714)
		(size 0.6096)
		(drill 0.3048)
		(layers "F.Cu" "B.Cu")
		(net "DEBUG_HDR_UART_SEL")
	)
	(via
		(at 72.621648 -136.8425)
		(size 0.508)
		(drill 0.254)
		(layers "F.Cu" "B.Cu")
		(net "DEBUG_HDR_UART_SEL")
	)
	(segment
		(start 92.0242 -141.0208)
		(end 91.894914 -141.0208)
		(width 0.127)
		(layer "B.Cu")
		(net "DEBUG_HDR_UART_SEL")
	)
	(segment
		(start 90.435684 -138.48588)
		(end 90.435684 -139.406884)
		(width 0.127)
		(layer "B.Cu")
		(net "DEBUG_HDR_UART_SEL")
	)
	(segment
		(start 90.435684 -139.406884)
		(end 90.5002 -139.4714)
		(width 0.127)
		(layer "B.Cu")
		(net "DEBUG_HDR_UART_SEL")
	)
	(segment
		(start 90.5002 -139.626086)
		(end 90.5002 -139.4714)
		(width 0.127)
		(layer "B.Cu")
		(net "DEBUG_HDR_UART_SEL")
	)
	(segment
		(start 91.894914 -141.0208)
		(end 90.5002 -139.626086)
		(width 0.127)
		(layer "B.Cu")
		(net "DEBUG_HDR_UART_SEL")
	)
	(segment
		(start 86.182454 -137.950448)
		(end 87.478616 -137.950448)
		(width 0.127)
		(layer "In5.Cu")
		(net "DEBUG_HDR_UART_SEL")
	)
	(segment
		(start 85.809328 -137.577322)
		(end 86.182454 -137.950448)
		(width 0.127)
		(layer "In5.Cu")
		(net "DEBUG_HDR_UART_SEL")
	)
	(segment
		(start 87.889588 -138.36142)
		(end 89.36482 -138.36142)
		(width 0.127)
		(layer "In5.Cu")
		(net "DEBUG_HDR_UART_SEL")
	)
	(segment
		(start 72.621648 -136.8425)
		(end 73.35647 -137.577322)
		(width 0.127)
		(layer "In5.Cu")
		(net "DEBUG_HDR_UART_SEL")
	)
	(segment
		(start 73.35647 -137.577322)
		(end 85.809328 -137.577322)
		(width 0.127)
		(layer "In5.Cu")
		(net "DEBUG_HDR_UART_SEL")
	)
	(segment
		(start 87.478616 -137.950448)
		(end 87.889588 -138.36142)
		(width 0.127)
		(layer "In5.Cu")
		(net "DEBUG_HDR_UART_SEL")
	)
	(segment
		(start 89.36482 -138.36142)
		(end 92.0242 -141.0208)
		(width 0.127)
		(layer "In5.Cu")
		(net "DEBUG_HDR_UART_SEL")
	)
	(segment
		(start 48.899826 -138.199876)
		(end 49.299876 -137.799826)
		(width 0.127)
		(layer "F.Cu")
		(net "BMC_PEREXT")
	)
	(via
		(at 49.299876 -137.799826)
		(size 0.4572)
		(drill 0.2032)
		(layers "F.Cu" "B.Cu")
		(net "BMC_PEREXT")
	)
	(via
		(at 49.515268 -136.270746)
		(size 0.6096)
		(drill 0.3048)
		(layers "F.Cu" "B.Cu")
		(net "BMC_PEREXT")
	)
	(segment
		(start 49.401222 -136.1567)
		(end 49.515268 -136.270746)
		(width 0.127)
		(layer "B.Cu")
		(net "BMC_PEREXT")
	)
	(segment
		(start 49.299876 -137.799826)
		(end 49.693576 -137.406126)
		(width 0.127)
		(layer "B.Cu")
		(net "BMC_PEREXT")
	)
	(segment
		(start 48.514 -136.1567)
		(end 49.401222 -136.1567)
		(width 0.127)
		(layer "B.Cu")
		(net "BMC_PEREXT")
	)
	(segment
		(start 49.693576 -136.449054)
		(end 49.515268 -136.270746)
		(width 0.127)
		(layer "B.Cu")
		(net "BMC_PEREXT")
	)
	(segment
		(start 49.693576 -137.406126)
		(end 49.693576 -136.449054)
		(width 0.127)
		(layer "B.Cu")
		(net "BMC_PEREXT")
	)
	(segment
		(start 23.167086 -126.083314)
		(end 22.5806 -126.6698)
		(width 0.127)
		(layer "F.Cu")
		(net "BMC_HBLED_R")
	)
	(segment
		(start 23.777956 -127.343408)
		(end 23.254208 -127.343408)
		(width 0.127)
		(layer "F.Cu")
		(net "BMC_HBLED_R")
	)
	(segment
		(start 23.254208 -127.343408)
		(end 22.5806 -126.6698)
		(width 0.127)
		(layer "F.Cu")
		(net "BMC_HBLED_R")
	)
	(segment
		(start 23.756874 -126.083314)
		(end 23.167086 -126.083314)
		(width 0.127)
		(layer "F.Cu")
		(net "BMC_HBLED_R")
	)
	(via
		(at 22.5806 -126.6698)
		(size 0.6604)
		(drill 0.3302)
		(layers "F.Cu" "B.Cu")
		(net "BMC_HBLED_R")
	)
	(segment
		(start 50.500026 -148.60016)
		(end 50.500026 -148.599906)
		(width 0.254)
		(layer "F.Cu")
		(net "VPLLAV33")
	)
	(segment
		(start 50.899822 -148.999956)
		(end 50.500026 -148.60016)
		(width 0.254)
		(layer "F.Cu")
		(net "VPLLAV33")
	)
	(segment
		(start 50.099976 -149.00021)
		(end 49.699926 -148.60016)
		(width 0.254)
		(layer "F.Cu")
		(net "VPLLAV33")
	)
	(segment
		(start 49.699926 -148.60016)
		(end 49.699926 -148.599906)
		(width 0.254)
		(layer "F.Cu")
		(net "VPLLAV33")
	)
	(via
		(at 50.899822 -148.999956)
		(size 0.4572)
		(drill 0.2032)
		(layers "F.Cu" "B.Cu")
		(net "VPLLAV33")
	)
	(via
		(at 59.2074 -158.3436)
		(size 0.6096)
		(drill 0.3048)
		(layers "F.Cu" "B.Cu")
		(net "VPLLAV33")
	)
	(via
		(at 50.099976 -149.00021)
		(size 0.4572)
		(drill 0.2032)
		(layers "F.Cu" "B.Cu")
		(net "VPLLAV33")
	)
	(via
		(at 56.194452 -157.613096)
		(size 0.508)
		(drill 0.254)
		(layers "F.Cu" "B.Cu")
		(net "VPLLAV33")
	)
	(segment
		(start 50.099976 -149.00021)
		(end 50.10023 -148.999956)
		(width 0.2032)
		(layer "B.Cu")
		(net "VPLLAV33")
	)
	(segment
		(start 50.10023 -148.999956)
		(end 50.899822 -148.999956)
		(width 0.2032)
		(layer "B.Cu")
		(net "VPLLAV33")
	)
	(segment
		(start 57.08396 -156.931868)
		(end 57.08396 -153.557986)
		(width 0.508)
		(layer "In2.Cu")
		(net "VPLLAV33")
	)
	(segment
		(start 51.857656 -148.606256)
		(end 51.86299 -148.606256)
		(width 0.127)
		(layer "In2.Cu")
		(net "VPLLAV33")
	)
	(segment
		(start 57.08396 -153.557986)
		(end 56.872632 -153.346658)
		(width 0.508)
		(layer "In2.Cu")
		(net "VPLLAV33")
	)
	(segment
		(start 55.88 -149.2504)
		(end 55.88 -148.7932)
		(width 0.127)
		(layer "In2.Cu")
		(net "VPLLAV33")
	)
	(segment
		(start 56.872632 -153.346658)
		(end 56.872632 -153.203656)
		(width 0.508)
		(layer "In2.Cu")
		(net "VPLLAV33")
	)
	(segment
		(start 55.566056 -147.806156)
		(end 55.88 -148.1201)
		(width 0.127)
		(layer "In2.Cu")
		(net "VPLLAV33")
	)
	(segment
		(start 52.106068 -148.363432)
		(end 52.336446 -148.59381)
		(width 0.127)
		(layer "In2.Cu")
		(net "VPLLAV33")
	)
	(segment
		(start 52.093368 -148.836634)
		(end 52.093368 -149.150578)
		(width 0.127)
		(layer "In2.Cu")
		(net "VPLLAV33")
	)
	(segment
		(start 51.86299 -148.606256)
		(end 52.093368 -148.836634)
		(width 0.127)
		(layer "In2.Cu")
		(net "VPLLAV33")
	)
	(segment
		(start 52.093368 -149.150578)
		(end 52.34813 -149.40534)
		(width 0.127)
		(layer "In2.Cu")
		(net "VPLLAV33")
	)
	(segment
		(start 52.336446 -148.59381)
		(end 55.18531 -148.59381)
		(width 0.127)
		(layer "In2.Cu")
		(net "VPLLAV33")
	)
	(segment
		(start 56.194452 -157.613096)
		(end 56.402732 -157.613096)
		(width 0.508)
		(layer "In2.Cu")
		(net "VPLLAV33")
	)
	(segment
		(start 52.34813 -149.40534)
		(end 55.72506 -149.40534)
		(width 0.127)
		(layer "In2.Cu")
		(net "VPLLAV33")
	)
	(segment
		(start 56.402732 -157.613096)
		(end 57.08396 -156.931868)
		(width 0.508)
		(layer "In2.Cu")
		(net "VPLLAV33")
	)
	(segment
		(start 55.18531 -148.59381)
		(end 55.3847 -148.7932)
		(width 0.127)
		(layer "In2.Cu")
		(net "VPLLAV33")
	)
	(segment
		(start 51.685444 -147.806156)
		(end 55.566056 -147.806156)
		(width 0.127)
		(layer "In2.Cu")
		(net "VPLLAV33")
	)
	(segment
		(start 55.88 -148.1201)
		(end 55.88 -148.7932)
		(width 0.127)
		(layer "In2.Cu")
		(net "VPLLAV33")
	)
	(segment
		(start 56.555132 -152.886156)
		(end 56.555132 -149.040342)
		(width 0.508)
		(layer "In2.Cu")
		(net "VPLLAV33")
	)
	(segment
		(start 55.72506 -149.40534)
		(end 55.88 -149.2504)
		(width 0.127)
		(layer "In2.Cu")
		(net "VPLLAV33")
	)
	(segment
		(start 56.555132 -149.040342)
		(end 56.30799 -148.7932)
		(width 0.508)
		(layer "In2.Cu")
		(net "VPLLAV33")
	)
	(segment
		(start 56.872632 -153.203656)
		(end 56.555132 -152.886156)
		(width 0.508)
		(layer "In2.Cu")
		(net "VPLLAV33")
	)
	(segment
		(start 55.3847 -148.7932)
		(end 55.88 -148.7932)
		(width 0.127)
		(layer "In2.Cu")
		(net "VPLLAV33")
	)
	(segment
		(start 56.30799 -148.7932)
		(end 55.88 -148.7932)
		(width 0.508)
		(layer "In2.Cu")
		(net "VPLLAV33")
	)
	(segment
		(start 48.499776 -149.800056)
		(end 48.499776 -149.799802)
		(width 0.254)
		(layer "F.Cu")
		(net "V1PLLAV11")
	)
	(segment
		(start 48.499776 -150.599648)
		(end 48.09998 -150.199852)
		(width 0.254)
		(layer "F.Cu")
		(net "V1PLLAV11")
	)
	(segment
		(start 48.499776 -149.799802)
		(end 48.09998 -149.400006)
		(width 0.254)
		(layer "F.Cu")
		(net "V1PLLAV11")
	)
	(segment
		(start 48.499776 -150.599902)
		(end 48.499776 -150.599648)
		(width 0.254)
		(layer "F.Cu")
		(net "V1PLLAV11")
	)
	(via
		(at 48.499776 -150.599902)
		(size 0.4572)
		(drill 0.2032)
		(layers "F.Cu" "B.Cu")
		(net "V1PLLAV11")
	)
	(via
		(at 48.499776 -149.800056)
		(size 0.4572)
		(drill 0.2032)
		(layers "F.Cu" "B.Cu")
		(net "V1PLLAV11")
	)
	(via
		(at 46.8122 -151.003)
		(size 0.6096)
		(drill 0.3048)
		(layers "F.Cu" "B.Cu")
		(net "V1PLLAV11")
	)
	(segment
		(start 48.499776 -150.599902)
		(end 48.499776 -149.800056)
		(width 0.2032)
		(layer "B.Cu")
		(net "V1PLLAV11")
	)
	(segment
		(start 70.18782 -179.289202)
		(end 70.18655 -179.289202)
		(width 0.254)
		(layer "F.Cu")
		(net "TPS74801_P2V5_STBY_SS")
	)
	(segment
		(start 70.419214 -179.057808)
		(end 70.18782 -179.289202)
		(width 0.254)
		(layer "F.Cu")
		(net "TPS74801_P2V5_STBY_SS")
	)
	(segment
		(start 69.572124 -179.904898)
		(end 70.18655 -179.290472)
		(width 0.254)
		(layer "F.Cu")
		(net "TPS74801_P2V5_STBY_SS")
	)
	(segment
		(start 70.18655 -179.290472)
		(end 70.18655 -179.289202)
		(width 0.254)
		(layer "F.Cu")
		(net "TPS74801_P2V5_STBY_SS")
	)
	(segment
		(start 72.616314 -179.057808)
		(end 70.419214 -179.057808)
		(width 0.254)
		(layer "F.Cu")
		(net "TPS74801_P2V5_STBY_SS")
	)
	(segment
		(start 69.215762 -179.904898)
		(end 69.572124 -179.904898)
		(width 0.254)
		(layer "F.Cu")
		(net "TPS74801_P2V5_STBY_SS")
	)
	(via
		(at 70.18655 -179.289202)
		(size 0.6604)
		(drill 0.3302)
		(layers "F.Cu" "B.Cu")
		(net "TPS74801_P2V5_STBY_SS")
	)
	(via
		(at 78.50886 -175.395128)
		(size 0.6604)
		(drill 0.3302)
		(layers "F.Cu" "B.Cu")
		(net "TPS74801_P2V5_STBY_OUT")
	)
	(via
		(at 72.771 -176.149)
		(size 0.6604)
		(drill 0.3302)
		(layers "F.Cu" "B.Cu")
		(net "TPS74801_P2V5_STBY_FB")
	)
	(segment
		(start 69.96938 -183.738266)
		(end 69.938646 -183.769)
		(width 0.254)
		(layer "F.Cu")
		(net "TPS74801_P2V5_STBY_EN")
	)
	(segment
		(start 72.616314 -181.657752)
		(end 70.012052 -181.657752)
		(width 0.254)
		(layer "F.Cu")
		(net "TPS74801_P2V5_STBY_EN")
	)
	(segment
		(start 69.96938 -182.60568)
		(end 69.96938 -181.65572)
		(width 0.254)
		(layer "F.Cu")
		(net "TPS74801_P2V5_STBY_EN")
	)
	(segment
		(start 70.012052 -181.657752)
		(end 69.9897 -181.6354)
		(width 0.254)
		(layer "F.Cu")
		(net "TPS74801_P2V5_STBY_EN")
	)
	(segment
		(start 69.96938 -182.60568)
		(end 69.96938 -183.738266)
		(width 0.254)
		(layer "F.Cu")
		(net "TPS74801_P2V5_STBY_EN")
	)
	(segment
		(start 69.938646 -183.769)
		(end 68.7451 -183.769)
		(width 0.254)
		(layer "F.Cu")
		(net "TPS74801_P2V5_STBY_EN")
	)
	(segment
		(start 69.96938 -181.65572)
		(end 69.9897 -181.6354)
		(width 0.254)
		(layer "F.Cu")
		(net "TPS74801_P2V5_STBY_EN")
	)
	(via
		(at 69.938646 -183.769)
		(size 0.6604)
		(drill 0.3302)
		(layers "F.Cu" "B.Cu")
		(net "TPS74801_P2V5_STBY_EN")
	)
	(segment
		(start 72.9996 -185.264044)
		(end 73.05548 -185.319924)
		(width 0.254)
		(layer "F.Cu")
		(net "TPS74801_P2V5_STBY_BIAS")
	)
	(segment
		(start 73.05548 -185.319924)
		(end 73.05548 -185.46318)
		(width 0.254)
		(layer "F.Cu")
		(net "TPS74801_P2V5_STBY_BIAS")
	)
	(segment
		(start 73.000362 -185.518298)
		(end 71.90232 -185.518298)
		(width 0.254)
		(layer "F.Cu")
		(net "TPS74801_P2V5_STBY_BIAS")
	)
	(segment
		(start 73.791064 -182.832502)
		(end 73.791064 -183.628792)
		(width 0.254)
		(layer "F.Cu")
		(net "TPS74801_P2V5_STBY_BIAS")
	)
	(segment
		(start 72.9996 -184.420256)
		(end 72.9996 -185.264044)
		(width 0.254)
		(layer "F.Cu")
		(net "TPS74801_P2V5_STBY_BIAS")
	)
	(segment
		(start 70.744842 -185.52287)
		(end 71.897748 -185.52287)
		(width 0.254)
		(layer "F.Cu")
		(net "TPS74801_P2V5_STBY_BIAS")
	)
	(segment
		(start 73.791064 -183.628792)
		(end 72.9996 -184.420256)
		(width 0.254)
		(layer "F.Cu")
		(net "TPS74801_P2V5_STBY_BIAS")
	)
	(segment
		(start 73.05548 -185.46318)
		(end 73.000362 -185.518298)
		(width 0.254)
		(layer "F.Cu")
		(net "TPS74801_P2V5_STBY_BIAS")
	)
	(segment
		(start 71.897748 -185.52287)
		(end 71.90232 -185.518298)
		(width 0.254)
		(layer "F.Cu")
		(net "TPS74801_P2V5_STBY_BIAS")
	)
	(via
		(at 71.90232 -185.518298)
		(size 0.6604)
		(drill 0.3302)
		(layers "F.Cu" "B.Cu")
		(net "TPS74801_P2V5_STBY_BIAS")
	)
	(via
		(at 203.298806 -122.466862)
		(size 0.6604)
		(drill 0.3302)
		(layers "F.Cu" "B.Cu")
		(net "TPS74801_P1V5_FB")
	)
	(segment
		(start 13.571728 -167.825928)
		(end 12.5222 -166.7764)
		(width 0.254)
		(layer "F.Cu")
		(net "TPS74801_P1V2_STBY_SS")
	)
	(segment
		(start 12.0269 -167.8178)
		(end 12.0269 -167.2717)
		(width 0.254)
		(layer "F.Cu")
		(net "TPS74801_P1V2_STBY_SS")
	)
	(segment
		(start 14.216634 -167.825928)
		(end 13.571728 -167.825928)
		(width 0.254)
		(layer "F.Cu")
		(net "TPS74801_P1V2_STBY_SS")
	)
	(segment
		(start 12.0269 -167.2717)
		(end 12.5222 -166.7764)
		(width 0.254)
		(layer "F.Cu")
		(net "TPS74801_P1V2_STBY_SS")
	)
	(via
		(at 12.5222 -166.7764)
		(size 0.6604)
		(drill 0.3302)
		(layers "F.Cu" "B.Cu")
		(net "TPS74801_P1V2_STBY_SS")
	)
	(via
		(at 21.1963 -164.24148)
		(size 0.6604)
		(drill 0.3302)
		(layers "F.Cu" "B.Cu")
		(net "TPS74801_P1V2_STBY_OUT")
	)
	(via
		(at 18.60931 -164.42817)
		(size 0.6604)
		(drill 0.3302)
		(layers "F.Cu" "B.Cu")
		(net "TPS74801_P1V2_STBY_OUT")
	)
	(via
		(at 14.19733 -163.446714)
		(size 0.6604)
		(drill 0.3302)
		(layers "F.Cu" "B.Cu")
		(net "TPS74801_P1V2_STBY_FB")
	)
	(segment
		(start 14.216634 -170.796712)
		(end 14.216634 -170.425872)
		(width 0.254)
		(layer "F.Cu")
		(net "TPS74801_P1V2_STBY_EN")
	)
	(segment
		(start 11.596116 -172.706284)
		(end 10.714482 -172.706284)
		(width 0.254)
		(layer "F.Cu")
		(net "TPS74801_P1V2_STBY_EN")
	)
	(segment
		(start 11.694922 -172.607478)
		(end 11.596116 -172.706284)
		(width 0.254)
		(layer "F.Cu")
		(net "TPS74801_P1V2_STBY_EN")
	)
	(segment
		(start 12.6746 -171.433236)
		(end 11.7348 -171.433236)
		(width 0.254)
		(layer "F.Cu")
		(net "TPS74801_P1V2_STBY_EN")
	)
	(segment
		(start 11.7094 -172.593)
		(end 11.694922 -172.607478)
		(width 0.254)
		(layer "F.Cu")
		(net "TPS74801_P1V2_STBY_EN")
	)
	(segment
		(start 12.6746 -171.433236)
		(end 13.58011 -171.433236)
		(width 0.254)
		(layer "F.Cu")
		(net "TPS74801_P1V2_STBY_EN")
	)
	(segment
		(start 11.7094 -171.458636)
		(end 11.7094 -172.593)
		(width 0.254)
		(layer "F.Cu")
		(net "TPS74801_P1V2_STBY_EN")
	)
	(segment
		(start 13.58011 -171.433236)
		(end 14.216634 -170.796712)
		(width 0.254)
		(layer "F.Cu")
		(net "TPS74801_P1V2_STBY_EN")
	)
	(segment
		(start 11.7348 -171.433236)
		(end 11.7094 -171.458636)
		(width 0.254)
		(layer "F.Cu")
		(net "TPS74801_P1V2_STBY_EN")
	)
	(via
		(at 11.694922 -172.607478)
		(size 0.6604)
		(drill 0.3302)
		(layers "F.Cu" "B.Cu")
		(net "TPS74801_P1V2_STBY_EN")
	)
	(segment
		(start 18.0594 -174.3456)
		(end 18.2372 -174.1678)
		(width 0.254)
		(layer "F.Cu")
		(net "TPS74801_P1V2_STBY_BIAS")
	)
	(segment
		(start 18.288 -174.117)
		(end 18.2372 -174.1678)
		(width 0.254)
		(layer "F.Cu")
		(net "TPS74801_P1V2_STBY_BIAS")
	)
	(segment
		(start 19.4564 -175.1965)
		(end 19.4564 -174.3202)
		(width 0.254)
		(layer "F.Cu")
		(net "TPS74801_P1V2_STBY_BIAS")
	)
	(segment
		(start 15.391384 -172.871384)
		(end 16.8656 -174.3456)
		(width 0.254)
		(layer "F.Cu")
		(net "TPS74801_P1V2_STBY_BIAS")
	)
	(segment
		(start 19.3294 -175.3235)
		(end 19.4564 -175.1965)
		(width 0.254)
		(layer "F.Cu")
		(net "TPS74801_P1V2_STBY_BIAS")
	)
	(segment
		(start 19.2532 -174.117)
		(end 18.288 -174.117)
		(width 0.254)
		(layer "F.Cu")
		(net "TPS74801_P1V2_STBY_BIAS")
	)
	(segment
		(start 19.4564 -174.3202)
		(end 19.371056 -174.234856)
		(width 0.254)
		(layer "F.Cu")
		(net "TPS74801_P1V2_STBY_BIAS")
	)
	(segment
		(start 16.8656 -174.3456)
		(end 18.0594 -174.3456)
		(width 0.254)
		(layer "F.Cu")
		(net "TPS74801_P1V2_STBY_BIAS")
	)
	(segment
		(start 15.391384 -171.600622)
		(end 15.391384 -172.871384)
		(width 0.254)
		(layer "F.Cu")
		(net "TPS74801_P1V2_STBY_BIAS")
	)
	(segment
		(start 19.371056 -174.234856)
		(end 19.2532 -174.117)
		(width 0.254)
		(layer "F.Cu")
		(net "TPS74801_P1V2_STBY_BIAS")
	)
	(via
		(at 19.371056 -174.234856)
		(size 0.6604)
		(drill 0.3302)
		(layers "F.Cu" "B.Cu")
		(net "TPS74801_P1V2_STBY_BIAS")
	)
	(segment
		(start 72.640952 -161.912046)
		(end 72.588628 -161.96437)
		(width 0.254)
		(layer "F.Cu")
		(net "TPS74801_P1V15_STBY_SS")
	)
	(segment
		(start 72.588628 -161.96437)
		(end 71.633842 -161.96437)
		(width 0.254)
		(layer "F.Cu")
		(net "TPS74801_P1V15_STBY_SS")
	)
	(segment
		(start 75.325478 -160.904428)
		(end 73.64857 -160.904428)
		(width 0.254)
		(layer "F.Cu")
		(net "TPS74801_P1V15_STBY_SS")
	)
	(segment
		(start 73.64857 -160.904428)
		(end 72.640952 -161.912046)
		(width 0.254)
		(layer "F.Cu")
		(net "TPS74801_P1V15_STBY_SS")
	)
	(via
		(at 72.640952 -161.912046)
		(size 0.6604)
		(drill 0.3302)
		(layers "F.Cu" "B.Cu")
		(net "TPS74801_P1V15_STBY_SS")
	)
	(via
		(at 79.85506 -157.69082)
		(size 0.6604)
		(drill 0.3302)
		(layers "F.Cu" "B.Cu")
		(net "TPS74801_P1V15_STBY_OUT")
	)
	(via
		(at 76.6318 -154.432)
		(size 0.6604)
		(drill 0.3302)
		(layers "F.Cu" "B.Cu")
		(net "TPS74801_P1V15_STBY_FB")
	)
	(segment
		(start 72.49414 -165.6334)
		(end 73.415398 -165.6334)
		(width 0.254)
		(layer "F.Cu")
		(net "TPS74801_P1V15_STBY_EN")
	)
	(segment
		(start 75.325478 -163.504372)
		(end 72.629268 -163.504372)
		(width 0.254)
		(layer "F.Cu")
		(net "TPS74801_P1V15_STBY_EN")
	)
	(segment
		(start 73.638918 -165.40988)
		(end 73.638918 -165.043612)
		(width 0.254)
		(layer "F.Cu")
		(net "TPS74801_P1V15_STBY_EN")
	)
	(segment
		(start 73.415398 -165.6334)
		(end 73.638918 -165.40988)
		(width 0.254)
		(layer "F.Cu")
		(net "TPS74801_P1V15_STBY_EN")
	)
	(segment
		(start 73.329292 -164.5793)
		(end 73.638918 -164.888926)
		(width 0.254)
		(layer "F.Cu")
		(net "TPS74801_P1V15_STBY_EN")
	)
	(segment
		(start 73.638918 -164.888926)
		(end 73.638918 -165.043612)
		(width 0.254)
		(layer "F.Cu")
		(net "TPS74801_P1V15_STBY_EN")
	)
	(segment
		(start 72.629268 -163.504372)
		(end 72.49414 -163.6395)
		(width 0.254)
		(layer "F.Cu")
		(net "TPS74801_P1V15_STBY_EN")
	)
	(segment
		(start 72.49414 -164.5793)
		(end 73.329292 -164.5793)
		(width 0.254)
		(layer "F.Cu")
		(net "TPS74801_P1V15_STBY_EN")
	)
	(segment
		(start 72.49414 -164.5793)
		(end 72.49414 -163.6395)
		(width 0.254)
		(layer "F.Cu")
		(net "TPS74801_P1V15_STBY_EN")
	)
	(via
		(at 73.638918 -165.043612)
		(size 0.6604)
		(drill 0.3302)
		(layers "F.Cu" "B.Cu")
		(net "TPS74801_P1V15_STBY_EN")
	)
	(segment
		(start 75.477878 -164.679122)
		(end 76.500228 -164.679122)
		(width 0.254)
		(layer "F.Cu")
		(net "TPS74801_P1V15_STBY_BIAS")
	)
	(segment
		(start 73.761346 -166.62781)
		(end 73.871328 -166.517828)
		(width 0.254)
		(layer "F.Cu")
		(net "TPS74801_P1V15_STBY_BIAS")
	)
	(segment
		(start 75.0316 -165.1254)
		(end 75.477878 -164.679122)
		(width 0.254)
		(layer "F.Cu")
		(net "TPS74801_P1V15_STBY_BIAS")
	)
	(segment
		(start 75.0316 -166.4208)
		(end 75.0316 -165.1254)
		(width 0.254)
		(layer "F.Cu")
		(net "TPS74801_P1V15_STBY_BIAS")
	)
	(segment
		(start 73.6092 -166.779956)
		(end 73.761346 -166.62781)
		(width 0.254)
		(layer "F.Cu")
		(net "TPS74801_P1V15_STBY_BIAS")
	)
	(segment
		(start 73.871328 -166.517828)
		(end 74.934572 -166.517828)
		(width 0.254)
		(layer "F.Cu")
		(net "TPS74801_P1V15_STBY_BIAS")
	)
	(segment
		(start 74.934572 -166.517828)
		(end 75.0316 -166.4208)
		(width 0.254)
		(layer "F.Cu")
		(net "TPS74801_P1V15_STBY_BIAS")
	)
	(segment
		(start 73.6092 -167.7543)
		(end 73.6092 -166.779956)
		(width 0.254)
		(layer "F.Cu")
		(net "TPS74801_P1V15_STBY_BIAS")
	)
	(via
		(at 73.761346 -166.62781)
		(size 0.6604)
		(drill 0.3302)
		(layers "F.Cu" "B.Cu")
		(net "TPS74801_P1V15_STBY_BIAS")
	)
	(segment
		(start 57.446672 -156.025596)
		(end 55.668164 -154.247088)
		(width 0.127)
		(layer "F.Cu")
		(net "TP_BMC_GPIOT6")
	)
	(segment
		(start 57.446672 -157.213808)
		(end 57.446672 -156.025596)
		(width 0.127)
		(layer "F.Cu")
		(net "TP_BMC_GPIOT6")
	)
	(segment
		(start 55.668164 -154.247088)
		(end 55.668164 -152.968198)
		(width 0.127)
		(layer "F.Cu")
		(net "TP_BMC_GPIOT6")
	)
	(segment
		(start 55.668164 -152.968198)
		(end 55.299864 -152.599898)
		(width 0.127)
		(layer "F.Cu")
		(net "TP_BMC_GPIOT6")
	)
	(segment
		(start 58.657998 -154.35834)
		(end 58.0644 -153.764742)
		(width 0.127)
		(layer "F.Cu")
		(net "TP_BMC_GPIOT0")
	)
	(segment
		(start 58.80354 -154.35834)
		(end 58.657998 -154.35834)
		(width 0.127)
		(layer "F.Cu")
		(net "TP_BMC_GPIOT0")
	)
	(segment
		(start 55.957724 -150.542752)
		(end 55.614824 -150.199852)
		(width 0.127)
		(layer "F.Cu")
		(net "TP_BMC_GPIOT0")
	)
	(segment
		(start 56.190896 -150.542752)
		(end 55.957724 -150.542752)
		(width 0.127)
		(layer "F.Cu")
		(net "TP_BMC_GPIOT0")
	)
	(segment
		(start 58.0644 -153.764742)
		(end 58.0644 -153.454862)
		(width 0.127)
		(layer "F.Cu")
		(net "TP_BMC_GPIOT0")
	)
	(segment
		(start 57.20842 -152.151842)
		(end 57.0992 -152.042622)
		(width 0.127)
		(layer "F.Cu")
		(net "TP_BMC_GPIOT0")
	)
	(segment
		(start 57.0992 -151.451056)
		(end 56.190896 -150.542752)
		(width 0.127)
		(layer "F.Cu")
		(net "TP_BMC_GPIOT0")
	)
	(segment
		(start 57.20842 -152.598882)
		(end 57.20842 -152.151842)
		(width 0.127)
		(layer "F.Cu")
		(net "TP_BMC_GPIOT0")
	)
	(segment
		(start 59.8424 -155.3972)
		(end 58.80354 -154.35834)
		(width 0.127)
		(layer "F.Cu")
		(net "TP_BMC_GPIOT0")
	)
	(segment
		(start 55.614824 -150.199852)
		(end 55.299864 -150.199852)
		(width 0.127)
		(layer "F.Cu")
		(net "TP_BMC_GPIOT0")
	)
	(segment
		(start 58.0644 -153.454862)
		(end 57.20842 -152.598882)
		(width 0.127)
		(layer "F.Cu")
		(net "TP_BMC_GPIOT0")
	)
	(segment
		(start 57.0992 -152.042622)
		(end 57.0992 -151.451056)
		(width 0.127)
		(layer "F.Cu")
		(net "TP_BMC_GPIOT0")
	)
	(segment
		(start 43.700192 -151.399748)
		(end 44.099988 -150.999952)
		(width 0.127)
		(layer "F.Cu")
		(net "TP_BMC_GPION7")
	)
	(segment
		(start 43.700192 -151.400002)
		(end 43.700192 -151.399748)
		(width 0.127)
		(layer "F.Cu")
		(net "TP_BMC_GPION7")
	)
	(via
		(at 43.700192 -151.400002)
		(size 0.4572)
		(drill 0.2032)
		(layers "F.Cu" "B.Cu")
		(net "TP_BMC_GPION7")
	)
	(segment
		(start 44.0944 -151.79421)
		(end 43.700192 -151.400002)
		(width 0.127)
		(layer "B.Cu")
		(net "TP_BMC_GPION7")
	)
	(segment
		(start 43.2308 -153.3144)
		(end 44.0944 -152.4508)
		(width 0.127)
		(layer "B.Cu")
		(net "TP_BMC_GPION7")
	)
	(segment
		(start 44.0944 -152.4508)
		(end 44.0944 -151.79421)
		(width 0.127)
		(layer "B.Cu")
		(net "TP_BMC_GPION7")
	)
	(segment
		(start 40.899842 -151.800052)
		(end 40.499792 -152.200102)
		(width 0.127)
		(layer "F.Cu")
		(net "TP_BMC_GPION6")
	)
	(via
		(at 40.499792 -152.200102)
		(size 0.4572)
		(drill 0.2032)
		(layers "F.Cu" "B.Cu")
		(net "TP_BMC_GPION6")
	)
	(segment
		(start 39.53764 -152.18156)
		(end 40.48125 -152.18156)
		(width 0.127)
		(layer "B.Cu")
		(net "TP_BMC_GPION6")
	)
	(segment
		(start 40.48125 -152.18156)
		(end 40.499792 -152.200102)
		(width 0.127)
		(layer "B.Cu")
		(net "TP_BMC_GPION6")
	)
	(segment
		(start 37.7952 -153.58364)
		(end 39.147242 -152.231598)
		(width 0.127)
		(layer "F.Cu")
		(net "TP_BMC_GPION5")
	)
	(segment
		(start 35.687 -157.133036)
		(end 37.7952 -155.024836)
		(width 0.127)
		(layer "F.Cu")
		(net "TP_BMC_GPION5")
	)
	(segment
		(start 39.66845 -152.231598)
		(end 40.099996 -151.800052)
		(width 0.127)
		(layer "F.Cu")
		(net "TP_BMC_GPION5")
	)
	(segment
		(start 37.7952 -155.024836)
		(end 37.7952 -153.58364)
		(width 0.127)
		(layer "F.Cu")
		(net "TP_BMC_GPION5")
	)
	(segment
		(start 35.687 -157.5562)
		(end 35.687 -157.133036)
		(width 0.127)
		(layer "F.Cu")
		(net "TP_BMC_GPION5")
	)
	(segment
		(start 39.147242 -152.231598)
		(end 39.66845 -152.231598)
		(width 0.127)
		(layer "F.Cu")
		(net "TP_BMC_GPION5")
	)
	(segment
		(start 41.699942 -151.800052)
		(end 41.299892 -152.200102)
		(width 0.127)
		(layer "F.Cu")
		(net "TP_BMC_GPION4")
	)
	(via
		(at 41.299892 -152.200102)
		(size 0.4572)
		(drill 0.2032)
		(layers "F.Cu" "B.Cu")
		(net "TP_BMC_GPION4")
	)
	(segment
		(start 41.122092 -152.377902)
		(end 41.299892 -152.200102)
		(width 0.127)
		(layer "B.Cu")
		(net "TP_BMC_GPION4")
	)
	(segment
		(start 39.457122 -154.500326)
		(end 40.289226 -153.668222)
		(width 0.127)
		(layer "B.Cu")
		(net "TP_BMC_GPION4")
	)
	(segment
		(start 41.122092 -152.628854)
		(end 41.122092 -152.377902)
		(width 0.127)
		(layer "B.Cu")
		(net "TP_BMC_GPION4")
	)
	(segment
		(start 40.289226 -153.46172)
		(end 41.122092 -152.628854)
		(width 0.127)
		(layer "B.Cu")
		(net "TP_BMC_GPION4")
	)
	(segment
		(start 40.289226 -153.668222)
		(end 40.289226 -153.46172)
		(width 0.127)
		(layer "B.Cu")
		(net "TP_BMC_GPION4")
	)
	(segment
		(start 39.457122 -154.728672)
		(end 39.457122 -154.500326)
		(width 0.127)
		(layer "B.Cu")
		(net "TP_BMC_GPION4")
	)
	(segment
		(start 42.900092 -152.199848)
		(end 43.299888 -151.800052)
		(width 0.127)
		(layer "F.Cu")
		(net "TP_BMC_GPION3")
	)
	(segment
		(start 42.900092 -152.200102)
		(end 42.900092 -152.199848)
		(width 0.127)
		(layer "F.Cu")
		(net "TP_BMC_GPION3")
	)
	(via
		(at 42.900092 -152.200102)
		(size 0.4572)
		(drill 0.2032)
		(layers "F.Cu" "B.Cu")
		(net "TP_BMC_GPION3")
	)
	(segment
		(start 42.900092 -152.517348)
		(end 42.36212 -153.05532)
		(width 0.127)
		(layer "B.Cu")
		(net "TP_BMC_GPION3")
	)
	(segment
		(start 41.020238 -155.983178)
		(end 40.350948 -155.983178)
		(width 0.127)
		(layer "B.Cu")
		(net "TP_BMC_GPION3")
	)
	(segment
		(start 42.900092 -152.200102)
		(end 42.900092 -152.517348)
		(width 0.127)
		(layer "B.Cu")
		(net "TP_BMC_GPION3")
	)
	(segment
		(start 42.36212 -153.05532)
		(end 42.36212 -154.641296)
		(width 0.127)
		(layer "B.Cu")
		(net "TP_BMC_GPION3")
	)
	(segment
		(start 42.36212 -154.641296)
		(end 41.020238 -155.983178)
		(width 0.127)
		(layer "B.Cu")
		(net "TP_BMC_GPION3")
	)
	(segment
		(start 42.500042 -151.800052)
		(end 42.099992 -152.200102)
		(width 0.127)
		(layer "F.Cu")
		(net "TP_BMC_GPION2")
	)
	(via
		(at 42.099992 -152.200102)
		(size 0.4572)
		(drill 0.2032)
		(layers "F.Cu" "B.Cu")
		(net "TP_BMC_GPION2")
	)
	(segment
		(start 42.099992 -151.957024)
		(end 42.506392 -151.550624)
		(width 0.127)
		(layer "B.Cu")
		(net "TP_BMC_GPION2")
	)
	(segment
		(start 42.74947 -150.993602)
		(end 43.063414 -150.993602)
		(width 0.127)
		(layer "B.Cu")
		(net "TP_BMC_GPION2")
	)
	(segment
		(start 39.810182 -150.193756)
		(end 39.723314 -150.106888)
		(width 0.127)
		(layer "B.Cu")
		(net "TP_BMC_GPION2")
	)
	(segment
		(start 43.293792 -150.763224)
		(end 43.293792 -150.43658)
		(width 0.127)
		(layer "B.Cu")
		(net "TP_BMC_GPION2")
	)
	(segment
		(start 42.506392 -151.23668)
		(end 42.74947 -150.993602)
		(width 0.127)
		(layer "B.Cu")
		(net "TP_BMC_GPION2")
	)
	(segment
		(start 43.063414 -150.993602)
		(end 43.293792 -150.763224)
		(width 0.127)
		(layer "B.Cu")
		(net "TP_BMC_GPION2")
	)
	(segment
		(start 43.050968 -150.193756)
		(end 39.810182 -150.193756)
		(width 0.127)
		(layer "B.Cu")
		(net "TP_BMC_GPION2")
	)
	(segment
		(start 42.506392 -151.550624)
		(end 42.506392 -151.23668)
		(width 0.127)
		(layer "B.Cu")
		(net "TP_BMC_GPION2")
	)
	(segment
		(start 42.099992 -152.200102)
		(end 42.099992 -151.957024)
		(width 0.127)
		(layer "B.Cu")
		(net "TP_BMC_GPION2")
	)
	(segment
		(start 43.293792 -150.43658)
		(end 43.050968 -150.193756)
		(width 0.127)
		(layer "B.Cu")
		(net "TP_BMC_GPION2")
	)
	(segment
		(start 59.7916 -139.2682)
		(end 59.817 -139.2428)
		(width 0.127)
		(layer "F.Cu")
		(net "TP_BMC_GPIOI7")
	)
	(segment
		(start 58.639202 -139.810998)
		(end 59.182 -139.2682)
		(width 0.127)
		(layer "F.Cu")
		(net "TP_BMC_GPIOI7")
	)
	(segment
		(start 56.099964 -142.199868)
		(end 56.958738 -142.199868)
		(width 0.127)
		(layer "F.Cu")
		(net "TP_BMC_GPIOI7")
	)
	(segment
		(start 58.639202 -140.519404)
		(end 58.639202 -139.810998)
		(width 0.127)
		(layer "F.Cu")
		(net "TP_BMC_GPIOI7")
	)
	(segment
		(start 56.958738 -142.199868)
		(end 58.639202 -140.519404)
		(width 0.127)
		(layer "F.Cu")
		(net "TP_BMC_GPIOI7")
	)
	(segment
		(start 59.182 -139.2682)
		(end 59.7916 -139.2682)
		(width 0.127)
		(layer "F.Cu")
		(net "TP_BMC_GPIOI7")
	)
	(segment
		(start 59.40171 -140.720318)
		(end 59.126882 -140.720318)
		(width 0.127)
		(layer "F.Cu")
		(net "TP_BMC_GPIOI6")
	)
	(segment
		(start 61.1886 -139.0142)
		(end 60.84697 -139.0142)
		(width 0.127)
		(layer "F.Cu")
		(net "TP_BMC_GPIOI6")
	)
	(segment
		(start 59.560206 -140.5763)
		(end 59.545728 -140.5763)
		(width 0.127)
		(layer "F.Cu")
		(net "TP_BMC_GPIOI6")
	)
	(segment
		(start 59.126882 -140.720318)
		(end 56.996584 -142.850616)
		(width 0.127)
		(layer "F.Cu")
		(net "TP_BMC_GPIOI6")
	)
	(segment
		(start 59.545728 -140.5763)
		(end 59.40171 -140.720318)
		(width 0.127)
		(layer "F.Cu")
		(net "TP_BMC_GPIOI6")
	)
	(segment
		(start 60.84697 -139.0142)
		(end 59.793632 -140.067538)
		(width 0.127)
		(layer "F.Cu")
		(net "TP_BMC_GPIOI6")
	)
	(segment
		(start 56.249316 -142.850616)
		(end 56.099964 -142.999968)
		(width 0.127)
		(layer "F.Cu")
		(net "TP_BMC_GPIOI6")
	)
	(segment
		(start 56.996584 -142.850616)
		(end 56.249316 -142.850616)
		(width 0.127)
		(layer "F.Cu")
		(net "TP_BMC_GPIOI6")
	)
	(segment
		(start 59.793632 -140.067538)
		(end 59.793632 -140.342874)
		(width 0.127)
		(layer "F.Cu")
		(net "TP_BMC_GPIOI6")
	)
	(segment
		(start 59.793632 -140.342874)
		(end 59.560206 -140.5763)
		(width 0.127)
		(layer "F.Cu")
		(net "TP_BMC_GPIOI6")
	)
	(segment
		(start 54.89956 -141.800326)
		(end 54.500018 -142.199868)
		(width 0.127)
		(layer "F.Cu")
		(net "TP_BMC_GPIOI5")
	)
	(segment
		(start 54.899814 -141.800326)
		(end 54.89956 -141.800326)
		(width 0.127)
		(layer "F.Cu")
		(net "TP_BMC_GPIOI5")
	)
	(via
		(at 54.899814 -141.800326)
		(size 0.4572)
		(drill 0.2032)
		(layers "F.Cu" "B.Cu")
		(net "TP_BMC_GPIOI5")
	)
	(segment
		(start 55.505604 -141.800326)
		(end 55.801514 -141.504416)
		(width 0.127)
		(layer "B.Cu")
		(net "TP_BMC_GPIOI5")
	)
	(segment
		(start 54.899814 -141.800326)
		(end 55.505604 -141.800326)
		(width 0.127)
		(layer "B.Cu")
		(net "TP_BMC_GPIOI5")
	)
	(segment
		(start 56.989726 -141.845538)
		(end 55.654194 -141.845538)
		(width 0.127)
		(layer "F.Cu")
		(net "TP_BMC_GPIOI4")
	)
	(segment
		(start 58.165238 -140.670026)
		(end 58.151776 -140.670026)
		(width 0.127)
		(layer "F.Cu")
		(net "TP_BMC_GPIOI4")
	)
	(segment
		(start 60.702952 -138.102848)
		(end 59.868308 -138.102848)
		(width 0.127)
		(layer "F.Cu")
		(net "TP_BMC_GPIOI4")
	)
	(segment
		(start 61.2394 -137.5664)
		(end 60.702952 -138.102848)
		(width 0.127)
		(layer "F.Cu")
		(net "TP_BMC_GPIOI4")
	)
	(segment
		(start 59.868308 -138.102848)
		(end 58.410602 -139.560554)
		(width 0.127)
		(layer "F.Cu")
		(net "TP_BMC_GPIOI4")
	)
	(segment
		(start 58.410602 -140.424662)
		(end 58.165238 -140.670026)
		(width 0.127)
		(layer "F.Cu")
		(net "TP_BMC_GPIOI4")
	)
	(segment
		(start 58.410602 -139.560554)
		(end 58.410602 -140.424662)
		(width 0.127)
		(layer "F.Cu")
		(net "TP_BMC_GPIOI4")
	)
	(segment
		(start 58.151776 -140.670026)
		(end 58.151776 -140.683488)
		(width 0.127)
		(layer "F.Cu")
		(net "TP_BMC_GPIOI4")
	)
	(segment
		(start 55.654194 -141.845538)
		(end 55.299864 -142.199868)
		(width 0.127)
		(layer "F.Cu")
		(net "TP_BMC_GPIOI4")
	)
	(segment
		(start 58.151776 -140.683488)
		(end 56.989726 -141.845538)
		(width 0.127)
		(layer "F.Cu")
		(net "TP_BMC_GPIOI4")
	)
	(segment
		(start 54.899814 -141.00048)
		(end 54.89956 -141.00048)
		(width 0.127)
		(layer "F.Cu")
		(net "TP_BMC_GPIOI3")
	)
	(segment
		(start 54.89956 -141.00048)
		(end 54.500018 -141.400022)
		(width 0.127)
		(layer "F.Cu")
		(net "TP_BMC_GPIOI3")
	)
	(via
		(at 54.899814 -141.00048)
		(size 0.4572)
		(drill 0.2032)
		(layers "F.Cu" "B.Cu")
		(net "TP_BMC_GPIOI3")
	)
	(segment
		(start 56.8452 -140.2842)
		(end 56.8452 -139.803632)
		(width 0.0889)
		(layer "B.Cu")
		(net "TP_BMC_GPIOI3")
	)
	(segment
		(start 55.240936 -141.00048)
		(end 55.487062 -140.754354)
		(width 0.0889)
		(layer "B.Cu")
		(net "TP_BMC_GPIOI3")
	)
	(segment
		(start 56.8452 -139.803632)
		(end 57.386728 -139.262104)
		(width 0.0889)
		(layer "B.Cu")
		(net "TP_BMC_GPIOI3")
	)
	(segment
		(start 55.487062 -140.754354)
		(end 56.375046 -140.754354)
		(width 0.0889)
		(layer "B.Cu")
		(net "TP_BMC_GPIOI3")
	)
	(segment
		(start 56.375046 -140.754354)
		(end 56.8452 -140.2842)
		(width 0.0889)
		(layer "B.Cu")
		(net "TP_BMC_GPIOI3")
	)
	(segment
		(start 54.899814 -141.00048)
		(end 55.240936 -141.00048)
		(width 0.0889)
		(layer "B.Cu")
		(net "TP_BMC_GPIOI3")
	)
	(segment
		(start 55.299864 -141.400022)
		(end 55.729886 -140.97)
		(width 0.127)
		(layer "F.Cu")
		(net "TP_BMC_GPIOI2")
	)
	(segment
		(start 56.677814 -140.97)
		(end 58.3565 -139.291314)
		(width 0.127)
		(layer "F.Cu")
		(net "TP_BMC_GPIOI2")
	)
	(segment
		(start 55.729886 -140.97)
		(end 56.677814 -140.97)
		(width 0.127)
		(layer "F.Cu")
		(net "TP_BMC_GPIOI2")
	)
	(segment
		(start 58.3565 -138.914632)
		(end 59.832748 -137.438384)
		(width 0.127)
		(layer "F.Cu")
		(net "TP_BMC_GPIOI2")
	)
	(segment
		(start 58.3565 -139.291314)
		(end 58.3565 -138.914632)
		(width 0.127)
		(layer "F.Cu")
		(net "TP_BMC_GPIOI2")
	)
	(segment
		(start 53.299868 -141.800072)
		(end 53.299614 -141.800072)
		(width 0.127)
		(layer "F.Cu")
		(net "TP_BMC_GPIOI1")
	)
	(segment
		(start 53.299614 -141.800072)
		(end 52.899818 -142.199868)
		(width 0.127)
		(layer "F.Cu")
		(net "TP_BMC_GPIOI1")
	)
	(via
		(at 53.299868 -141.800072)
		(size 0.4572)
		(drill 0.2032)
		(layers "F.Cu" "B.Cu")
		(net "TP_BMC_GPIOI1")
	)
	(segment
		(start 50.4698 -139.7762)
		(end 52.5272 -139.7762)
		(width 0.0889)
		(layer "B.Cu")
		(net "TP_BMC_GPIOI1")
	)
	(segment
		(start 50.1396 -139.446)
		(end 50.4698 -139.7762)
		(width 0.0889)
		(layer "B.Cu")
		(net "TP_BMC_GPIOI1")
	)
	(segment
		(start 52.874418 -140.123418)
		(end 52.874418 -141.374622)
		(width 0.0889)
		(layer "B.Cu")
		(net "TP_BMC_GPIOI1")
	)
	(segment
		(start 52.874418 -141.374622)
		(end 53.299868 -141.800072)
		(width 0.0889)
		(layer "B.Cu")
		(net "TP_BMC_GPIOI1")
	)
	(segment
		(start 52.5272 -139.7762)
		(end 52.874418 -140.123418)
		(width 0.0889)
		(layer "B.Cu")
		(net "TP_BMC_GPIOI1")
	)
	(segment
		(start 54.900068 -139.40028)
		(end 54.500272 -139.800076)
		(width 0.127)
		(layer "F.Cu")
		(net "TP_BMC_GPIOI0")
	)
	(segment
		(start 54.500272 -139.800076)
		(end 54.500018 -139.800076)
		(width 0.127)
		(layer "F.Cu")
		(net "TP_BMC_GPIOI0")
	)
	(via
		(at 54.900068 -139.40028)
		(size 0.4572)
		(drill 0.2032)
		(layers "F.Cu" "B.Cu")
		(net "TP_BMC_GPIOI0")
	)
	(segment
		(start 54.900068 -139.319762)
		(end 55.894732 -138.325098)
		(width 0.127)
		(layer "B.Cu")
		(net "TP_BMC_GPIOI0")
	)
	(segment
		(start 55.894732 -138.325098)
		(end 56.376824 -138.325098)
		(width 0.127)
		(layer "B.Cu")
		(net "TP_BMC_GPIOI0")
	)
	(segment
		(start 54.900068 -139.40028)
		(end 54.900068 -139.319762)
		(width 0.127)
		(layer "B.Cu")
		(net "TP_BMC_GPIOI0")
	)
	(segment
		(start 54.099714 -141.800072)
		(end 53.699918 -142.199868)
		(width 0.127)
		(layer "F.Cu")
		(net "TP_BMC_GPIOG6")
	)
	(segment
		(start 54.099968 -141.800072)
		(end 54.099714 -141.800072)
		(width 0.127)
		(layer "F.Cu")
		(net "TP_BMC_GPIOG6")
	)
	(via
		(at 54.099968 -141.800072)
		(size 0.4572)
		(drill 0.2032)
		(layers "F.Cu" "B.Cu")
		(net "TP_BMC_GPIOG6")
	)
	(segment
		(start 55.13578 -141.37513)
		(end 54.52491 -141.37513)
		(width 0.0889)
		(layer "B.Cu")
		(net "TP_BMC_GPIOG6")
	)
	(segment
		(start 58.900568 -138.905234)
		(end 58.612532 -138.905234)
		(width 0.127)
		(layer "B.Cu")
		(net "TP_BMC_GPIOG6")
	)
	(segment
		(start 56.5404 -140.977366)
		(end 55.533544 -140.977366)
		(width 0.0889)
		(layer "B.Cu")
		(net "TP_BMC_GPIOG6")
	)
	(segment
		(start 54.52491 -141.37513)
		(end 54.099968 -141.800072)
		(width 0.0889)
		(layer "B.Cu")
		(net "TP_BMC_GPIOG6")
	)
	(segment
		(start 58.612532 -138.905234)
		(end 56.5404 -140.977366)
		(width 0.127)
		(layer "B.Cu")
		(net "TP_BMC_GPIOG6")
	)
	(segment
		(start 55.533544 -140.977366)
		(end 55.13578 -141.37513)
		(width 0.0889)
		(layer "B.Cu")
		(net "TP_BMC_GPIOG6")
	)
	(segment
		(start 54.099714 -141.000226)
		(end 53.699918 -141.400022)
		(width 0.127)
		(layer "F.Cu")
		(net "TP_BMC_GPIOG5")
	)
	(segment
		(start 54.099968 -141.000226)
		(end 54.099714 -141.000226)
		(width 0.127)
		(layer "F.Cu")
		(net "TP_BMC_GPIOG5")
	)
	(via
		(at 54.099968 -141.000226)
		(size 0.4572)
		(drill 0.2032)
		(layers "F.Cu" "B.Cu")
		(net "TP_BMC_GPIOG5")
	)
	(segment
		(start 54.325774 -141.000226)
		(end 54.099968 -141.000226)
		(width 0.0889)
		(layer "B.Cu")
		(net "TP_BMC_GPIOG5")
	)
	(segment
		(start 55.259224 -140.600176)
		(end 54.725824 -140.600176)
		(width 0.0889)
		(layer "B.Cu")
		(net "TP_BMC_GPIOG5")
	)
	(segment
		(start 55.708296 -140.151104)
		(end 55.259224 -140.600176)
		(width 0.0889)
		(layer "B.Cu")
		(net "TP_BMC_GPIOG5")
	)
	(segment
		(start 54.725824 -140.600176)
		(end 54.325774 -141.000226)
		(width 0.0889)
		(layer "B.Cu")
		(net "TP_BMC_GPIOG5")
	)
	(segment
		(start 56.091328 -140.151104)
		(end 55.708296 -140.151104)
		(width 0.0889)
		(layer "B.Cu")
		(net "TP_BMC_GPIOG5")
	)
	(segment
		(start 39.157656 -150.657052)
		(end 39.642796 -150.657052)
		(width 0.127)
		(layer "F.Cu")
		(net "THROTTLE_N")
	)
	(segment
		(start 39.642796 -150.657052)
		(end 40.099996 -150.199852)
		(width 0.127)
		(layer "F.Cu")
		(net "THROTTLE_N")
	)
	(segment
		(start 34.2138 -152.2095)
		(end 34.870136 -151.553164)
		(width 0.127)
		(layer "F.Cu")
		(net "THROTTLE_N")
	)
	(segment
		(start 34.870136 -151.553164)
		(end 35.490912 -151.553164)
		(width 0.127)
		(layer "F.Cu")
		(net "THROTTLE_N")
	)
	(segment
		(start 37.447728 -151.363172)
		(end 38.451536 -151.363172)
		(width 0.127)
		(layer "F.Cu")
		(net "THROTTLE_N")
	)
	(segment
		(start 35.490912 -151.553164)
		(end 37.257736 -151.553164)
		(width 0.127)
		(layer "F.Cu")
		(net "THROTTLE_N")
	)
	(segment
		(start 38.451536 -151.363172)
		(end 39.157656 -150.657052)
		(width 0.127)
		(layer "F.Cu")
		(net "THROTTLE_N")
	)
	(segment
		(start 37.257736 -151.553164)
		(end 37.447728 -151.363172)
		(width 0.127)
		(layer "F.Cu")
		(net "THROTTLE_N")
	)
	(via
		(at 35.490912 -151.553164)
		(size 0.6604)
		(drill 0.3302)
		(layers "F.Cu" "B.Cu")
		(net "THROTTLE_N")
	)
	(segment
		(start 112.4712 -23.097236)
		(end 113.071402 -23.697438)
		(width 0.127)
		(layer "F.Cu")
		(net "SYS_RESET_N")
	)
	(segment
		(start 113.452402 -41.847516)
		(end 112.499902 -42.800016)
		(width 0.127)
		(layer "F.Cu")
		(net "SYS_RESET_N")
	)
	(segment
		(start 113.071402 -23.697438)
		(end 113.071402 -26.0223)
		(width 0.127)
		(layer "F.Cu")
		(net "SYS_RESET_N")
	)
	(segment
		(start 113.452402 -26.4033)
		(end 113.452402 -41.847516)
		(width 0.127)
		(layer "F.Cu")
		(net "SYS_RESET_N")
	)
	(segment
		(start 113.071402 -26.0223)
		(end 113.452402 -26.4033)
		(width 0.127)
		(layer "F.Cu")
		(net "SYS_RESET_N")
	)
	(via
		(at 29.083 -124.46)
		(size 0.508)
		(drill 0.254)
		(layers "F.Cu" "B.Cu")
		(net "SYS_RESET_N")
	)
	(via
		(at 65.628774 -129.412492)
		(size 0.508)
		(drill 0.254)
		(layers "F.Cu" "B.Cu")
		(net "SYS_RESET_N")
	)
	(via
		(at 113.071402 -26.0223)
		(size 0.6604)
		(drill 0.3302)
		(layers "F.Cu" "B.Cu")
		(net "SYS_RESET_N")
	)
	(via
		(at 75.973178 -45.14596)
		(size 0.508)
		(drill 0.254)
		(layers "F.Cu" "B.Cu")
		(net "SYS_RESET_N")
	)
	(via
		(at 68.3006 -113.0681)
		(size 0.508)
		(drill 0.254)
		(layers "F.Cu" "B.Cu")
		(net "SYS_RESET_N")
	)
	(via
		(at 112.4712 -23.097236)
		(size 0.508)
		(drill 0.254)
		(layers "F.Cu" "B.Cu")
		(net "SYS_RESET_N")
	)
	(segment
		(start 76.6953 -99.76866)
		(end 80.135984 -99.76866)
		(width 0.127)
		(layer "B.Cu")
		(net "SYS_RESET_N")
	)
	(segment
		(start 29.083 -124.0663)
		(end 29.083 -124.46)
		(width 0.127)
		(layer "B.Cu")
		(net "SYS_RESET_N")
	)
	(segment
		(start 75.810872 -45.14596)
		(end 74.491088 -46.465744)
		(width 0.127)
		(layer "B.Cu")
		(net "SYS_RESET_N")
	)
	(segment
		(start 80.7466 -110.8456)
		(end 75.6158 -110.8456)
		(width 0.127)
		(layer "B.Cu")
		(net "SYS_RESET_N")
	)
	(segment
		(start 74.49058 -46.554644)
		(end 74.49058 -97.56394)
		(width 0.127)
		(layer "B.Cu")
		(net "SYS_RESET_N")
	)
	(segment
		(start 74.491088 -46.465744)
		(end 74.491088 -46.554136)
		(width 0.127)
		(layer "B.Cu")
		(net "SYS_RESET_N")
	)
	(segment
		(start 80.135984 -99.76866)
		(end 80.468724 -100.1014)
		(width 0.127)
		(layer "B.Cu")
		(net "SYS_RESET_N")
	)
	(segment
		(start 29.93644 -123.21286)
		(end 29.083 -124.0663)
		(width 0.127)
		(layer "B.Cu")
		(net "SYS_RESET_N")
	)
	(segment
		(start 84.141818 -102.8446)
		(end 84.141818 -107.450382)
		(width 0.127)
		(layer "B.Cu")
		(net "SYS_RESET_N")
	)
	(segment
		(start 30.5689 -123.21286)
		(end 29.93644 -123.21286)
		(width 0.127)
		(layer "B.Cu")
		(net "SYS_RESET_N")
	)
	(segment
		(start 84.141818 -107.450382)
		(end 80.7466 -110.8456)
		(width 0.127)
		(layer "B.Cu")
		(net "SYS_RESET_N")
	)
	(segment
		(start 68.8467 -112.522)
		(end 68.3006 -113.0681)
		(width 0.127)
		(layer "B.Cu")
		(net "SYS_RESET_N")
	)
	(segment
		(start 75.6158 -110.8456)
		(end 73.9394 -112.522)
		(width 0.127)
		(layer "B.Cu")
		(net "SYS_RESET_N")
	)
	(segment
		(start 75.973178 -45.14596)
		(end 75.810872 -45.14596)
		(width 0.127)
		(layer "B.Cu")
		(net "SYS_RESET_N")
	)
	(segment
		(start 80.468724 -100.1014)
		(end 81.398618 -100.1014)
		(width 0.127)
		(layer "B.Cu")
		(net "SYS_RESET_N")
	)
	(segment
		(start 73.9394 -112.522)
		(end 68.8467 -112.522)
		(width 0.127)
		(layer "B.Cu")
		(net "SYS_RESET_N")
	)
	(segment
		(start 74.491088 -46.554136)
		(end 74.49058 -46.554644)
		(width 0.127)
		(layer "B.Cu")
		(net "SYS_RESET_N")
	)
	(segment
		(start 74.49058 -97.56394)
		(end 76.6953 -99.76866)
		(width 0.127)
		(layer "B.Cu")
		(net "SYS_RESET_N")
	)
	(segment
		(start 81.398618 -100.1014)
		(end 84.141818 -102.8446)
		(width 0.127)
		(layer "B.Cu")
		(net "SYS_RESET_N")
	)
	(segment
		(start 68.3006 -113.0681)
		(end 66.421 -114.9477)
		(width 0.127)
		(layer "In2.Cu")
		(net "SYS_RESET_N")
	)
	(segment
		(start 66.421 -114.9477)
		(end 66.421 -120.3198)
		(width 0.127)
		(layer "In2.Cu")
		(net "SYS_RESET_N")
	)
	(segment
		(start 66.4718 -120.3706)
		(end 66.4718 -127.047498)
		(width 0.127)
		(layer "In2.Cu")
		(net "SYS_RESET_N")
	)
	(segment
		(start 66.421 -120.3198)
		(end 66.4718 -120.3706)
		(width 0.127)
		(layer "In2.Cu")
		(net "SYS_RESET_N")
	)
	(segment
		(start 65.628774 -127.890524)
		(end 65.628774 -129.412492)
		(width 0.127)
		(layer "In2.Cu")
		(net "SYS_RESET_N")
	)
	(segment
		(start 66.4718 -127.047498)
		(end 65.628774 -127.890524)
		(width 0.127)
		(layer "In2.Cu")
		(net "SYS_RESET_N")
	)
	(segment
		(start 77.882242 -28.08859)
		(end 75.428348 -30.542484)
		(width 0.127)
		(layer "In5.Cu")
		(net "SYS_RESET_N")
	)
	(segment
		(start 112.4712 -16.885412)
		(end 110.418118 -14.83233)
		(width 0.127)
		(layer "In5.Cu")
		(net "SYS_RESET_N")
	)
	(segment
		(start 75.428348 -30.542484)
		(end 75.428348 -40.42791)
		(width 0.127)
		(layer "In5.Cu")
		(net "SYS_RESET_N")
	)
	(segment
		(start 77.882242 -15.27937)
		(end 77.882242 -28.08859)
		(width 0.127)
		(layer "In5.Cu")
		(net "SYS_RESET_N")
	)
	(segment
		(start 94.353888 -8.6487)
		(end 84.512912 -8.6487)
		(width 0.127)
		(layer "In5.Cu")
		(net "SYS_RESET_N")
	)
	(segment
		(start 30.3022 -124.46)
		(end 37.195506 -131.353306)
		(width 0.127)
		(layer "In5.Cu")
		(net "SYS_RESET_N")
	)
	(segment
		(start 75.428348 -40.42791)
		(end 75.973178 -40.97274)
		(width 0.127)
		(layer "In5.Cu")
		(net "SYS_RESET_N")
	)
	(segment
		(start 53.512212 -131.353306)
		(end 55.973218 -128.8923)
		(width 0.127)
		(layer "In5.Cu")
		(net "SYS_RESET_N")
	)
	(segment
		(start 100.537518 -14.83233)
		(end 94.353888 -8.6487)
		(width 0.127)
		(layer "In5.Cu")
		(net "SYS_RESET_N")
	)
	(segment
		(start 84.512912 -8.6487)
		(end 77.882242 -15.27937)
		(width 0.127)
		(layer "In5.Cu")
		(net "SYS_RESET_N")
	)
	(segment
		(start 37.195506 -131.353306)
		(end 53.512212 -131.353306)
		(width 0.127)
		(layer "In5.Cu")
		(net "SYS_RESET_N")
	)
	(segment
		(start 55.973218 -128.8923)
		(end 65.108582 -128.8923)
		(width 0.127)
		(layer "In5.Cu")
		(net "SYS_RESET_N")
	)
	(segment
		(start 112.4712 -23.097236)
		(end 112.4712 -16.885412)
		(width 0.127)
		(layer "In5.Cu")
		(net "SYS_RESET_N")
	)
	(segment
		(start 75.973178 -40.97274)
		(end 75.973178 -45.14596)
		(width 0.127)
		(layer "In5.Cu")
		(net "SYS_RESET_N")
	)
	(segment
		(start 110.418118 -14.83233)
		(end 100.537518 -14.83233)
		(width 0.127)
		(layer "In5.Cu")
		(net "SYS_RESET_N")
	)
	(segment
		(start 29.083 -124.46)
		(end 30.3022 -124.46)
		(width 0.127)
		(layer "In5.Cu")
		(net "SYS_RESET_N")
	)
	(segment
		(start 65.108582 -128.8923)
		(end 65.628774 -129.412492)
		(width 0.127)
		(layer "In5.Cu")
		(net "SYS_RESET_N")
	)
	(segment
		(start 60.618116 -130.85318)
		(end 60.616592 -130.851656)
		(width 0.127)
		(layer "F.Cu")
		(net "SCC_STBY_PWR_EN")
	)
	(segment
		(start 60.071 -130.306064)
		(end 60.071 -125.1458)
		(width 0.127)
		(layer "F.Cu")
		(net "SCC_STBY_PWR_EN")
	)
	(segment
		(start 60.071 -125.1458)
		(end 59.6138 -124.6886)
		(width 0.127)
		(layer "F.Cu")
		(net "SCC_STBY_PWR_EN")
	)
	(segment
		(start 61.6458 -130.85318)
		(end 60.618116 -130.85318)
		(width 0.127)
		(layer "F.Cu")
		(net "SCC_STBY_PWR_EN")
	)
	(segment
		(start 60.616592 -130.851656)
		(end 60.071 -130.306064)
		(width 0.127)
		(layer "F.Cu")
		(net "SCC_STBY_PWR_EN")
	)
	(via
		(at 59.6138 -124.6886)
		(size 0.508)
		(drill 0.254)
		(layers "F.Cu" "B.Cu")
		(net "SCC_STBY_PWR_EN")
	)
	(via
		(at 82.6516 -128.4732)
		(size 0.508)
		(drill 0.254)
		(layers "F.Cu" "B.Cu")
		(net "SCC_STBY_PWR_EN")
	)
	(segment
		(start 88.23833 -42.629328)
		(end 88.23833 -36.866322)
		(width 0.127)
		(layer "In2.Cu")
		(net "SCC_STBY_PWR_EN")
	)
	(segment
		(start 86.5251 -109.88548)
		(end 87.947246 -108.463334)
		(width 0.127)
		(layer "In2.Cu")
		(net "SCC_STBY_PWR_EN")
	)
	(segment
		(start 119.54383 -20.56257)
		(end 121.171716 -20.56257)
		(width 0.127)
		(layer "In2.Cu")
		(net "SCC_STBY_PWR_EN")
	)
	(segment
		(start 97.980754 -14.62659)
		(end 102.489 -19.134836)
		(width 0.127)
		(layer "In2.Cu")
		(net "SCC_STBY_PWR_EN")
	)
	(segment
		(start 85.1408 -122.933206)
		(end 85.1408 -122.932952)
		(width 0.127)
		(layer "In2.Cu")
		(net "SCC_STBY_PWR_EN")
	)
	(segment
		(start 87.947246 -108.463334)
		(end 87.947246 -101.104446)
		(width 0.127)
		(layer "In2.Cu")
		(net "SCC_STBY_PWR_EN")
	)
	(segment
		(start 131.83235 -26.7462)
		(end 136.471406 -31.385256)
		(width 0.127)
		(layer "In2.Cu")
		(net "SCC_STBY_PWR_EN")
	)
	(segment
		(start 97.020888 -14.62659)
		(end 97.980754 -14.62659)
		(width 0.127)
		(layer "In2.Cu")
		(net "SCC_STBY_PWR_EN")
	)
	(segment
		(start 82.6516 -125.422406)
		(end 85.1408 -122.933206)
		(width 0.127)
		(layer "In2.Cu")
		(net "SCC_STBY_PWR_EN")
	)
	(segment
		(start 121.171716 -20.56257)
		(end 123.54052 -22.931374)
		(width 0.127)
		(layer "In2.Cu")
		(net "SCC_STBY_PWR_EN")
	)
	(segment
		(start 85.1408 -122.932952)
		(end 85.315044 -122.758708)
		(width 0.127)
		(layer "In2.Cu")
		(net "SCC_STBY_PWR_EN")
	)
	(segment
		(start 88.343232 -66.1162)
		(end 86.368128 -64.141096)
		(width 0.127)
		(layer "In2.Cu")
		(net "SCC_STBY_PWR_EN")
	)
	(segment
		(start 102.489 -19.134836)
		(end 118.116096 -19.134836)
		(width 0.127)
		(layer "In2.Cu")
		(net "SCC_STBY_PWR_EN")
	)
	(segment
		(start 95.949262 -10.830306)
		(end 95.949262 -13.554964)
		(width 0.127)
		(layer "In2.Cu")
		(net "SCC_STBY_PWR_EN")
	)
	(segment
		(start 136.471406 -31.385256)
		(end 136.471406 -39.82847)
		(width 0.127)
		(layer "In2.Cu")
		(net "SCC_STBY_PWR_EN")
	)
	(segment
		(start 82.6516 -128.4732)
		(end 82.6516 -125.422406)
		(width 0.127)
		(layer "In2.Cu")
		(net "SCC_STBY_PWR_EN")
	)
	(segment
		(start 87.053928 -91.09964)
		(end 88.343232 -89.810336)
		(width 0.127)
		(layer "In2.Cu")
		(net "SCC_STBY_PWR_EN")
	)
	(segment
		(start 84.2264 -116.853462)
		(end 84.2264 -114.1984)
		(width 0.127)
		(layer "In2.Cu")
		(net "SCC_STBY_PWR_EN")
	)
	(segment
		(start 86.368128 -64.141096)
		(end 86.368128 -44.49953)
		(width 0.127)
		(layer "In2.Cu")
		(net "SCC_STBY_PWR_EN")
	)
	(segment
		(start 88.343232 -89.810336)
		(end 88.343232 -66.1162)
		(width 0.127)
		(layer "In2.Cu")
		(net "SCC_STBY_PWR_EN")
	)
	(segment
		(start 81.78038 -30.408372)
		(end 81.78038 -10.692892)
		(width 0.127)
		(layer "In2.Cu")
		(net "SCC_STBY_PWR_EN")
	)
	(segment
		(start 87.947246 -101.104446)
		(end 87.053928 -100.211128)
		(width 0.127)
		(layer "In2.Cu")
		(net "SCC_STBY_PWR_EN")
	)
	(segment
		(start 84.206334 -8.266938)
		(end 93.385894 -8.266938)
		(width 0.127)
		(layer "In2.Cu")
		(net "SCC_STBY_PWR_EN")
	)
	(segment
		(start 118.116096 -19.134836)
		(end 119.54383 -20.56257)
		(width 0.127)
		(layer "In2.Cu")
		(net "SCC_STBY_PWR_EN")
	)
	(segment
		(start 85.315044 -117.94236)
		(end 84.2264 -116.853462)
		(width 0.127)
		(layer "In2.Cu")
		(net "SCC_STBY_PWR_EN")
	)
	(segment
		(start 88.23833 -36.866322)
		(end 81.78038 -30.408372)
		(width 0.127)
		(layer "In2.Cu")
		(net "SCC_STBY_PWR_EN")
	)
	(segment
		(start 123.54052 -22.931374)
		(end 126.088394 -22.931374)
		(width 0.127)
		(layer "In2.Cu")
		(net "SCC_STBY_PWR_EN")
	)
	(segment
		(start 87.053928 -100.211128)
		(end 87.053928 -91.09964)
		(width 0.127)
		(layer "In2.Cu")
		(net "SCC_STBY_PWR_EN")
	)
	(segment
		(start 84.2264 -114.1984)
		(end 86.5251 -111.8997)
		(width 0.127)
		(layer "In2.Cu")
		(net "SCC_STBY_PWR_EN")
	)
	(segment
		(start 85.315044 -122.758708)
		(end 85.315044 -117.94236)
		(width 0.127)
		(layer "In2.Cu")
		(net "SCC_STBY_PWR_EN")
	)
	(segment
		(start 93.385894 -8.266938)
		(end 95.949262 -10.830306)
		(width 0.127)
		(layer "In2.Cu")
		(net "SCC_STBY_PWR_EN")
	)
	(segment
		(start 81.78038 -10.692892)
		(end 84.206334 -8.266938)
		(width 0.127)
		(layer "In2.Cu")
		(net "SCC_STBY_PWR_EN")
	)
	(segment
		(start 95.949262 -13.554964)
		(end 97.020888 -14.62659)
		(width 0.127)
		(layer "In2.Cu")
		(net "SCC_STBY_PWR_EN")
	)
	(segment
		(start 86.368128 -44.49953)
		(end 88.23833 -42.629328)
		(width 0.127)
		(layer "In2.Cu")
		(net "SCC_STBY_PWR_EN")
	)
	(segment
		(start 129.90322 -26.7462)
		(end 131.83235 -26.7462)
		(width 0.127)
		(layer "In2.Cu")
		(net "SCC_STBY_PWR_EN")
	)
	(segment
		(start 86.5251 -111.8997)
		(end 86.5251 -109.88548)
		(width 0.127)
		(layer "In2.Cu")
		(net "SCC_STBY_PWR_EN")
	)
	(segment
		(start 126.088394 -22.931374)
		(end 129.90322 -26.7462)
		(width 0.127)
		(layer "In2.Cu")
		(net "SCC_STBY_PWR_EN")
	)
	(segment
		(start 136.471406 -39.82847)
		(end 135.899906 -40.39997)
		(width 0.127)
		(layer "In2.Cu")
		(net "SCC_STBY_PWR_EN")
	)
	(segment
		(start 82.6516 -128.4732)
		(end 82.1944 -128.9304)
		(width 0.127)
		(layer "In5.Cu")
		(net "SCC_STBY_PWR_EN")
	)
	(segment
		(start 77.961236 -127.254254)
		(end 73.787 -127.254254)
		(width 0.127)
		(layer "In5.Cu")
		(net "SCC_STBY_PWR_EN")
	)
	(segment
		(start 82.1944 -128.9304)
		(end 79.637382 -128.9304)
		(width 0.127)
		(layer "In5.Cu")
		(net "SCC_STBY_PWR_EN")
	)
	(segment
		(start 68.834 -125.222)
		(end 68.3006 -124.6886)
		(width 0.127)
		(layer "In5.Cu")
		(net "SCC_STBY_PWR_EN")
	)
	(segment
		(start 73.787 -127.254254)
		(end 71.754746 -125.222)
		(width 0.127)
		(layer "In5.Cu")
		(net "SCC_STBY_PWR_EN")
	)
	(segment
		(start 79.637382 -128.9304)
		(end 77.961236 -127.254254)
		(width 0.127)
		(layer "In5.Cu")
		(net "SCC_STBY_PWR_EN")
	)
	(segment
		(start 68.3006 -124.6886)
		(end 59.6138 -124.6886)
		(width 0.127)
		(layer "In5.Cu")
		(net "SCC_STBY_PWR_EN")
	)
	(segment
		(start 71.754746 -125.222)
		(end 68.834 -125.222)
		(width 0.127)
		(layer "In5.Cu")
		(net "SCC_STBY_PWR_EN")
	)
	(via
		(at 36.7665 -154.0129)
		(size 0.508)
		(drill 0.254)
		(layers "F.Cu" "B.Cu")
		(net "SCC_RMT_HEARTBEAT")
	)
	(via
		(at 37.592 -154.0891)
		(size 0.6096)
		(drill 0.3048)
		(layers "F.Cu" "B.Cu")
		(net "SCC_RMT_HEARTBEAT")
	)
	(via
		(at 85.8774 -161.4932)
		(size 0.508)
		(drill 0.254)
		(layers "F.Cu" "B.Cu")
		(net "SCC_RMT_HEARTBEAT")
	)
	(segment
		(start 36.7665 -154.0129)
		(end 36.9443 -154.1907)
		(width 0.127)
		(layer "B.Cu")
		(net "SCC_RMT_HEARTBEAT")
	)
	(segment
		(start 36.9443 -154.1907)
		(end 37.4904 -154.1907)
		(width 0.127)
		(layer "B.Cu")
		(net "SCC_RMT_HEARTBEAT")
	)
	(segment
		(start 37.4904 -154.1907)
		(end 37.592 -154.0891)
		(width 0.127)
		(layer "B.Cu")
		(net "SCC_RMT_HEARTBEAT")
	)
	(segment
		(start 37.593778 -153.050748)
		(end 37.592 -153.052526)
		(width 0.127)
		(layer "B.Cu")
		(net "SCC_RMT_HEARTBEAT")
	)
	(segment
		(start 37.592 -153.052526)
		(end 37.592 -154.0891)
		(width 0.127)
		(layer "B.Cu")
		(net "SCC_RMT_HEARTBEAT")
	)
	(segment
		(start 81.710022 -149.079204)
		(end 81.710022 -147.70354)
		(width 0.127)
		(layer "In2.Cu")
		(net "SCC_RMT_HEARTBEAT")
	)
	(segment
		(start 82.632296 -158.247842)
		(end 82.632296 -150.001478)
		(width 0.127)
		(layer "In2.Cu")
		(net "SCC_RMT_HEARTBEAT")
	)
	(segment
		(start 80.2259 -146.219418)
		(end 80.2259 -140.614654)
		(width 0.127)
		(layer "In2.Cu")
		(net "SCC_RMT_HEARTBEAT")
	)
	(segment
		(start 74.743056 -117.94236)
		(end 75.832716 -116.852446)
		(width 0.127)
		(layer "In2.Cu")
		(net "SCC_RMT_HEARTBEAT")
	)
	(segment
		(start 132.44195 -25.425654)
		(end 136.963912 -29.947616)
		(width 0.127)
		(layer "In2.Cu")
		(net "SCC_RMT_HEARTBEAT")
	)
	(segment
		(start 79.248762 -113.4364)
		(end 83.052412 -113.4364)
		(width 0.127)
		(layer "In2.Cu")
		(net "SCC_RMT_HEARTBEAT")
	)
	(segment
		(start 138.652504 -30.5054)
		(end 138.652504 -39.647622)
		(width 0.127)
		(layer "In2.Cu")
		(net "SCC_RMT_HEARTBEAT")
	)
	(segment
		(start 126.562358 -21.788374)
		(end 130.199638 -25.425654)
		(width 0.127)
		(layer "In2.Cu")
		(net "SCC_RMT_HEARTBEAT")
	)
	(segment
		(start 75.950572 -116.676424)
		(end 76.676504 -115.950492)
		(width 0.127)
		(layer "In2.Cu")
		(net "SCC_RMT_HEARTBEAT")
	)
	(segment
		(start 80.2259 -140.614654)
		(end 80.108044 -140.496798)
		(width 0.127)
		(layer "In2.Cu")
		(net "SCC_RMT_HEARTBEAT")
	)
	(segment
		(start 102.065582 -17.043654)
		(end 108.03509 -17.043654)
		(width 0.127)
		(layer "In2.Cu")
		(net "SCC_RMT_HEARTBEAT")
	)
	(segment
		(start 94.031562 -7.123938)
		(end 97.710498 -10.802874)
		(width 0.127)
		(layer "In2.Cu")
		(net "SCC_RMT_HEARTBEAT")
	)
	(segment
		(start 80.63738 -9.01827)
		(end 82.531712 -7.123938)
		(width 0.127)
		(layer "In2.Cu")
		(net "SCC_RMT_HEARTBEAT")
	)
	(segment
		(start 80.108044 -129.287016)
		(end 80.3275 -129.06756)
		(width 0.127)
		(layer "In2.Cu")
		(net "SCC_RMT_HEARTBEAT")
	)
	(segment
		(start 138.652504 -39.647622)
		(end 137.700004 -40.600122)
		(width 0.127)
		(layer "In2.Cu")
		(net "SCC_RMT_HEARTBEAT")
	)
	(segment
		(start 80.3275 -129.06756)
		(end 80.3275 -128.120394)
		(width 0.127)
		(layer "In2.Cu")
		(net "SCC_RMT_HEARTBEAT")
	)
	(segment
		(start 85.834728 -100.808282)
		(end 85.834728 -90.63228)
		(width 0.127)
		(layer "In2.Cu")
		(net "SCC_RMT_HEARTBEAT")
	)
	(segment
		(start 84.107528 -66.429128)
		(end 84.107528 -47.159672)
		(width 0.127)
		(layer "In2.Cu")
		(net "SCC_RMT_HEARTBEAT")
	)
	(segment
		(start 84.107528 -47.159672)
		(end 84.992972 -46.274228)
		(width 0.127)
		(layer "In2.Cu")
		(net "SCC_RMT_HEARTBEAT")
	)
	(segment
		(start 74.743056 -122.53595)
		(end 74.743056 -117.94236)
		(width 0.127)
		(layer "In2.Cu")
		(net "SCC_RMT_HEARTBEAT")
	)
	(segment
		(start 97.710498 -12.68857)
		(end 102.065582 -17.043654)
		(width 0.127)
		(layer "In2.Cu")
		(net "SCC_RMT_HEARTBEAT")
	)
	(segment
		(start 76.852526 -115.832636)
		(end 79.248762 -113.4364)
		(width 0.127)
		(layer "In2.Cu")
		(net "SCC_RMT_HEARTBEAT")
	)
	(segment
		(start 80.108044 -140.496798)
		(end 80.108044 -129.287016)
		(width 0.127)
		(layer "In2.Cu")
		(net "SCC_RMT_HEARTBEAT")
	)
	(segment
		(start 86.549738 -68.871338)
		(end 84.107528 -66.429128)
		(width 0.127)
		(layer "In2.Cu")
		(net "SCC_RMT_HEARTBEAT")
	)
	(segment
		(start 86.654132 -89.812876)
		(end 86.654132 -72.6948)
		(width 0.127)
		(layer "In2.Cu")
		(net "SCC_RMT_HEARTBEAT")
	)
	(segment
		(start 84.8106 -109.983016)
		(end 86.804246 -107.98937)
		(width 0.127)
		(layer "In2.Cu")
		(net "SCC_RMT_HEARTBEAT")
	)
	(segment
		(start 85.8774 -161.4932)
		(end 85.6488 -161.4932)
		(width 0.127)
		(layer "In2.Cu")
		(net "SCC_RMT_HEARTBEAT")
	)
	(segment
		(start 82.531712 -7.123938)
		(end 94.031562 -7.123938)
		(width 0.127)
		(layer "In2.Cu")
		(net "SCC_RMT_HEARTBEAT")
	)
	(segment
		(start 86.249256 -36.80968)
		(end 86.249256 -36.494212)
		(width 0.127)
		(layer "In2.Cu")
		(net "SCC_RMT_HEARTBEAT")
	)
	(segment
		(start 80.3275 -128.120394)
		(end 74.743056 -122.53595)
		(width 0.127)
		(layer "In2.Cu")
		(net "SCC_RMT_HEARTBEAT")
	)
	(segment
		(start 75.832716 -116.852446)
		(end 75.950572 -116.676424)
		(width 0.127)
		(layer "In2.Cu")
		(net "SCC_RMT_HEARTBEAT")
	)
	(segment
		(start 97.710498 -10.802874)
		(end 97.710498 -12.68857)
		(width 0.127)
		(layer "In2.Cu")
		(net "SCC_RMT_HEARTBEAT")
	)
	(segment
		(start 86.249256 -36.494212)
		(end 80.63738 -30.882336)
		(width 0.127)
		(layer "In2.Cu")
		(net "SCC_RMT_HEARTBEAT")
	)
	(segment
		(start 86.654132 -72.6948)
		(end 86.549738 -72.590406)
		(width 0.127)
		(layer "In2.Cu")
		(net "SCC_RMT_HEARTBEAT")
	)
	(segment
		(start 136.963912 -29.947616)
		(end 138.09472 -29.947616)
		(width 0.127)
		(layer "In2.Cu")
		(net "SCC_RMT_HEARTBEAT")
	)
	(segment
		(start 86.804246 -101.7778)
		(end 85.834728 -100.808282)
		(width 0.127)
		(layer "In2.Cu")
		(net "SCC_RMT_HEARTBEAT")
	)
	(segment
		(start 84.8106 -111.678212)
		(end 84.8106 -109.983016)
		(width 0.127)
		(layer "In2.Cu")
		(net "SCC_RMT_HEARTBEAT")
	)
	(segment
		(start 81.710022 -147.70354)
		(end 80.2259 -146.219418)
		(width 0.127)
		(layer "In2.Cu")
		(net "SCC_RMT_HEARTBEAT")
	)
	(segment
		(start 84.963 -160.578546)
		(end 82.632296 -158.247842)
		(width 0.127)
		(layer "In2.Cu")
		(net "SCC_RMT_HEARTBEAT")
	)
	(segment
		(start 85.834728 -90.63228)
		(end 86.654132 -89.812876)
		(width 0.127)
		(layer "In2.Cu")
		(net "SCC_RMT_HEARTBEAT")
	)
	(segment
		(start 85.6488 -161.4932)
		(end 84.963 -160.8074)
		(width 0.127)
		(layer "In2.Cu")
		(net "SCC_RMT_HEARTBEAT")
	)
	(segment
		(start 82.632296 -150.001478)
		(end 81.710022 -149.079204)
		(width 0.127)
		(layer "In2.Cu")
		(net "SCC_RMT_HEARTBEAT")
	)
	(segment
		(start 120.017794 -19.41957)
		(end 121.64568 -19.41957)
		(width 0.127)
		(layer "In2.Cu")
		(net "SCC_RMT_HEARTBEAT")
	)
	(segment
		(start 86.549738 -72.590406)
		(end 86.549738 -68.871338)
		(width 0.127)
		(layer "In2.Cu")
		(net "SCC_RMT_HEARTBEAT")
	)
	(segment
		(start 124.014484 -21.788374)
		(end 126.562358 -21.788374)
		(width 0.127)
		(layer "In2.Cu")
		(net "SCC_RMT_HEARTBEAT")
	)
	(segment
		(start 83.052412 -113.4364)
		(end 84.8106 -111.678212)
		(width 0.127)
		(layer "In2.Cu")
		(net "SCC_RMT_HEARTBEAT")
	)
	(segment
		(start 84.992972 -46.274228)
		(end 84.992972 -44.099226)
		(width 0.127)
		(layer "In2.Cu")
		(net "SCC_RMT_HEARTBEAT")
	)
	(segment
		(start 138.09472 -29.947616)
		(end 138.652504 -30.5054)
		(width 0.127)
		(layer "In2.Cu")
		(net "SCC_RMT_HEARTBEAT")
	)
	(segment
		(start 118.472712 -17.874488)
		(end 120.017794 -19.41957)
		(width 0.127)
		(layer "In2.Cu")
		(net "SCC_RMT_HEARTBEAT")
	)
	(segment
		(start 108.865924 -17.874488)
		(end 118.472712 -17.874488)
		(width 0.127)
		(layer "In2.Cu")
		(net "SCC_RMT_HEARTBEAT")
	)
	(segment
		(start 86.249002 -42.843196)
		(end 86.249002 -36.809934)
		(width 0.127)
		(layer "In2.Cu")
		(net "SCC_RMT_HEARTBEAT")
	)
	(segment
		(start 84.963 -160.8074)
		(end 84.963 -160.578546)
		(width 0.127)
		(layer "In2.Cu")
		(net "SCC_RMT_HEARTBEAT")
	)
	(segment
		(start 86.249002 -36.809934)
		(end 86.249256 -36.80968)
		(width 0.127)
		(layer "In2.Cu")
		(net "SCC_RMT_HEARTBEAT")
	)
	(segment
		(start 86.804246 -107.98937)
		(end 86.804246 -101.7778)
		(width 0.127)
		(layer "In2.Cu")
		(net "SCC_RMT_HEARTBEAT")
	)
	(segment
		(start 130.199638 -25.425654)
		(end 132.44195 -25.425654)
		(width 0.127)
		(layer "In2.Cu")
		(net "SCC_RMT_HEARTBEAT")
	)
	(segment
		(start 80.63738 -30.882336)
		(end 80.63738 -9.01827)
		(width 0.127)
		(layer "In2.Cu")
		(net "SCC_RMT_HEARTBEAT")
	)
	(segment
		(start 76.676504 -115.950492)
		(end 76.852526 -115.832636)
		(width 0.127)
		(layer "In2.Cu")
		(net "SCC_RMT_HEARTBEAT")
	)
	(segment
		(start 121.64568 -19.41957)
		(end 124.014484 -21.788374)
		(width 0.127)
		(layer "In2.Cu")
		(net "SCC_RMT_HEARTBEAT")
	)
	(segment
		(start 108.03509 -17.043654)
		(end 108.865924 -17.874488)
		(width 0.127)
		(layer "In2.Cu")
		(net "SCC_RMT_HEARTBEAT")
	)
	(segment
		(start 84.992972 -44.099226)
		(end 86.249002 -42.843196)
		(width 0.127)
		(layer "In2.Cu")
		(net "SCC_RMT_HEARTBEAT")
	)
	(segment
		(start 72.440546 -157.480254)
		(end 72.18172 -157.73908)
		(width 0.127)
		(layer "In5.Cu")
		(net "SCC_RMT_HEARTBEAT")
	)
	(segment
		(start 61.341 -154.3304)
		(end 56.87314 -154.3304)
		(width 0.127)
		(layer "In5.Cu")
		(net "SCC_RMT_HEARTBEAT")
	)
	(segment
		(start 38.638226 -153.5049)
		(end 37.2745 -153.5049)
		(width 0.127)
		(layer "In5.Cu")
		(net "SCC_RMT_HEARTBEAT")
	)
	(segment
		(start 50.281332 -154.83205)
		(end 49.525682 -154.0764)
		(width 0.127)
		(layer "In5.Cu")
		(net "SCC_RMT_HEARTBEAT")
	)
	(segment
		(start 56.37149 -154.83205)
		(end 50.281332 -154.83205)
		(width 0.127)
		(layer "In5.Cu")
		(net "SCC_RMT_HEARTBEAT")
	)
	(segment
		(start 39.161466 -153.5049)
		(end 39.063168 -153.406602)
		(width 0.127)
		(layer "In5.Cu")
		(net "SCC_RMT_HEARTBEAT")
	)
	(segment
		(start 38.736524 -153.406602)
		(end 38.638226 -153.5049)
		(width 0.127)
		(layer "In5.Cu")
		(net "SCC_RMT_HEARTBEAT")
	)
	(segment
		(start 37.2745 -153.5049)
		(end 36.7665 -154.0129)
		(width 0.127)
		(layer "In5.Cu")
		(net "SCC_RMT_HEARTBEAT")
	)
	(segment
		(start 72.18172 -157.73908)
		(end 67.96278 -157.73908)
		(width 0.127)
		(layer "In5.Cu")
		(net "SCC_RMT_HEARTBEAT")
	)
	(segment
		(start 63.059818 -156.049218)
		(end 61.341 -154.3304)
		(width 0.127)
		(layer "In5.Cu")
		(net "SCC_RMT_HEARTBEAT")
	)
	(segment
		(start 73.708514 -157.480254)
		(end 72.440546 -157.480254)
		(width 0.127)
		(layer "In5.Cu")
		(net "SCC_RMT_HEARTBEAT")
	)
	(segment
		(start 81.911698 -157.756098)
		(end 73.984358 -157.756098)
		(width 0.127)
		(layer "In5.Cu")
		(net "SCC_RMT_HEARTBEAT")
	)
	(segment
		(start 85.6488 -161.4932)
		(end 81.911698 -157.756098)
		(width 0.127)
		(layer "In5.Cu")
		(net "SCC_RMT_HEARTBEAT")
	)
	(segment
		(start 48.225456 -153.5049)
		(end 39.161466 -153.5049)
		(width 0.127)
		(layer "In5.Cu")
		(net "SCC_RMT_HEARTBEAT")
	)
	(segment
		(start 48.796956 -154.0764)
		(end 48.225456 -153.5049)
		(width 0.127)
		(layer "In5.Cu")
		(net "SCC_RMT_HEARTBEAT")
	)
	(segment
		(start 66.272918 -156.049218)
		(end 63.059818 -156.049218)
		(width 0.127)
		(layer "In5.Cu")
		(net "SCC_RMT_HEARTBEAT")
	)
	(segment
		(start 39.063168 -153.406602)
		(end 38.736524 -153.406602)
		(width 0.127)
		(layer "In5.Cu")
		(net "SCC_RMT_HEARTBEAT")
	)
	(segment
		(start 67.96278 -157.73908)
		(end 66.272918 -156.049218)
		(width 0.127)
		(layer "In5.Cu")
		(net "SCC_RMT_HEARTBEAT")
	)
	(segment
		(start 73.984358 -157.756098)
		(end 73.708514 -157.480254)
		(width 0.127)
		(layer "In5.Cu")
		(net "SCC_RMT_HEARTBEAT")
	)
	(segment
		(start 85.8774 -161.4932)
		(end 85.6488 -161.4932)
		(width 0.127)
		(layer "In5.Cu")
		(net "SCC_RMT_HEARTBEAT")
	)
	(segment
		(start 56.87314 -154.3304)
		(end 56.37149 -154.83205)
		(width 0.127)
		(layer "In5.Cu")
		(net "SCC_RMT_HEARTBEAT")
	)
	(segment
		(start 49.525682 -154.0764)
		(end 48.796956 -154.0764)
		(width 0.127)
		(layer "In5.Cu")
		(net "SCC_RMT_HEARTBEAT")
	)
	(segment
		(start 58.725816 -133.907784)
		(end 58.725816 -134.468616)
		(width 0.127)
		(layer "F.Cu")
		(net "SCC_PWR_EN_R")
	)
	(segment
		(start 56.215026 -137.284968)
		(end 56.331104 -137.284968)
		(width 0.127)
		(layer "F.Cu")
		(net "SCC_PWR_EN_R")
	)
	(segment
		(start 57.628536 -135.565896)
		(end 58.725816 -134.468616)
		(width 0.127)
		(layer "F.Cu")
		(net "SCC_PWR_EN_R")
	)
	(segment
		(start 56.331104 -137.284968)
		(end 57.628536 -135.987536)
		(width 0.127)
		(layer "F.Cu")
		(net "SCC_PWR_EN_R")
	)
	(segment
		(start 60.616592 -131.740656)
		(end 60.616592 -132.017008)
		(width 0.127)
		(layer "F.Cu")
		(net "SCC_PWR_EN_R")
	)
	(segment
		(start 56.099964 -137.40003)
		(end 56.215026 -137.284968)
		(width 0.127)
		(layer "F.Cu")
		(net "SCC_PWR_EN_R")
	)
	(segment
		(start 60.616592 -132.017008)
		(end 58.725816 -133.907784)
		(width 0.127)
		(layer "F.Cu")
		(net "SCC_PWR_EN_R")
	)
	(segment
		(start 57.628536 -135.987536)
		(end 57.628536 -135.565896)
		(width 0.127)
		(layer "F.Cu")
		(net "SCC_PWR_EN_R")
	)
	(via
		(at 58.725816 -134.468616)
		(size 0.6604)
		(drill 0.3302)
		(layers "F.Cu" "B.Cu")
		(net "SCC_PWR_EN_R")
	)
	(segment
		(start 32.906716 -156.889958)
		(end 33.519872 -156.889958)
		(width 0.127)
		(layer "F.Cu")
		(net "SCC_LOC_HEARTBEAT")
	)
	(segment
		(start 32.861504 -155.6766)
		(end 34.2011 -155.6766)
		(width 0.127)
		(layer "F.Cu")
		(net "SCC_LOC_HEARTBEAT")
	)
	(segment
		(start 32.713422 -156.696664)
		(end 32.906716 -156.889958)
		(width 0.127)
		(layer "F.Cu")
		(net "SCC_LOC_HEARTBEAT")
	)
	(segment
		(start 32.713422 -155.824682)
		(end 32.713422 -156.696664)
		(width 0.127)
		(layer "F.Cu")
		(net "SCC_LOC_HEARTBEAT")
	)
	(segment
		(start 32.713422 -155.824682)
		(end 32.861504 -155.6766)
		(width 0.127)
		(layer "F.Cu")
		(net "SCC_LOC_HEARTBEAT")
	)
	(via
		(at 32.713422 -155.824682)
		(size 0.6604)
		(drill 0.3302)
		(layers "F.Cu" "B.Cu")
		(net "SCC_LOC_HEARTBEAT")
	)
	(via
		(at 34.2011 -155.6766)
		(size 0.508)
		(drill 0.254)
		(layers "F.Cu" "B.Cu")
		(net "SCC_LOC_HEARTBEAT")
	)
	(via
		(at 85.1154 -165.2524)
		(size 0.508)
		(drill 0.254)
		(layers "F.Cu" "B.Cu")
		(net "SCC_LOC_HEARTBEAT")
	)
	(segment
		(start 79.30515 -113.919)
		(end 83.1088 -113.919)
		(width 0.127)
		(layer "In2.Cu")
		(net "SCC_LOC_HEARTBEAT")
	)
	(segment
		(start 82.091276 -147.5232)
		(end 80.6069 -146.038824)
		(width 0.127)
		(layer "In2.Cu")
		(net "SCC_LOC_HEARTBEAT")
	)
	(segment
		(start 85.1916 -111.8362)
		(end 85.1916 -110.141004)
		(width 0.127)
		(layer "In2.Cu")
		(net "SCC_LOC_HEARTBEAT")
	)
	(segment
		(start 138.271504 -38.628574)
		(end 137.700004 -39.200074)
		(width 0.127)
		(layer "In2.Cu")
		(net "SCC_LOC_HEARTBEAT")
	)
	(segment
		(start 81.01838 -9.176258)
		(end 82.6897 -7.504938)
		(width 0.127)
		(layer "In2.Cu")
		(net "SCC_LOC_HEARTBEAT")
	)
	(segment
		(start 136.805924 -30.328616)
		(end 137.936732 -30.328616)
		(width 0.127)
		(layer "In2.Cu")
		(net "SCC_LOC_HEARTBEAT")
	)
	(segment
		(start 86.630002 -36.967922)
		(end 86.630256 -36.967668)
		(width 0.127)
		(layer "In2.Cu")
		(net "SCC_LOC_HEARTBEAT")
	)
	(segment
		(start 86.630256 -36.967668)
		(end 86.630256 -36.336224)
		(width 0.127)
		(layer "In2.Cu")
		(net "SCC_LOC_HEARTBEAT")
	)
	(segment
		(start 85.5726 -163.9062)
		(end 85.5726 -162.962082)
		(width 0.127)
		(layer "In2.Cu")
		(net "SCC_LOC_HEARTBEAT")
	)
	(segment
		(start 126.40437 -22.169374)
		(end 130.141472 -25.906476)
		(width 0.127)
		(layer "In2.Cu")
		(net "SCC_LOC_HEARTBEAT")
	)
	(segment
		(start 101.907594 -17.424654)
		(end 107.79633 -17.424654)
		(width 0.127)
		(layer "In2.Cu")
		(net "SCC_LOC_HEARTBEAT")
	)
	(segment
		(start 85.7123 -162.822382)
		(end 85.7123 -162.3695)
		(width 0.127)
		(layer "In2.Cu")
		(net "SCC_LOC_HEARTBEAT")
	)
	(segment
		(start 84.488528 -63.482728)
		(end 84.488528 -47.3964)
		(width 0.127)
		(layer "In2.Cu")
		(net "SCC_LOC_HEARTBEAT")
	)
	(segment
		(start 80.489044 -140.33881)
		(end 80.489044 -129.445004)
		(width 0.127)
		(layer "In2.Cu")
		(net "SCC_LOC_HEARTBEAT")
	)
	(segment
		(start 86.3473 -161.7345)
		(end 86.3473 -161.298382)
		(width 0.127)
		(layer "In2.Cu")
		(net "SCC_LOC_HEARTBEAT")
	)
	(segment
		(start 80.6069 -146.038824)
		(end 80.6069 -140.456666)
		(width 0.127)
		(layer "In2.Cu")
		(net "SCC_LOC_HEARTBEAT")
	)
	(segment
		(start 87.581232 -66.575432)
		(end 84.488528 -63.482728)
		(width 0.127)
		(layer "In2.Cu")
		(net "SCC_LOC_HEARTBEAT")
	)
	(segment
		(start 82.6897 -7.504938)
		(end 93.873574 -7.504938)
		(width 0.127)
		(layer "In2.Cu")
		(net "SCC_LOC_HEARTBEAT")
	)
	(segment
		(start 85.1154 -165.2524)
		(end 85.1154 -164.3634)
		(width 0.127)
		(layer "In2.Cu")
		(net "SCC_LOC_HEARTBEAT")
	)
	(segment
		(start 86.215728 -90.859864)
		(end 87.581232 -89.49436)
		(width 0.127)
		(layer "In2.Cu")
		(net "SCC_LOC_HEARTBEAT")
	)
	(segment
		(start 87.185246 -101.6)
		(end 86.215728 -100.630482)
		(width 0.127)
		(layer "In2.Cu")
		(net "SCC_LOC_HEARTBEAT")
	)
	(segment
		(start 87.581232 -89.49436)
		(end 87.581232 -66.575432)
		(width 0.127)
		(layer "In2.Cu")
		(net "SCC_LOC_HEARTBEAT")
	)
	(segment
		(start 85.5726 -162.962082)
		(end 85.7123 -162.822382)
		(width 0.127)
		(layer "In2.Cu")
		(net "SCC_LOC_HEARTBEAT")
	)
	(segment
		(start 97.329498 -12.846558)
		(end 101.907594 -17.424654)
		(width 0.127)
		(layer "In2.Cu")
		(net "SCC_LOC_HEARTBEAT")
	)
	(segment
		(start 86.3473 -161.298382)
		(end 85.635846 -160.586928)
		(width 0.127)
		(layer "In2.Cu")
		(net "SCC_LOC_HEARTBEAT")
	)
	(segment
		(start 86.215728 -100.630482)
		(end 86.215728 -90.859864)
		(width 0.127)
		(layer "In2.Cu")
		(net "SCC_LOC_HEARTBEAT")
	)
	(segment
		(start 84.488528 -47.3964)
		(end 85.389466 -46.495462)
		(width 0.127)
		(layer "In2.Cu")
		(net "SCC_LOC_HEARTBEAT")
	)
	(segment
		(start 108.627164 -18.255488)
		(end 118.314724 -18.255488)
		(width 0.127)
		(layer "In2.Cu")
		(net "SCC_LOC_HEARTBEAT")
	)
	(segment
		(start 80.7466 -129.187448)
		(end 80.7466 -127.9398)
		(width 0.127)
		(layer "In2.Cu")
		(net "SCC_LOC_HEARTBEAT")
	)
	(segment
		(start 80.6069 -140.456666)
		(end 80.489044 -140.33881)
		(width 0.127)
		(layer "In2.Cu")
		(net "SCC_LOC_HEARTBEAT")
	)
	(segment
		(start 80.7466 -127.9398)
		(end 75.124056 -122.317256)
		(width 0.127)
		(layer "In2.Cu")
		(net "SCC_LOC_HEARTBEAT")
	)
	(segment
		(start 107.79633 -17.424654)
		(end 108.627164 -18.255488)
		(width 0.127)
		(layer "In2.Cu")
		(net "SCC_LOC_HEARTBEAT")
	)
	(segment
		(start 85.389466 -46.495462)
		(end 85.389466 -44.24172)
		(width 0.127)
		(layer "In2.Cu")
		(net "SCC_LOC_HEARTBEAT")
	)
	(segment
		(start 130.141472 -25.906476)
		(end 131.87807 -25.906476)
		(width 0.127)
		(layer "In2.Cu")
		(net "SCC_LOC_HEARTBEAT")
	)
	(segment
		(start 93.873574 -7.504938)
		(end 97.329498 -10.960862)
		(width 0.127)
		(layer "In2.Cu")
		(net "SCC_LOC_HEARTBEAT")
	)
	(segment
		(start 85.635846 -159.372046)
		(end 83.0326 -156.7688)
		(width 0.127)
		(layer "In2.Cu")
		(net "SCC_LOC_HEARTBEAT")
	)
	(segment
		(start 123.856496 -22.169374)
		(end 126.40437 -22.169374)
		(width 0.127)
		(layer "In2.Cu")
		(net "SCC_LOC_HEARTBEAT")
	)
	(segment
		(start 138.271504 -30.663388)
		(end 138.271504 -38.628574)
		(width 0.127)
		(layer "In2.Cu")
		(net "SCC_LOC_HEARTBEAT")
	)
	(segment
		(start 119.859806 -19.80057)
		(end 121.487692 -19.80057)
		(width 0.127)
		(layer "In2.Cu")
		(net "SCC_LOC_HEARTBEAT")
	)
	(segment
		(start 76.919582 -116.246402)
		(end 77.095604 -116.128546)
		(width 0.127)
		(layer "In2.Cu")
		(net "SCC_LOC_HEARTBEAT")
	)
	(segment
		(start 83.0326 -156.7688)
		(end 83.0326 -149.862794)
		(width 0.127)
		(layer "In2.Cu")
		(net "SCC_LOC_HEARTBEAT")
	)
	(segment
		(start 81.01838 -30.724348)
		(end 81.01838 -9.176258)
		(width 0.127)
		(layer "In2.Cu")
		(net "SCC_LOC_HEARTBEAT")
	)
	(segment
		(start 86.630002 -43.001184)
		(end 86.630002 -36.967922)
		(width 0.127)
		(layer "In2.Cu")
		(net "SCC_LOC_HEARTBEAT")
	)
	(segment
		(start 137.936732 -30.328616)
		(end 138.271504 -30.663388)
		(width 0.127)
		(layer "In2.Cu")
		(net "SCC_LOC_HEARTBEAT")
	)
	(segment
		(start 85.1916 -110.141004)
		(end 87.185246 -108.147358)
		(width 0.127)
		(layer "In2.Cu")
		(net "SCC_LOC_HEARTBEAT")
	)
	(segment
		(start 76.128626 -117.095524)
		(end 76.246482 -116.919502)
		(width 0.127)
		(layer "In2.Cu")
		(net "SCC_LOC_HEARTBEAT")
	)
	(segment
		(start 85.635846 -160.586928)
		(end 85.635846 -159.372046)
		(width 0.127)
		(layer "In2.Cu")
		(net "SCC_LOC_HEARTBEAT")
	)
	(segment
		(start 118.314724 -18.255488)
		(end 119.859806 -19.80057)
		(width 0.127)
		(layer "In2.Cu")
		(net "SCC_LOC_HEARTBEAT")
	)
	(segment
		(start 85.7123 -162.3695)
		(end 86.3473 -161.7345)
		(width 0.127)
		(layer "In2.Cu")
		(net "SCC_LOC_HEARTBEAT")
	)
	(segment
		(start 131.87807 -25.906476)
		(end 132.384292 -25.906984)
		(width 0.127)
		(layer "In2.Cu")
		(net "SCC_LOC_HEARTBEAT")
	)
	(segment
		(start 87.185246 -108.147358)
		(end 87.185246 -101.6)
		(width 0.127)
		(layer "In2.Cu")
		(net "SCC_LOC_HEARTBEAT")
	)
	(segment
		(start 82.091276 -148.92147)
		(end 82.091276 -147.5232)
		(width 0.127)
		(layer "In2.Cu")
		(net "SCC_LOC_HEARTBEAT")
	)
	(segment
		(start 75.124056 -122.317256)
		(end 75.124056 -118.100348)
		(width 0.127)
		(layer "In2.Cu")
		(net "SCC_LOC_HEARTBEAT")
	)
	(segment
		(start 85.389466 -44.24172)
		(end 86.630002 -43.001184)
		(width 0.127)
		(layer "In2.Cu")
		(net "SCC_LOC_HEARTBEAT")
	)
	(segment
		(start 121.487692 -19.80057)
		(end 123.856496 -22.169374)
		(width 0.127)
		(layer "In2.Cu")
		(net "SCC_LOC_HEARTBEAT")
	)
	(segment
		(start 97.329498 -10.960862)
		(end 97.329498 -12.846558)
		(width 0.127)
		(layer "In2.Cu")
		(net "SCC_LOC_HEARTBEAT")
	)
	(segment
		(start 83.1088 -113.919)
		(end 85.1916 -111.8362)
		(width 0.127)
		(layer "In2.Cu")
		(net "SCC_LOC_HEARTBEAT")
	)
	(segment
		(start 77.095604 -116.128546)
		(end 79.30515 -113.919)
		(width 0.127)
		(layer "In2.Cu")
		(net "SCC_LOC_HEARTBEAT")
	)
	(segment
		(start 85.1154 -164.3634)
		(end 85.5726 -163.9062)
		(width 0.127)
		(layer "In2.Cu")
		(net "SCC_LOC_HEARTBEAT")
	)
	(segment
		(start 80.489044 -129.445004)
		(end 80.7466 -129.187448)
		(width 0.127)
		(layer "In2.Cu")
		(net "SCC_LOC_HEARTBEAT")
	)
	(segment
		(start 76.246482 -116.919502)
		(end 76.919582 -116.246402)
		(width 0.127)
		(layer "In2.Cu")
		(net "SCC_LOC_HEARTBEAT")
	)
	(segment
		(start 83.0326 -149.862794)
		(end 82.091276 -148.92147)
		(width 0.127)
		(layer "In2.Cu")
		(net "SCC_LOC_HEARTBEAT")
	)
	(segment
		(start 132.384292 -25.906984)
		(end 136.805924 -30.328616)
		(width 0.127)
		(layer "In2.Cu")
		(net "SCC_LOC_HEARTBEAT")
	)
	(segment
		(start 75.124056 -118.100348)
		(end 76.128626 -117.095524)
		(width 0.127)
		(layer "In2.Cu")
		(net "SCC_LOC_HEARTBEAT")
	)
	(segment
		(start 86.630256 -36.336224)
		(end 81.01838 -30.724348)
		(width 0.127)
		(layer "In2.Cu")
		(net "SCC_LOC_HEARTBEAT")
	)
	(segment
		(start 85.1154 -165.374574)
		(end 84.551774 -165.9382)
		(width 0.127)
		(layer "In5.Cu")
		(net "SCC_LOC_HEARTBEAT")
	)
	(segment
		(start 82.412078 -165.482016)
		(end 73.743312 -165.482016)
		(width 0.127)
		(layer "In5.Cu")
		(net "SCC_LOC_HEARTBEAT")
	)
	(segment
		(start 47.531782 -160.1089)
		(end 47.2567 -159.833818)
		(width 0.127)
		(layer "In5.Cu")
		(net "SCC_LOC_HEARTBEAT")
	)
	(segment
		(start 45.955458 -158.364936)
		(end 37.15258 -158.364936)
		(width 0.127)
		(layer "In5.Cu")
		(net "SCC_LOC_HEARTBEAT")
	)
	(segment
		(start 56.1467 -164.193982)
		(end 55.871618 -163.9189)
		(width 0.127)
		(layer "In5.Cu")
		(net "SCC_LOC_HEARTBEAT")
	)
	(segment
		(start 84.551774 -165.9382)
		(end 82.868262 -165.9382)
		(width 0.127)
		(layer "In5.Cu")
		(net "SCC_LOC_HEARTBEAT")
	)
	(segment
		(start 53.537358 -162.143186)
		(end 52.086256 -160.692084)
		(width 0.127)
		(layer "In5.Cu")
		(net "SCC_LOC_HEARTBEAT")
	)
	(segment
		(start 56.1467 -164.752782)
		(end 56.1467 -164.193982)
		(width 0.127)
		(layer "In5.Cu")
		(net "SCC_LOC_HEARTBEAT")
	)
	(segment
		(start 55.871618 -163.9189)
		(end 55.312818 -163.9189)
		(width 0.127)
		(layer "In5.Cu")
		(net "SCC_LOC_HEARTBEAT")
	)
	(segment
		(start 64.135762 -166.549578)
		(end 63.327534 -165.74135)
		(width 0.127)
		(layer "In5.Cu")
		(net "SCC_LOC_HEARTBEAT")
	)
	(segment
		(start 49.952656 -161.059114)
		(end 48.884586 -161.059114)
		(width 0.127)
		(layer "In5.Cu")
		(net "SCC_LOC_HEARTBEAT")
	)
	(segment
		(start 49.95291 -161.059368)
		(end 49.952656 -161.059114)
		(width 0.127)
		(layer "In5.Cu")
		(net "SCC_LOC_HEARTBEAT")
	)
	(segment
		(start 50.268378 -161.059368)
		(end 49.95291 -161.059368)
		(width 0.127)
		(layer "In5.Cu")
		(net "SCC_LOC_HEARTBEAT")
	)
	(segment
		(start 50.635662 -160.692084)
		(end 50.268378 -161.059368)
		(width 0.127)
		(layer "In5.Cu")
		(net "SCC_LOC_HEARTBEAT")
	)
	(segment
		(start 55.312818 -163.9189)
		(end 53.537358 -162.14344)
		(width 0.127)
		(layer "In5.Cu")
		(net "SCC_LOC_HEARTBEAT")
	)
	(segment
		(start 53.537358 -162.14344)
		(end 53.537358 -162.143186)
		(width 0.127)
		(layer "In5.Cu")
		(net "SCC_LOC_HEARTBEAT")
	)
	(segment
		(start 72.67575 -166.549578)
		(end 64.135762 -166.549578)
		(width 0.127)
		(layer "In5.Cu")
		(net "SCC_LOC_HEARTBEAT")
	)
	(segment
		(start 47.2567 -159.833818)
		(end 47.2567 -159.666178)
		(width 0.127)
		(layer "In5.Cu")
		(net "SCC_LOC_HEARTBEAT")
	)
	(segment
		(start 48.884586 -161.059114)
		(end 47.934372 -160.1089)
		(width 0.127)
		(layer "In5.Cu")
		(net "SCC_LOC_HEARTBEAT")
	)
	(segment
		(start 73.743312 -165.482016)
		(end 72.67575 -166.549578)
		(width 0.127)
		(layer "In5.Cu")
		(net "SCC_LOC_HEARTBEAT")
	)
	(segment
		(start 47.2567 -159.666178)
		(end 45.955458 -158.364936)
		(width 0.127)
		(layer "In5.Cu")
		(net "SCC_LOC_HEARTBEAT")
	)
	(segment
		(start 34.464244 -155.6766)
		(end 34.2011 -155.6766)
		(width 0.127)
		(layer "In5.Cu")
		(net "SCC_LOC_HEARTBEAT")
	)
	(segment
		(start 82.868262 -165.9382)
		(end 82.412078 -165.482016)
		(width 0.127)
		(layer "In5.Cu")
		(net "SCC_LOC_HEARTBEAT")
	)
	(segment
		(start 63.327534 -165.74135)
		(end 57.135268 -165.74135)
		(width 0.127)
		(layer "In5.Cu")
		(net "SCC_LOC_HEARTBEAT")
	)
	(segment
		(start 52.086256 -160.692084)
		(end 50.635662 -160.692084)
		(width 0.127)
		(layer "In5.Cu")
		(net "SCC_LOC_HEARTBEAT")
	)
	(segment
		(start 37.15258 -158.364936)
		(end 34.464244 -155.6766)
		(width 0.127)
		(layer "In5.Cu")
		(net "SCC_LOC_HEARTBEAT")
	)
	(segment
		(start 85.1154 -165.2524)
		(end 85.1154 -165.374574)
		(width 0.127)
		(layer "In5.Cu")
		(net "SCC_LOC_HEARTBEAT")
	)
	(segment
		(start 47.934372 -160.1089)
		(end 47.531782 -160.1089)
		(width 0.127)
		(layer "In5.Cu")
		(net "SCC_LOC_HEARTBEAT")
	)
	(segment
		(start 57.135268 -165.74135)
		(end 56.1467 -164.752782)
		(width 0.127)
		(layer "In5.Cu")
		(net "SCC_LOC_HEARTBEAT")
	)
	(segment
		(start 73.6346 -185.0009)
		(end 74.0918 -185.4581)
		(width 0.254)
		(layer "F.Cu")
		(net "PWRGD_P2V5_STBY")
	)
	(segment
		(start 153.203656 -138.240262)
		(end 153.203656 -139.106656)
		(width 0.254)
		(layer "F.Cu")
		(net "PWRGD_P2V5_STBY")
	)
	(segment
		(start 153.203656 -139.106656)
		(end 153.373074 -139.276074)
		(width 0.254)
		(layer "F.Cu")
		(net "PWRGD_P2V5_STBY")
	)
	(segment
		(start 73.6346 -184.6834)
		(end 73.6346 -185.0009)
		(width 0.254)
		(layer "F.Cu")
		(net "PWRGD_P2V5_STBY")
	)
	(segment
		(start 73.66 -184.658)
		(end 73.6346 -184.6834)
		(width 0.254)
		(layer "F.Cu")
		(net "PWRGD_P2V5_STBY")
	)
	(segment
		(start 74.0918 -185.4581)
		(end 74.44105 -185.10885)
		(width 0.254)
		(layer "F.Cu")
		(net "PWRGD_P2V5_STBY")
	)
	(segment
		(start 153.373074 -139.276074)
		(end 154.0764 -139.9794)
		(width 0.254)
		(layer "F.Cu")
		(net "PWRGD_P2V5_STBY")
	)
	(segment
		(start 74.44105 -185.10885)
		(end 74.44105 -182.832502)
		(width 0.254)
		(layer "F.Cu")
		(net "PWRGD_P2V5_STBY")
	)
	(via
		(at 154.0764 -139.9794)
		(size 0.508)
		(drill 0.254)
		(layers "F.Cu" "B.Cu")
		(net "PWRGD_P2V5_STBY")
	)
	(via
		(at 153.373074 -139.276074)
		(size 0.6604)
		(drill 0.3302)
		(layers "F.Cu" "B.Cu")
		(net "PWRGD_P2V5_STBY")
	)
	(via
		(at 73.66 -184.658)
		(size 0.508)
		(drill 0.254)
		(layers "F.Cu" "B.Cu")
		(net "PWRGD_P2V5_STBY")
	)
	(segment
		(start 143.625824 -20.59559)
		(end 147.701 -24.670766)
		(width 0.254)
		(layer "In2.Cu")
		(net "PWRGD_P2V5_STBY")
	)
	(segment
		(start 143.797782 -15.362428)
		(end 144.040606 -15.605252)
		(width 0.254)
		(layer "In2.Cu")
		(net "PWRGD_P2V5_STBY")
	)
	(segment
		(start 73.66 -184.658)
		(end 72.932544 -184.658)
		(width 0.254)
		(layer "In2.Cu")
		(net "PWRGD_P2V5_STBY")
	)
	(segment
		(start 78.5876 -99.990656)
		(end 78.5876 -93.6752)
		(width 0.254)
		(layer "In2.Cu")
		(net "PWRGD_P2V5_STBY")
	)
	(segment
		(start 143.797782 -9.287002)
		(end 143.797782 -15.362428)
		(width 0.254)
		(layer "In2.Cu")
		(net "PWRGD_P2V5_STBY")
	)
	(segment
		(start 81.101438 -69.773038)
		(end 80.137 -68.8086)
		(width 0.254)
		(layer "In2.Cu")
		(net "PWRGD_P2V5_STBY")
	)
	(segment
		(start 70.6628 -171.831)
		(end 71.755 -170.7388)
		(width 0.254)
		(layer "In2.Cu")
		(net "PWRGD_P2V5_STBY")
	)
	(segment
		(start 68.7959 -151.142954)
		(end 68.7959 -145.29308)
		(width 0.254)
		(layer "In2.Cu")
		(net "PWRGD_P2V5_STBY")
	)
	(segment
		(start 142.303754 -4.538726)
		(end 142.303754 -7.792974)
		(width 0.254)
		(layer "In2.Cu")
		(net "PWRGD_P2V5_STBY")
	)
	(segment
		(start 79.790544 -101.1936)
		(end 78.5876 -99.990656)
		(width 0.254)
		(layer "In2.Cu")
		(net "PWRGD_P2V5_STBY")
	)
	(segment
		(start 68.025264 -138.905488)
		(end 67.527678 -138.407902)
		(width 0.254)
		(layer "In2.Cu")
		(net "PWRGD_P2V5_STBY")
	)
	(segment
		(start 82.517742 -36.913566)
		(end 77.560424 -31.956248)
		(width 0.254)
		(layer "In2.Cu")
		(net "PWRGD_P2V5_STBY")
	)
	(segment
		(start 68.586096 -134.84733)
		(end 68.586096 -123.748292)
		(width 0.254)
		(layer "In2.Cu")
		(net "PWRGD_P2V5_STBY")
	)
	(segment
		(start 140.653008 -2.88798)
		(end 142.303754 -4.538726)
		(width 0.254)
		(layer "In2.Cu")
		(net "PWRGD_P2V5_STBY")
	)
	(segment
		(start 149.96922 -135.87222)
		(end 154.0764 -139.9794)
		(width 0.254)
		(layer "In2.Cu")
		(net "PWRGD_P2V5_STBY")
	)
	(segment
		(start 80.4418 -93.1672)
		(end 81.101438 -92.507562)
		(width 0.254)
		(layer "In2.Cu")
		(net "PWRGD_P2V5_STBY")
	)
	(segment
		(start 82.95894 -4.3688)
		(end 84.43976 -2.88798)
		(width 0.254)
		(layer "In2.Cu")
		(net "PWRGD_P2V5_STBY")
	)
	(segment
		(start 147.701 -24.670766)
		(end 147.701 -44.894246)
		(width 0.254)
		(layer "In2.Cu")
		(net "PWRGD_P2V5_STBY")
	)
	(segment
		(start 71.755 -167.58412)
		(end 69.8627 -165.69182)
		(width 0.254)
		(layer "In2.Cu")
		(net "PWRGD_P2V5_STBY")
	)
	(segment
		(start 78.5876 -93.6752)
		(end 79.0956 -93.1672)
		(width 0.254)
		(layer "In2.Cu")
		(net "PWRGD_P2V5_STBY")
	)
	(segment
		(start 149.96922 -105.127298)
		(end 149.96922 -135.87222)
		(width 0.254)
		(layer "In2.Cu")
		(net "PWRGD_P2V5_STBY")
	)
	(segment
		(start 80.137 -49.403)
		(end 80.974692 -48.565308)
		(width 0.254)
		(layer "In2.Cu")
		(net "PWRGD_P2V5_STBY")
	)
	(segment
		(start 150.61057 -95.24492)
		(end 151.8539 -96.48825)
		(width 0.254)
		(layer "In2.Cu")
		(net "PWRGD_P2V5_STBY")
	)
	(segment
		(start 70.850252 -113.214404)
		(end 73.793858 -113.214404)
		(width 0.254)
		(layer "In2.Cu")
		(net "PWRGD_P2V5_STBY")
	)
	(segment
		(start 80.974692 -42.240708)
		(end 82.517742 -40.697658)
		(width 0.254)
		(layer "In2.Cu")
		(net "PWRGD_P2V5_STBY")
	)
	(segment
		(start 144.040606 -15.605252)
		(end 144.040606 -16.83766)
		(width 0.254)
		(layer "In2.Cu")
		(net "PWRGD_P2V5_STBY")
	)
	(segment
		(start 69.2277 -123.106688)
		(end 69.2277 -121.394474)
		(width 0.254)
		(layer "In2.Cu")
		(net "PWRGD_P2V5_STBY")
	)
	(segment
		(start 67.527678 -135.905748)
		(end 68.586096 -134.84733)
		(width 0.254)
		(layer "In2.Cu")
		(net "PWRGD_P2V5_STBY")
	)
	(segment
		(start 81.697322 -101.1936)
		(end 79.790544 -101.1936)
		(width 0.254)
		(layer "In2.Cu")
		(net "PWRGD_P2V5_STBY")
	)
	(segment
		(start 151.8539 -103.242618)
		(end 149.96922 -105.127298)
		(width 0.254)
		(layer "In2.Cu")
		(net "PWRGD_P2V5_STBY")
	)
	(segment
		(start 149.988778 -47.182024)
		(end 149.988778 -85.964522)
		(width 0.254)
		(layer "In2.Cu")
		(net "PWRGD_P2V5_STBY")
	)
	(segment
		(start 84.073746 -106.501946)
		(end 84.073746 -103.570024)
		(width 0.254)
		(layer "In2.Cu")
		(net "PWRGD_P2V5_STBY")
	)
	(segment
		(start 67.6275 -119.794274)
		(end 67.6275 -116.437156)
		(width 0.254)
		(layer "In2.Cu")
		(net "PWRGD_P2V5_STBY")
	)
	(segment
		(start 147.701 -44.894246)
		(end 149.988778 -47.182024)
		(width 0.254)
		(layer "In2.Cu")
		(net "PWRGD_P2V5_STBY")
	)
	(segment
		(start 78.207362 -108.8009)
		(end 81.774792 -108.8009)
		(width 0.254)
		(layer "In2.Cu")
		(net "PWRGD_P2V5_STBY")
	)
	(segment
		(start 151.8539 -96.48825)
		(end 151.8539 -103.242618)
		(width 0.254)
		(layer "In2.Cu")
		(net "PWRGD_P2V5_STBY")
	)
	(segment
		(start 144.040606 -16.83766)
		(end 143.625824 -17.252442)
		(width 0.254)
		(layer "In2.Cu")
		(net "PWRGD_P2V5_STBY")
	)
	(segment
		(start 72.932544 -184.658)
		(end 69.7357 -181.461156)
		(width 0.254)
		(layer "In2.Cu")
		(net "PWRGD_P2V5_STBY")
	)
	(segment
		(start 77.560424 -31.956248)
		(end 77.560424 -9.669526)
		(width 0.254)
		(layer "In2.Cu")
		(net "PWRGD_P2V5_STBY")
	)
	(segment
		(start 78.28788 -8.044434)
		(end 81.963514 -4.3688)
		(width 0.254)
		(layer "In2.Cu")
		(net "PWRGD_P2V5_STBY")
	)
	(segment
		(start 68.025264 -141.377162)
		(end 68.025264 -138.905488)
		(width 0.254)
		(layer "In2.Cu")
		(net "PWRGD_P2V5_STBY")
	)
	(segment
		(start 72.2884 -157.7594)
		(end 72.2884 -156.9847)
		(width 0.254)
		(layer "In2.Cu")
		(net "PWRGD_P2V5_STBY")
	)
	(segment
		(start 70.6628 -172.35678)
		(end 70.6628 -171.831)
		(width 0.254)
		(layer "In2.Cu")
		(net "PWRGD_P2V5_STBY")
	)
	(segment
		(start 67.527678 -138.407902)
		(end 67.527678 -135.905748)
		(width 0.254)
		(layer "In2.Cu")
		(net "PWRGD_P2V5_STBY")
	)
	(segment
		(start 69.634608 -159.0675)
		(end 70.9803 -159.0675)
		(width 0.254)
		(layer "In2.Cu")
		(net "PWRGD_P2V5_STBY")
	)
	(segment
		(start 82.517742 -40.697658)
		(end 82.517742 -36.913566)
		(width 0.254)
		(layer "In2.Cu")
		(net "PWRGD_P2V5_STBY")
	)
	(segment
		(start 143.625824 -17.252442)
		(end 143.625824 -20.59559)
		(width 0.254)
		(layer "In2.Cu")
		(net "PWRGD_P2V5_STBY")
	)
	(segment
		(start 69.8627 -165.69182)
		(end 69.8627 -163.7538)
		(width 0.254)
		(layer "In2.Cu")
		(net "PWRGD_P2V5_STBY")
	)
	(segment
		(start 81.101438 -92.507562)
		(end 81.101438 -69.773038)
		(width 0.254)
		(layer "In2.Cu")
		(net "PWRGD_P2V5_STBY")
	)
	(segment
		(start 73.793858 -113.214404)
		(end 78.207362 -108.8009)
		(width 0.254)
		(layer "In2.Cu")
		(net "PWRGD_P2V5_STBY")
	)
	(segment
		(start 80.137 -68.8086)
		(end 80.137 -49.403)
		(width 0.254)
		(layer "In2.Cu")
		(net "PWRGD_P2V5_STBY")
	)
	(segment
		(start 69.7357 -181.461156)
		(end 69.7357 -173.28388)
		(width 0.254)
		(layer "In2.Cu")
		(net "PWRGD_P2V5_STBY")
	)
	(segment
		(start 68.586096 -123.748292)
		(end 69.2277 -123.106688)
		(width 0.254)
		(layer "In2.Cu")
		(net "PWRGD_P2V5_STBY")
	)
	(segment
		(start 69.8627 -163.7538)
		(end 68.989956 -162.881056)
		(width 0.254)
		(layer "In2.Cu")
		(net "PWRGD_P2V5_STBY")
	)
	(segment
		(start 78.28788 -8.94207)
		(end 78.28788 -8.044434)
		(width 0.254)
		(layer "In2.Cu")
		(net "PWRGD_P2V5_STBY")
	)
	(segment
		(start 68.7959 -145.29308)
		(end 68.0212 -144.51838)
		(width 0.254)
		(layer "In2.Cu")
		(net "PWRGD_P2V5_STBY")
	)
	(segment
		(start 84.073746 -103.570024)
		(end 81.697322 -101.1936)
		(width 0.254)
		(layer "In2.Cu")
		(net "PWRGD_P2V5_STBY")
	)
	(segment
		(start 79.0956 -93.1672)
		(end 80.4418 -93.1672)
		(width 0.254)
		(layer "In2.Cu")
		(net "PWRGD_P2V5_STBY")
	)
	(segment
		(start 68.989956 -162.881056)
		(end 68.989956 -159.712152)
		(width 0.254)
		(layer "In2.Cu")
		(net "PWRGD_P2V5_STBY")
	)
	(segment
		(start 84.43976 -2.88798)
		(end 140.653008 -2.88798)
		(width 0.254)
		(layer "In2.Cu")
		(net "PWRGD_P2V5_STBY")
	)
	(segment
		(start 142.303754 -7.792974)
		(end 143.797782 -9.287002)
		(width 0.254)
		(layer "In2.Cu")
		(net "PWRGD_P2V5_STBY")
	)
	(segment
		(start 70.9803 -159.0675)
		(end 72.2884 -157.7594)
		(width 0.254)
		(layer "In2.Cu")
		(net "PWRGD_P2V5_STBY")
	)
	(segment
		(start 81.774792 -108.8009)
		(end 84.073746 -106.501946)
		(width 0.254)
		(layer "In2.Cu")
		(net "PWRGD_P2V5_STBY")
	)
	(segment
		(start 69.2277 -121.394474)
		(end 67.6275 -119.794274)
		(width 0.254)
		(layer "In2.Cu")
		(net "PWRGD_P2V5_STBY")
	)
	(segment
		(start 149.988778 -85.964522)
		(end 150.61057 -86.586314)
		(width 0.254)
		(layer "In2.Cu")
		(net "PWRGD_P2V5_STBY")
	)
	(segment
		(start 69.7357 -173.28388)
		(end 70.6628 -172.35678)
		(width 0.254)
		(layer "In2.Cu")
		(net "PWRGD_P2V5_STBY")
	)
	(segment
		(start 68.0212 -141.381226)
		(end 68.025264 -141.377162)
		(width 0.254)
		(layer "In2.Cu")
		(net "PWRGD_P2V5_STBY")
	)
	(segment
		(start 68.989956 -159.712152)
		(end 69.634608 -159.0675)
		(width 0.254)
		(layer "In2.Cu")
		(net "PWRGD_P2V5_STBY")
	)
	(segment
		(start 67.6275 -116.437156)
		(end 70.850252 -113.214404)
		(width 0.254)
		(layer "In2.Cu")
		(net "PWRGD_P2V5_STBY")
	)
	(segment
		(start 68.0212 -144.51838)
		(end 68.0212 -141.381226)
		(width 0.254)
		(layer "In2.Cu")
		(net "PWRGD_P2V5_STBY")
	)
	(segment
		(start 72.79513 -156.47797)
		(end 72.79513 -155.142184)
		(width 0.254)
		(layer "In2.Cu")
		(net "PWRGD_P2V5_STBY")
	)
	(segment
		(start 81.963514 -4.3688)
		(end 82.95894 -4.3688)
		(width 0.254)
		(layer "In2.Cu")
		(net "PWRGD_P2V5_STBY")
	)
	(segment
		(start 71.755 -170.7388)
		(end 71.755 -167.58412)
		(width 0.254)
		(layer "In2.Cu")
		(net "PWRGD_P2V5_STBY")
	)
	(segment
		(start 150.61057 -86.586314)
		(end 150.61057 -95.24492)
		(width 0.254)
		(layer "In2.Cu")
		(net "PWRGD_P2V5_STBY")
	)
	(segment
		(start 72.2884 -156.9847)
		(end 72.79513 -156.47797)
		(width 0.254)
		(layer "In2.Cu")
		(net "PWRGD_P2V5_STBY")
	)
	(segment
		(start 72.79513 -155.142184)
		(end 68.7959 -151.142954)
		(width 0.254)
		(layer "In2.Cu")
		(net "PWRGD_P2V5_STBY")
	)
	(segment
		(start 77.560424 -9.669526)
		(end 78.28788 -8.94207)
		(width 0.254)
		(layer "In2.Cu")
		(net "PWRGD_P2V5_STBY")
	)
	(segment
		(start 80.974692 -48.565308)
		(end 80.974692 -42.240708)
		(width 0.254)
		(layer "In2.Cu")
		(net "PWRGD_P2V5_STBY")
	)
	(segment
		(start 195.200016 -54.70017)
		(end 195.599812 -55.099966)
		(width 0.254)
		(layer "F.Cu")
		(net "PWRGD_P1V8")
	)
	(segment
		(start 199.213724 -131.699)
		(end 199.263 -131.748276)
		(width 0.254)
		(layer "F.Cu")
		(net "PWRGD_P1V8")
	)
	(segment
		(start 199.263 -131.748276)
		(end 199.792336 -132.277612)
		(width 0.254)
		(layer "F.Cu")
		(net "PWRGD_P1V8")
	)
	(segment
		(start 198.5518 -130.440684)
		(end 198.5518 -129.7686)
		(width 0.254)
		(layer "F.Cu")
		(net "PWRGD_P1V8")
	)
	(segment
		(start 198.756016 -130.6449)
		(end 198.5518 -130.440684)
		(width 0.254)
		(layer "F.Cu")
		(net "PWRGD_P1V8")
	)
	(segment
		(start 195.599812 -55.099966)
		(end 195.600066 -55.099966)
		(width 0.254)
		(layer "F.Cu")
		(net "PWRGD_P1V8")
	)
	(segment
		(start 199.792336 -132.277612)
		(end 199.792336 -133.35)
		(width 0.254)
		(layer "F.Cu")
		(net "PWRGD_P1V8")
	)
	(segment
		(start 198.3105 -131.699)
		(end 198.3105 -131.090416)
		(width 0.254)
		(layer "F.Cu")
		(net "PWRGD_P1V8")
	)
	(segment
		(start 198.3105 -131.090416)
		(end 198.756016 -130.6449)
		(width 0.254)
		(layer "F.Cu")
		(net "PWRGD_P1V8")
	)
	(segment
		(start 198.3105 -131.699)
		(end 199.213724 -131.699)
		(width 0.254)
		(layer "F.Cu")
		(net "PWRGD_P1V8")
	)
	(via
		(at 198.5518 -129.7686)
		(size 0.508)
		(drill 0.254)
		(layers "F.Cu" "B.Cu")
		(net "PWRGD_P1V8")
	)
	(via
		(at 211.202016 -50.578766)
		(size 0.508)
		(drill 0.254)
		(layers "F.Cu" "B.Cu")
		(net "PWRGD_P1V8")
	)
	(via
		(at 195.200016 -54.70017)
		(size 0.508)
		(drill 0.254)
		(layers "F.Cu" "B.Cu")
		(net "PWRGD_P1V8")
	)
	(via
		(at 199.263 -131.748276)
		(size 0.6604)
		(drill 0.3302)
		(layers "F.Cu" "B.Cu")
		(net "PWRGD_P1V8")
	)
	(segment
		(start 211.896452 -50.787808)
		(end 221.28226 -60.173616)
		(width 0.254)
		(layer "In2.Cu")
		(net "PWRGD_P1V8")
	)
	(segment
		(start 221.869762 -81.534762)
		(end 223.139 -82.804)
		(width 0.254)
		(layer "In2.Cu")
		(net "PWRGD_P1V8")
	)
	(segment
		(start 214.91448 -129.488692)
		(end 198.831708 -129.488692)
		(width 0.254)
		(layer "In2.Cu")
		(net "PWRGD_P1V8")
	)
	(segment
		(start 227.8634 -116.539772)
		(end 214.91448 -129.488692)
		(width 0.254)
		(layer "In2.Cu")
		(net "PWRGD_P1V8")
	)
	(segment
		(start 221.28226 -60.173616)
		(end 221.28226 -80.960722)
		(width 0.254)
		(layer "In2.Cu")
		(net "PWRGD_P1V8")
	)
	(segment
		(start 223.139 -98.636836)
		(end 227.8634 -103.361236)
		(width 0.254)
		(layer "In2.Cu")
		(net "PWRGD_P1V8")
	)
	(segment
		(start 211.411058 -50.787808)
		(end 211.896452 -50.787808)
		(width 0.254)
		(layer "In2.Cu")
		(net "PWRGD_P1V8")
	)
	(segment
		(start 198.831708 -129.488692)
		(end 198.5518 -129.7686)
		(width 0.254)
		(layer "In2.Cu")
		(net "PWRGD_P1V8")
	)
	(segment
		(start 221.28226 -80.960722)
		(end 221.8563 -81.534762)
		(width 0.254)
		(layer "In2.Cu")
		(net "PWRGD_P1V8")
	)
	(segment
		(start 211.202016 -50.578766)
		(end 211.411058 -50.787808)
		(width 0.254)
		(layer "In2.Cu")
		(net "PWRGD_P1V8")
	)
	(segment
		(start 227.8634 -103.361236)
		(end 227.8634 -116.539772)
		(width 0.254)
		(layer "In2.Cu")
		(net "PWRGD_P1V8")
	)
	(segment
		(start 221.8563 -81.534762)
		(end 221.869762 -81.534762)
		(width 0.254)
		(layer "In2.Cu")
		(net "PWRGD_P1V8")
	)
	(segment
		(start 223.139 -82.804)
		(end 223.139 -98.636836)
		(width 0.254)
		(layer "In2.Cu")
		(net "PWRGD_P1V8")
	)
	(segment
		(start 208.186528 -51.533806)
		(end 196.598794 -51.533806)
		(width 0.254)
		(layer "In5.Cu")
		(net "PWRGD_P1V8")
	)
	(segment
		(start 196.598794 -51.533806)
		(end 195.2752 -52.8574)
		(width 0.254)
		(layer "In5.Cu")
		(net "PWRGD_P1V8")
	)
	(segment
		(start 211.202016 -50.578766)
		(end 209.141568 -50.578766)
		(width 0.254)
		(layer "In5.Cu")
		(net "PWRGD_P1V8")
	)
	(segment
		(start 195.2752 -54.624986)
		(end 195.200016 -54.70017)
		(width 0.254)
		(layer "In5.Cu")
		(net "PWRGD_P1V8")
	)
	(segment
		(start 195.2752 -52.8574)
		(end 195.2752 -54.624986)
		(width 0.254)
		(layer "In5.Cu")
		(net "PWRGD_P1V8")
	)
	(segment
		(start 209.141568 -50.578766)
		(end 208.186528 -51.533806)
		(width 0.254)
		(layer "In5.Cu")
		(net "PWRGD_P1V8")
	)
	(segment
		(start 205.3336 -132.836412)
		(end 204.533246 -132.036058)
		(width 0.254)
		(layer "F.Cu")
		(net "PWRGD_P1V5")
	)
	(segment
		(start 202.346814 -138.267186)
		(end 205.3336 -135.2804)
		(width 0.254)
		(layer "F.Cu")
		(net "PWRGD_P1V5")
	)
	(segment
		(start 205.3336 -135.2804)
		(end 205.3336 -132.836412)
		(width 0.254)
		(layer "F.Cu")
		(net "PWRGD_P1V5")
	)
	(segment
		(start 204.533246 -132.036058)
		(end 205.14437 -131.424934)
		(width 0.254)
		(layer "F.Cu")
		(net "PWRGD_P1V5")
	)
	(segment
		(start 193.30797 -138.267186)
		(end 202.346814 -138.267186)
		(width 0.254)
		(layer "F.Cu")
		(net "PWRGD_P1V5")
	)
	(segment
		(start 191.71285 -136.672066)
		(end 193.30797 -138.267186)
		(width 0.254)
		(layer "F.Cu")
		(net "PWRGD_P1V5")
	)
	(segment
		(start 205.14437 -131.424934)
		(end 205.14437 -129.436622)
		(width 0.254)
		(layer "F.Cu")
		(net "PWRGD_P1V5")
	)
	(segment
		(start 190.220346 -135.179562)
		(end 191.71285 -136.672066)
		(width 0.254)
		(layer "F.Cu")
		(net "PWRGD_P1V5")
	)
	(segment
		(start 190.220346 -133.709664)
		(end 190.220346 -135.179562)
		(width 0.254)
		(layer "F.Cu")
		(net "PWRGD_P1V5")
	)
	(via
		(at 191.71285 -136.672066)
		(size 0.6604)
		(drill 0.3302)
		(layers "F.Cu" "B.Cu")
		(net "PWRGD_P1V5")
	)
	(segment
		(start 69.51599 -165.235382)
		(end 69.977 -165.696392)
		(width 0.254)
		(layer "F.Cu")
		(net "PWRGD_P1V2_STBY")
	)
	(segment
		(start 19.590766 -173.4693)
		(end 19.603466 -173.482)
		(width 0.254)
		(layer "F.Cu")
		(net "PWRGD_P1V2_STBY")
	)
	(segment
		(start 21.308822 -174.752)
		(end 21.4884 -174.752)
		(width 0.254)
		(layer "F.Cu")
		(net "PWRGD_P1V2_STBY")
	)
	(segment
		(start 19.8501 -173.482)
		(end 20.4724 -174.1043)
		(width 0.254)
		(layer "F.Cu")
		(net "PWRGD_P1V2_STBY")
	)
	(segment
		(start 69.51599 -165.10889)
		(end 69.51599 -165.235382)
		(width 0.254)
		(layer "F.Cu")
		(net "PWRGD_P1V2_STBY")
	)
	(segment
		(start 19.603466 -173.482)
		(end 19.8501 -173.482)
		(width 0.254)
		(layer "F.Cu")
		(net "PWRGD_P1V2_STBY")
	)
	(segment
		(start 16.04137 -171.600622)
		(end 16.04137 -172.58157)
		(width 0.254)
		(layer "F.Cu")
		(net "PWRGD_P1V2_STBY")
	)
	(segment
		(start 17.999456 -173.5074)
		(end 18.037556 -173.4693)
		(width 0.254)
		(layer "F.Cu")
		(net "PWRGD_P1V2_STBY")
	)
	(segment
		(start 69.1388 -164.7317)
		(end 69.51599 -165.10889)
		(width 0.254)
		(layer "F.Cu")
		(net "PWRGD_P1V2_STBY")
	)
	(segment
		(start 20.661122 -174.1043)
		(end 21.308822 -174.752)
		(width 0.254)
		(layer "F.Cu")
		(net "PWRGD_P1V2_STBY")
	)
	(segment
		(start 69.977 -165.696392)
		(end 71.021448 -165.696392)
		(width 0.254)
		(layer "F.Cu")
		(net "PWRGD_P1V2_STBY")
	)
	(segment
		(start 71.08444 -165.6334)
		(end 71.60514 -165.6334)
		(width 0.254)
		(layer "F.Cu")
		(net "PWRGD_P1V2_STBY")
	)
	(segment
		(start 16.9672 -173.5074)
		(end 17.999456 -173.5074)
		(width 0.254)
		(layer "F.Cu")
		(net "PWRGD_P1V2_STBY")
	)
	(segment
		(start 20.4724 -174.1043)
		(end 20.661122 -174.1043)
		(width 0.254)
		(layer "F.Cu")
		(net "PWRGD_P1V2_STBY")
	)
	(segment
		(start 16.04137 -172.58157)
		(end 16.9672 -173.5074)
		(width 0.254)
		(layer "F.Cu")
		(net "PWRGD_P1V2_STBY")
	)
	(segment
		(start 71.021448 -165.696392)
		(end 71.08444 -165.6334)
		(width 0.254)
		(layer "F.Cu")
		(net "PWRGD_P1V2_STBY")
	)
	(segment
		(start 18.037556 -173.4693)
		(end 19.590766 -173.4693)
		(width 0.254)
		(layer "F.Cu")
		(net "PWRGD_P1V2_STBY")
	)
	(via
		(at 69.1388 -164.7317)
		(size 0.508)
		(drill 0.254)
		(layers "F.Cu" "B.Cu")
		(net "PWRGD_P1V2_STBY")
	)
	(via
		(at 69.977 -165.696392)
		(size 0.6604)
		(drill 0.3302)
		(layers "F.Cu" "B.Cu")
		(net "PWRGD_P1V2_STBY")
	)
	(via
		(at 64.410082 -166.072566)
		(size 0.6096)
		(drill 0.3048)
		(layers "F.Cu" "B.Cu")
		(net "PWRGD_P1V2_STBY")
	)
	(via
		(at 30.607 -165.5572)
		(size 0.508)
		(drill 0.254)
		(layers "F.Cu" "B.Cu")
		(net "PWRGD_P1V2_STBY")
	)
	(via
		(at 21.4884 -174.752)
		(size 0.508)
		(drill 0.254)
		(layers "F.Cu" "B.Cu")
		(net "PWRGD_P1V2_STBY")
	)
	(segment
		(start 59.40298 -167.259)
		(end 58.842656 -166.698676)
		(width 0.254)
		(layer "B.Cu")
		(net "PWRGD_P1V2_STBY")
	)
	(segment
		(start 45.263562 -166.10076)
		(end 45.229526 -166.10076)
		(width 0.254)
		(layer "B.Cu")
		(net "PWRGD_P1V2_STBY")
	)
	(segment
		(start 31.973012 -164.191188)
		(end 30.607 -165.5572)
		(width 0.254)
		(layer "B.Cu")
		(net "PWRGD_P1V2_STBY")
	)
	(segment
		(start 49.163224 -166.6748)
		(end 48.615854 -166.12743)
		(width 0.254)
		(layer "B.Cu")
		(net "PWRGD_P1V2_STBY")
	)
	(segment
		(start 63.223648 -167.259)
		(end 59.40298 -167.259)
		(width 0.254)
		(layer "B.Cu")
		(net "PWRGD_P1V2_STBY")
	)
	(segment
		(start 54.15788 -166.6748)
		(end 49.163224 -166.6748)
		(width 0.254)
		(layer "B.Cu")
		(net "PWRGD_P1V2_STBY")
	)
	(segment
		(start 43.303444 -164.191188)
		(end 31.973012 -164.191188)
		(width 0.254)
		(layer "B.Cu")
		(net "PWRGD_P1V2_STBY")
	)
	(segment
		(start 43.303952 -164.191696)
		(end 43.303444 -164.191188)
		(width 0.254)
		(layer "B.Cu")
		(net "PWRGD_P1V2_STBY")
	)
	(segment
		(start 68.58254 -165.28796)
		(end 65.194688 -165.28796)
		(width 0.254)
		(layer "B.Cu")
		(net "PWRGD_P1V2_STBY")
	)
	(segment
		(start 45.290232 -166.12743)
		(end 45.263562 -166.10076)
		(width 0.254)
		(layer "B.Cu")
		(net "PWRGD_P1V2_STBY")
	)
	(segment
		(start 45.229526 -166.10076)
		(end 43.320462 -164.191696)
		(width 0.254)
		(layer "B.Cu")
		(net "PWRGD_P1V2_STBY")
	)
	(segment
		(start 64.410082 -166.072566)
		(end 63.223648 -167.259)
		(width 0.254)
		(layer "B.Cu")
		(net "PWRGD_P1V2_STBY")
	)
	(segment
		(start 43.320462 -164.191696)
		(end 43.303952 -164.191696)
		(width 0.254)
		(layer "B.Cu")
		(net "PWRGD_P1V2_STBY")
	)
	(segment
		(start 54.181756 -166.698676)
		(end 54.15788 -166.6748)
		(width 0.254)
		(layer "B.Cu")
		(net "PWRGD_P1V2_STBY")
	)
	(segment
		(start 65.194688 -165.28796)
		(end 64.410082 -166.072566)
		(width 0.254)
		(layer "B.Cu")
		(net "PWRGD_P1V2_STBY")
	)
	(segment
		(start 69.1388 -164.7317)
		(end 68.58254 -165.28796)
		(width 0.254)
		(layer "B.Cu")
		(net "PWRGD_P1V2_STBY")
	)
	(segment
		(start 48.615854 -166.12743)
		(end 45.290232 -166.12743)
		(width 0.254)
		(layer "B.Cu")
		(net "PWRGD_P1V2_STBY")
	)
	(segment
		(start 58.842656 -166.698676)
		(end 54.181756 -166.698676)
		(width 0.254)
		(layer "B.Cu")
		(net "PWRGD_P1V2_STBY")
	)
	(segment
		(start 28.8798 -165.5572)
		(end 21.4884 -172.9486)
		(width 0.254)
		(layer "In5.Cu")
		(net "PWRGD_P1V2_STBY")
	)
	(segment
		(start 30.607 -165.5572)
		(end 28.8798 -165.5572)
		(width 0.254)
		(layer "In5.Cu")
		(net "PWRGD_P1V2_STBY")
	)
	(segment
		(start 21.4884 -172.9486)
		(end 21.4884 -174.752)
		(width 0.254)
		(layer "In5.Cu")
		(net "PWRGD_P1V2_STBY")
	)
	(segment
		(start 194.5386 -48.7426)
		(end 194.5386 -49.973738)
		(width 0.254)
		(layer "F.Cu")
		(net "PWRGD_P0V975")
	)
	(segment
		(start 194.799966 -53.50002)
		(end 194.799966 -52.106322)
		(width 0.254)
		(layer "F.Cu")
		(net "PWRGD_P0V975")
	)
	(segment
		(start 194.799966 -52.106322)
		(end 194.5132 -51.819556)
		(width 0.254)
		(layer "F.Cu")
		(net "PWRGD_P0V975")
	)
	(segment
		(start 175.477424 -117.032024)
		(end 176.917858 -117.032024)
		(width 0.254)
		(layer "F.Cu")
		(net "PWRGD_P0V975")
	)
	(segment
		(start 194.5386 -49.973738)
		(end 194.5132 -49.999138)
		(width 0.254)
		(layer "F.Cu")
		(net "PWRGD_P0V975")
	)
	(segment
		(start 194.5132 -51.819556)
		(end 194.5132 -49.999138)
		(width 0.254)
		(layer "F.Cu")
		(net "PWRGD_P0V975")
	)
	(segment
		(start 177.851054 -117.96522)
		(end 176.917858 -117.032024)
		(width 0.254)
		(layer "F.Cu")
		(net "PWRGD_P0V975")
	)
	(segment
		(start 178.517296 -117.96522)
		(end 177.851054 -117.96522)
		(width 0.254)
		(layer "F.Cu")
		(net "PWRGD_P0V975")
	)
	(segment
		(start 175.3362 -116.8908)
		(end 175.477424 -117.032024)
		(width 0.254)
		(layer "F.Cu")
		(net "PWRGD_P0V975")
	)
	(via
		(at 175.3362 -116.8908)
		(size 0.508)
		(drill 0.254)
		(layers "F.Cu" "B.Cu")
		(net "PWRGD_P0V975")
	)
	(via
		(at 194.5132 -49.999138)
		(size 0.6604)
		(drill 0.3302)
		(layers "F.Cu" "B.Cu")
		(net "PWRGD_P0V975")
	)
	(via
		(at 157.52064 -51.689)
		(size 0.508)
		(drill 0.254)
		(layers "F.Cu" "B.Cu")
		(net "PWRGD_P0V975")
	)
	(via
		(at 154.083004 -90.099642)
		(size 0.508)
		(drill 0.254)
		(layers "F.Cu" "B.Cu")
		(net "PWRGD_P0V975")
	)
	(via
		(at 194.5386 -48.7426)
		(size 0.508)
		(drill 0.254)
		(layers "F.Cu" "B.Cu")
		(net "PWRGD_P0V975")
	)
	(via
		(at 162.805872 -94.08795)
		(size 0.508)
		(drill 0.254)
		(layers "F.Cu" "B.Cu")
		(net "PWRGD_P0V975")
	)
	(segment
		(start 152.781 -90.4748)
		(end 152.781 -91.2241)
		(width 0.254)
		(layer "B.Cu")
		(net "PWRGD_P0V975")
	)
	(segment
		(start 154.083004 -90.099642)
		(end 154.063446 -90.1192)
		(width 0.254)
		(layer "B.Cu")
		(net "PWRGD_P0V975")
	)
	(segment
		(start 154.063446 -90.1192)
		(end 153.1366 -90.1192)
		(width 0.254)
		(layer "B.Cu")
		(net "PWRGD_P0V975")
	)
	(segment
		(start 153.1366 -90.1192)
		(end 152.781 -90.4748)
		(width 0.254)
		(layer "B.Cu")
		(net "PWRGD_P0V975")
	)
	(segment
		(start 157.52064 -53.732684)
		(end 157.52064 -51.689)
		(width 0.254)
		(layer "In2.Cu")
		(net "PWRGD_P0V975")
	)
	(segment
		(start 174.879 -115.51158)
		(end 174.879 -116.4336)
		(width 0.254)
		(layer "In2.Cu")
		(net "PWRGD_P0V975")
	)
	(segment
		(start 166.371524 -100.2792)
		(end 168.518586 -100.2792)
		(width 0.254)
		(layer "In2.Cu")
		(net "PWRGD_P0V975")
	)
	(segment
		(start 162.805872 -95.0468)
		(end 162.69208 -95.160592)
		(width 0.254)
		(layer "In2.Cu")
		(net "PWRGD_P0V975")
	)
	(segment
		(start 163.66998 -97.281746)
		(end 163.66998 -97.577656)
		(width 0.254)
		(layer "In2.Cu")
		(net "PWRGD_P0V975")
	)
	(segment
		(start 174.879 -116.4336)
		(end 175.3362 -116.8908)
		(width 0.254)
		(layer "In2.Cu")
		(net "PWRGD_P0V975")
	)
	(segment
		(start 155.448 -55.805324)
		(end 157.52064 -53.732684)
		(width 0.254)
		(layer "In2.Cu")
		(net "PWRGD_P0V975")
	)
	(segment
		(start 162.805872 -94.08795)
		(end 162.805872 -95.0468)
		(width 0.254)
		(layer "In2.Cu")
		(net "PWRGD_P0V975")
	)
	(segment
		(start 174.8663 -106.626914)
		(end 174.8663 -115.49888)
		(width 0.254)
		(layer "In2.Cu")
		(net "PWRGD_P0V975")
	)
	(segment
		(start 168.518586 -100.2792)
		(end 174.8663 -106.626914)
		(width 0.254)
		(layer "In2.Cu")
		(net "PWRGD_P0V975")
	)
	(segment
		(start 174.8663 -115.49888)
		(end 174.879 -115.51158)
		(width 0.254)
		(layer "In2.Cu")
		(net "PWRGD_P0V975")
	)
	(segment
		(start 162.805872 -91.406726)
		(end 161.061654 -89.662508)
		(width 0.254)
		(layer "In2.Cu")
		(net "PWRGD_P0V975")
	)
	(segment
		(start 161.061654 -89.662508)
		(end 161.061654 -82.398362)
		(width 0.254)
		(layer "In2.Cu")
		(net "PWRGD_P0V975")
	)
	(segment
		(start 161.061654 -82.398362)
		(end 155.448 -76.784708)
		(width 0.254)
		(layer "In2.Cu")
		(net "PWRGD_P0V975")
	)
	(segment
		(start 163.66998 -97.577656)
		(end 166.371524 -100.2792)
		(width 0.254)
		(layer "In2.Cu")
		(net "PWRGD_P0V975")
	)
	(segment
		(start 162.69208 -96.303846)
		(end 163.66998 -97.281746)
		(width 0.254)
		(layer "In2.Cu")
		(net "PWRGD_P0V975")
	)
	(segment
		(start 162.805872 -94.08795)
		(end 162.805872 -91.406726)
		(width 0.254)
		(layer "In2.Cu")
		(net "PWRGD_P0V975")
	)
	(segment
		(start 155.448 -76.784708)
		(end 155.448 -55.805324)
		(width 0.254)
		(layer "In2.Cu")
		(net "PWRGD_P0V975")
	)
	(segment
		(start 162.69208 -95.160592)
		(end 162.69208 -96.303846)
		(width 0.254)
		(layer "In2.Cu")
		(net "PWRGD_P0V975")
	)
	(segment
		(start 158.14294 -51.689)
		(end 160.68294 -49.149)
		(width 0.254)
		(layer "In5.Cu")
		(net "PWRGD_P0V975")
	)
	(segment
		(start 168.318688 -49.149)
		(end 174.452788 -43.0149)
		(width 0.254)
		(layer "In5.Cu")
		(net "PWRGD_P0V975")
	)
	(segment
		(start 174.452788 -43.0149)
		(end 192.9257 -43.0149)
		(width 0.254)
		(layer "In5.Cu")
		(net "PWRGD_P0V975")
	)
	(segment
		(start 162.805872 -94.08795)
		(end 160.183322 -91.4654)
		(width 0.254)
		(layer "In5.Cu")
		(net "PWRGD_P0V975")
	)
	(segment
		(start 155.448762 -91.4654)
		(end 154.083004 -90.099642)
		(width 0.254)
		(layer "In5.Cu")
		(net "PWRGD_P0V975")
	)
	(segment
		(start 157.52064 -51.689)
		(end 158.14294 -51.689)
		(width 0.254)
		(layer "In5.Cu")
		(net "PWRGD_P0V975")
	)
	(segment
		(start 192.9257 -43.0149)
		(end 194.5386 -44.6278)
		(width 0.254)
		(layer "In5.Cu")
		(net "PWRGD_P0V975")
	)
	(segment
		(start 160.183322 -91.4654)
		(end 155.448762 -91.4654)
		(width 0.254)
		(layer "In5.Cu")
		(net "PWRGD_P0V975")
	)
	(segment
		(start 194.5386 -44.6278)
		(end 194.5386 -48.7426)
		(width 0.254)
		(layer "In5.Cu")
		(net "PWRGD_P0V975")
	)
	(segment
		(start 160.68294 -49.149)
		(end 168.318688 -49.149)
		(width 0.254)
		(layer "In5.Cu")
		(net "PWRGD_P0V975")
	)
	(segment
		(start 175.387 -118.6942)
		(end 175.387 -119.255286)
		(width 0.127)
		(layer "F.Cu")
		(net "PQ4_G")
	)
	(segment
		(start 176.9618 -119.3419)
		(end 176.9618 -118.255542)
		(width 0.127)
		(layer "F.Cu")
		(net "PQ4_G")
	)
	(segment
		(start 176.9618 -118.255542)
		(end 176.911 -118.204742)
		(width 0.127)
		(layer "F.Cu")
		(net "PQ4_G")
	)
	(segment
		(start 175.876458 -118.204742)
		(end 175.387 -118.6942)
		(width 0.127)
		(layer "F.Cu")
		(net "PQ4_G")
	)
	(segment
		(start 176.911 -118.204742)
		(end 175.876458 -118.204742)
		(width 0.127)
		(layer "F.Cu")
		(net "PQ4_G")
	)
	(via
		(at 176.911 -118.204742)
		(size 0.6604)
		(drill 0.3302)
		(layers "F.Cu" "B.Cu")
		(net "PQ4_G")
	)
	(segment
		(start 94.999556 -47.331376)
		(end 93.338904 -45.670724)
		(width 0.127)
		(layer "F.Cu")
		(net "PQ2_G")
	)
	(segment
		(start 94.153228 -48.977296)
		(end 94.153228 -48.80737)
		(width 0.127)
		(layer "F.Cu")
		(net "PQ2_G")
	)
	(segment
		(start 94.153228 -48.80737)
		(end 94.999556 -47.961042)
		(width 0.127)
		(layer "F.Cu")
		(net "PQ2_G")
	)
	(segment
		(start 94.999556 -47.961042)
		(end 94.999556 -47.331376)
		(width 0.127)
		(layer "F.Cu")
		(net "PQ2_G")
	)
	(via
		(at 94.999556 -47.961042)
		(size 0.6604)
		(drill 0.3302)
		(layers "F.Cu" "B.Cu")
		(net "PQ2_G")
	)
	(segment
		(start 205.364588 -67.124072)
		(end 204.424026 -67.124072)
		(width 0.12446)
		(layer "F.Cu")
		(net "PHY_IOC_TO_CON_B_3_DP_C")
	)
	(segment
		(start 206.087472 -66.401188)
		(end 205.364588 -67.124072)
		(width 0.12446)
		(layer "F.Cu")
		(net "PHY_IOC_TO_CON_B_3_DP_C")
	)
	(segment
		(start 204.424026 -67.124072)
		(end 204.399896 -67.099942)
		(width 0.12446)
		(layer "F.Cu")
		(net "PHY_IOC_TO_CON_B_3_DP_C")
	)
	(segment
		(start 206.087472 -65.551558)
		(end 206.087472 -66.401188)
		(width 0.12446)
		(layer "F.Cu")
		(net "PHY_IOC_TO_CON_B_3_DP_C")
	)
	(segment
		(start 207.70215 -64.898778)
		(end 206.740252 -64.898778)
		(width 0.12446)
		(layer "F.Cu")
		(net "PHY_IOC_TO_CON_B_3_DP_C")
	)
	(segment
		(start 206.740252 -64.898778)
		(end 206.087472 -65.551558)
		(width 0.12446)
		(layer "F.Cu")
		(net "PHY_IOC_TO_CON_B_3_DP_C")
	)
	(segment
		(start 207.776572 -64.9732)
		(end 207.70215 -64.898778)
		(width 0.12446)
		(layer "F.Cu")
		(net "PHY_IOC_TO_CON_B_3_DP_C")
	)
	(segment
		(start 209.165444 -64.89319)
		(end 209.957416 -64.101472)
		(width 0.12446)
		(layer "F.Cu")
		(net "PHY_IOC_TO_CON_B_3_DP")
	)
	(segment
		(start 208.335372 -64.9732)
		(end 208.415382 -64.89319)
		(width 0.12446)
		(layer "F.Cu")
		(net "PHY_IOC_TO_CON_B_3_DP")
	)
	(segment
		(start 211.231226 -63.753492)
		(end 211.06003 -63.924688)
		(width 0.12446)
		(layer "F.Cu")
		(net "PHY_IOC_TO_CON_B_3_DP")
	)
	(segment
		(start 209.957416 -64.101472)
		(end 209.957416 -63.768986)
		(width 0.12446)
		(layer "F.Cu")
		(net "PHY_IOC_TO_CON_B_3_DP")
	)
	(segment
		(start 208.415382 -64.89319)
		(end 209.165444 -64.89319)
		(width 0.12446)
		(layer "F.Cu")
		(net "PHY_IOC_TO_CON_B_3_DP")
	)
	(segment
		(start 210.494118 -63.232284)
		(end 210.888072 -63.232284)
		(width 0.12446)
		(layer "F.Cu")
		(net "PHY_IOC_TO_CON_B_3_DP")
	)
	(segment
		(start 210.888072 -63.232284)
		(end 211.231226 -63.575438)
		(width 0.12446)
		(layer "F.Cu")
		(net "PHY_IOC_TO_CON_B_3_DP")
	)
	(segment
		(start 209.957416 -63.768986)
		(end 210.494118 -63.232284)
		(width 0.12446)
		(layer "F.Cu")
		(net "PHY_IOC_TO_CON_B_3_DP")
	)
	(arc
		(start 211.231226 -63.575438)
		(mid 211.268229 -63.664502)
		(end 211.231226 -63.753492)
		(width 0.12446)
		(layer "F.Cu")
		(net "PHY_IOC_TO_CON_B_3_DP")
	)
	(segment
		(start 187.666884 -39.572184)
		(end 187.890912 -39.422578)
		(width 0.1016)
		(layer "In5.Cu")
		(net "PHY_IOC_TO_CON_B_3_DP")
	)
	(segment
		(start 213.730332 -53.40985)
		(end 212.131656 -61.401452)
		(width 0.1016)
		(layer "In5.Cu")
		(net "PHY_IOC_TO_CON_B_3_DP")
	)
	(segment
		(start 167.803322 -35.416236)
		(end 168.10228 -35.475926)
		(width 0.1016)
		(layer "In5.Cu")
		(net "PHY_IOC_TO_CON_B_3_DP")
	)
	(segment
		(start 166.607744 -35.37204)
		(end 166.831772 -35.222688)
		(width 0.1016)
		(layer "In5.Cu")
		(net "PHY_IOC_TO_CON_B_3_DP")
	)
	(segment
		(start 186.695334 -39.378382)
		(end 186.919616 -39.228776)
		(width 0.1016)
		(layer "In5.Cu")
		(net "PHY_IOC_TO_CON_B_3_DP")
	)
	(segment
		(start 203.116434 -42.653458)
		(end 203.415392 -42.713148)
		(width 0.1016)
		(layer "In5.Cu")
		(net "PHY_IOC_TO_CON_B_3_DP")
	)
	(segment
		(start 186.247024 -39.094664)
		(end 186.39663 -39.318692)
		(width 0.1016)
		(layer "In5.Cu")
		(net "PHY_IOC_TO_CON_B_3_DP")
	)
	(segment
		(start 205.58252 -42.951146)
		(end 206.681578 -43.170348)
		(width 0.1016)
		(layer "In5.Cu")
		(net "PHY_IOC_TO_CON_B_3_DP")
	)
	(segment
		(start 186.39663 -39.318692)
		(end 186.695334 -39.378382)
		(width 0.1016)
		(layer "In5.Cu")
		(net "PHY_IOC_TO_CON_B_3_DP")
	)
	(segment
		(start 159.88919 -30.205934)
		(end 159.88919 -30.697424)
		(width 0.1016)
		(layer "In5.Cu")
		(net "PHY_IOC_TO_CON_B_3_DP")
	)
	(segment
		(start 204.909928 -42.817034)
		(end 205.05928 -43.041062)
		(width 0.1016)
		(layer "In5.Cu")
		(net "PHY_IOC_TO_CON_B_3_DP")
	)
	(segment
		(start 211.497164 -46.380654)
		(end 212.680296 -48.154844)
		(width 0.1016)
		(layer "In5.Cu")
		(net "PHY_IOC_TO_CON_B_3_DP")
	)
	(segment
		(start 205.05928 -43.041062)
		(end 205.358238 -43.100752)
		(width 0.1016)
		(layer "In5.Cu")
		(net "PHY_IOC_TO_CON_B_3_DP")
	)
	(segment
		(start 205.358238 -43.100752)
		(end 205.58252 -42.951146)
		(width 0.1016)
		(layer "In5.Cu")
		(net "PHY_IOC_TO_CON_B_3_DP")
	)
	(segment
		(start 187.890912 -39.422578)
		(end 202.966828 -42.42943)
		(width 0.1016)
		(layer "In5.Cu")
		(net "PHY_IOC_TO_CON_B_3_DP")
	)
	(segment
		(start 167.579294 -35.565842)
		(end 167.803322 -35.416236)
		(width 0.1016)
		(layer "In5.Cu")
		(net "PHY_IOC_TO_CON_B_3_DP")
	)
	(segment
		(start 187.367926 -39.512494)
		(end 187.666884 -39.572184)
		(width 0.1016)
		(layer "In5.Cu")
		(net "PHY_IOC_TO_CON_B_3_DP")
	)
	(segment
		(start 187.21832 -39.288466)
		(end 187.367926 -39.512494)
		(width 0.1016)
		(layer "In5.Cu")
		(net "PHY_IOC_TO_CON_B_3_DP")
	)
	(segment
		(start 159.505142 -30.023816)
		(end 159.642556 -29.982414)
		(width 0.1016)
		(layer "In5.Cu")
		(net "PHY_IOC_TO_CON_B_3_DP")
	)
	(segment
		(start 185.948066 -39.034974)
		(end 186.247024 -39.094664)
		(width 0.1016)
		(layer "In5.Cu")
		(net "PHY_IOC_TO_CON_B_3_DP")
	)
	(segment
		(start 203.415392 -42.713148)
		(end 203.63942 -42.563542)
		(width 0.1016)
		(layer "In5.Cu")
		(net "PHY_IOC_TO_CON_B_3_DP")
	)
	(segment
		(start 160.88995 -32.237934)
		(end 164.888926 -34.835084)
		(width 0.1016)
		(layer "In5.Cu")
		(net "PHY_IOC_TO_CON_B_3_DP")
	)
	(segment
		(start 203.63942 -42.563542)
		(end 203.938378 -42.623232)
		(width 0.1016)
		(layer "In5.Cu")
		(net "PHY_IOC_TO_CON_B_3_DP")
	)
	(segment
		(start 159.642556 -29.982414)
		(end 159.69234 -30.009338)
		(width 0.1016)
		(layer "In5.Cu")
		(net "PHY_IOC_TO_CON_B_3_DP")
	)
	(segment
		(start 185.42508 -39.12489)
		(end 185.724038 -39.18458)
		(width 0.1016)
		(layer "In5.Cu")
		(net "PHY_IOC_TO_CON_B_3_DP")
	)
	(segment
		(start 204.61097 -42.757344)
		(end 204.909928 -42.817034)
		(width 0.1016)
		(layer "In5.Cu")
		(net "PHY_IOC_TO_CON_B_3_DP")
	)
	(segment
		(start 211.223098 -63.76162)
		(end 211.06003 -63.924688)
		(width 0.1016)
		(layer "In5.Cu")
		(net "PHY_IOC_TO_CON_B_3_DP")
	)
	(segment
		(start 168.10228 -35.475926)
		(end 168.251886 -35.699954)
		(width 0.1016)
		(layer "In5.Cu")
		(net "PHY_IOC_TO_CON_B_3_DP")
	)
	(segment
		(start 206.681578 -43.170348)
		(end 211.497164 -46.380654)
		(width 0.1016)
		(layer "In5.Cu")
		(net "PHY_IOC_TO_CON_B_3_DP")
	)
	(segment
		(start 202.966828 -42.42943)
		(end 203.116434 -42.653458)
		(width 0.1016)
		(layer "In5.Cu")
		(net "PHY_IOC_TO_CON_B_3_DP")
	)
	(segment
		(start 167.13073 -35.282124)
		(end 167.280336 -35.506152)
		(width 0.1016)
		(layer "In5.Cu")
		(net "PHY_IOC_TO_CON_B_3_DP")
	)
	(segment
		(start 203.938378 -42.623232)
		(end 204.087984 -42.84726)
		(width 0.1016)
		(layer "In5.Cu")
		(net "PHY_IOC_TO_CON_B_3_DP")
	)
	(segment
		(start 159.69234 -30.009338)
		(end 159.88919 -30.205934)
		(width 0.1016)
		(layer "In5.Cu")
		(net "PHY_IOC_TO_CON_B_3_DP")
	)
	(segment
		(start 204.386942 -42.90695)
		(end 204.61097 -42.757344)
		(width 0.1016)
		(layer "In5.Cu")
		(net "PHY_IOC_TO_CON_B_3_DP")
	)
	(segment
		(start 204.087984 -42.84726)
		(end 204.386942 -42.90695)
		(width 0.1016)
		(layer "In5.Cu")
		(net "PHY_IOC_TO_CON_B_3_DP")
	)
	(segment
		(start 212.131656 -61.401452)
		(end 210.947 -62.586108)
		(width 0.1016)
		(layer "In5.Cu")
		(net "PHY_IOC_TO_CON_B_3_DP")
	)
	(segment
		(start 166.831772 -35.222688)
		(end 167.13073 -35.282124)
		(width 0.1016)
		(layer "In5.Cu")
		(net "PHY_IOC_TO_CON_B_3_DP")
	)
	(segment
		(start 185.275474 -38.900862)
		(end 185.42508 -39.12489)
		(width 0.1016)
		(layer "In5.Cu")
		(net "PHY_IOC_TO_CON_B_3_DP")
	)
	(segment
		(start 159.88919 -30.697424)
		(end 160.88995 -32.237934)
		(width 0.1016)
		(layer "In5.Cu")
		(net "PHY_IOC_TO_CON_B_3_DP")
	)
	(segment
		(start 168.550844 -35.759644)
		(end 168.774872 -35.610038)
		(width 0.1016)
		(layer "In5.Cu")
		(net "PHY_IOC_TO_CON_B_3_DP")
	)
	(segment
		(start 166.308786 -35.312604)
		(end 166.607744 -35.37204)
		(width 0.1016)
		(layer "In5.Cu")
		(net "PHY_IOC_TO_CON_B_3_DP")
	)
	(segment
		(start 168.774872 -35.610038)
		(end 185.275474 -38.900862)
		(width 0.1016)
		(layer "In5.Cu")
		(net "PHY_IOC_TO_CON_B_3_DP")
	)
	(segment
		(start 167.280336 -35.506152)
		(end 167.579294 -35.565842)
		(width 0.1016)
		(layer "In5.Cu")
		(net "PHY_IOC_TO_CON_B_3_DP")
	)
	(segment
		(start 164.888926 -34.835084)
		(end 164.88918 -34.835084)
		(width 0.1016)
		(layer "In5.Cu")
		(net "PHY_IOC_TO_CON_B_3_DP")
	)
	(segment
		(start 164.88918 -34.835084)
		(end 166.159434 -35.088322)
		(width 0.1016)
		(layer "In5.Cu")
		(net "PHY_IOC_TO_CON_B_3_DP")
	)
	(segment
		(start 186.919616 -39.228776)
		(end 187.21832 -39.288466)
		(width 0.1016)
		(layer "In5.Cu")
		(net "PHY_IOC_TO_CON_B_3_DP")
	)
	(segment
		(start 185.724038 -39.18458)
		(end 185.948066 -39.034974)
		(width 0.1016)
		(layer "In5.Cu")
		(net "PHY_IOC_TO_CON_B_3_DP")
	)
	(segment
		(start 166.159434 -35.088322)
		(end 166.308786 -35.312604)
		(width 0.1016)
		(layer "In5.Cu")
		(net "PHY_IOC_TO_CON_B_3_DP")
	)
	(segment
		(start 210.947 -63.219076)
		(end 211.223352 -63.495428)
		(width 0.1016)
		(layer "In5.Cu")
		(net "PHY_IOC_TO_CON_B_3_DP")
	)
	(segment
		(start 168.251886 -35.699954)
		(end 168.550844 -35.759644)
		(width 0.1016)
		(layer "In5.Cu")
		(net "PHY_IOC_TO_CON_B_3_DP")
	)
	(segment
		(start 211.223352 -63.495428)
		(end 211.223098 -63.495428)
		(width 0.1016)
		(layer "In5.Cu")
		(net "PHY_IOC_TO_CON_B_3_DP")
	)
	(segment
		(start 159.250126 -30.500066)
		(end 159.505142 -30.023816)
		(width 0.1016)
		(layer "In5.Cu")
		(net "PHY_IOC_TO_CON_B_3_DP")
	)
	(segment
		(start 212.680296 -48.154844)
		(end 213.730332 -53.40985)
		(width 0.1016)
		(layer "In5.Cu")
		(net "PHY_IOC_TO_CON_B_3_DP")
	)
	(segment
		(start 210.947 -62.586108)
		(end 210.947 -63.219076)
		(width 0.1016)
		(layer "In5.Cu")
		(net "PHY_IOC_TO_CON_B_3_DP")
	)
	(arc
		(start 211.223098 -63.495428)
		(mid 211.278228 -63.628524)
		(end 211.223098 -63.76162)
		(width 0.1016)
		(layer "In5.Cu")
		(net "PHY_IOC_TO_CON_B_3_DP")
	)
	(segment
		(start 203.60005 -67.099942)
		(end 204.05852 -66.641472)
		(width 0.12446)
		(layer "F.Cu")
		(net "PHY_IOC_TO_CON_B_3_DN_C")
	)
	(segment
		(start 205.681072 -66.232786)
		(end 205.681072 -65.383156)
		(width 0.12446)
		(layer "F.Cu")
		(net "PHY_IOC_TO_CON_B_3_DN_C")
	)
	(segment
		(start 206.57185 -64.492378)
		(end 207.698594 -64.492378)
		(width 0.12446)
		(layer "F.Cu")
		(net "PHY_IOC_TO_CON_B_3_DN_C")
	)
	(segment
		(start 204.617828 -66.717672)
		(end 205.196186 -66.717672)
		(width 0.12446)
		(layer "F.Cu")
		(net "PHY_IOC_TO_CON_B_3_DN_C")
	)
	(segment
		(start 205.196186 -66.717672)
		(end 205.681072 -66.232786)
		(width 0.12446)
		(layer "F.Cu")
		(net "PHY_IOC_TO_CON_B_3_DN_C")
	)
	(segment
		(start 204.05852 -66.641472)
		(end 204.541628 -66.641472)
		(width 0.12446)
		(layer "F.Cu")
		(net "PHY_IOC_TO_CON_B_3_DN_C")
	)
	(segment
		(start 207.698594 -64.492378)
		(end 207.776572 -64.4144)
		(width 0.12446)
		(layer "F.Cu")
		(net "PHY_IOC_TO_CON_B_3_DN_C")
	)
	(segment
		(start 204.541628 -66.641472)
		(end 204.617828 -66.717672)
		(width 0.12446)
		(layer "F.Cu")
		(net "PHY_IOC_TO_CON_B_3_DN_C")
	)
	(segment
		(start 205.681072 -65.383156)
		(end 206.57185 -64.492378)
		(width 0.12446)
		(layer "F.Cu")
		(net "PHY_IOC_TO_CON_B_3_DN_C")
	)
	(segment
		(start 211.868258 -63.11646)
		(end 211.696554 -63.288164)
		(width 0.12446)
		(layer "F.Cu")
		(net "PHY_IOC_TO_CON_B_3_DN")
	)
	(segment
		(start 208.407762 -64.48679)
		(end 208.335372 -64.4144)
		(width 0.12446)
		(layer "F.Cu")
		(net "PHY_IOC_TO_CON_B_3_DN")
	)
	(segment
		(start 208.997042 -64.48679)
		(end 208.407762 -64.48679)
		(width 0.12446)
		(layer "F.Cu")
		(net "PHY_IOC_TO_CON_B_3_DN")
	)
	(segment
		(start 211.518754 -63.288164)
		(end 211.056474 -62.825884)
		(width 0.12446)
		(layer "F.Cu")
		(net "PHY_IOC_TO_CON_B_3_DN")
	)
	(segment
		(start 209.551016 -63.600584)
		(end 209.551016 -63.932816)
		(width 0.12446)
		(layer "F.Cu")
		(net "PHY_IOC_TO_CON_B_3_DN")
	)
	(segment
		(start 210.325716 -62.825884)
		(end 209.551016 -63.600584)
		(width 0.12446)
		(layer "F.Cu")
		(net "PHY_IOC_TO_CON_B_3_DN")
	)
	(segment
		(start 209.551016 -63.932816)
		(end 208.997042 -64.48679)
		(width 0.12446)
		(layer "F.Cu")
		(net "PHY_IOC_TO_CON_B_3_DN")
	)
	(segment
		(start 211.056474 -62.825884)
		(end 210.325716 -62.825884)
		(width 0.12446)
		(layer "F.Cu")
		(net "PHY_IOC_TO_CON_B_3_DN")
	)
	(arc
		(start 211.696554 -63.288164)
		(mid 211.607654 -63.324988)
		(end 211.518754 -63.288164)
		(width 0.12446)
		(layer "F.Cu")
		(net "PHY_IOC_TO_CON_B_3_DN")
	)
	(segment
		(start 159.999934 -29.100018)
		(end 159.744664 -29.576268)
		(width 0.1016)
		(layer "In5.Cu")
		(net "PHY_IOC_TO_CON_B_3_DN")
	)
	(segment
		(start 211.2518 -62.7126)
		(end 211.2518 -63.092584)
		(width 0.1016)
		(layer "In5.Cu")
		(net "PHY_IOC_TO_CON_B_3_DN")
	)
	(segment
		(start 211.717128 -46.16069)
		(end 212.96757 -48.035972)
		(width 0.1016)
		(layer "In5.Cu")
		(net "PHY_IOC_TO_CON_B_3_DN")
	)
	(segment
		(start 159.786574 -29.713682)
		(end 159.876236 -29.761688)
		(width 0.1016)
		(layer "In5.Cu")
		(net "PHY_IOC_TO_CON_B_3_DN")
	)
	(segment
		(start 161.110422 -32.017462)
		(end 165.00602 -34.547302)
		(width 0.1016)
		(layer "In5.Cu")
		(net "PHY_IOC_TO_CON_B_3_DN")
	)
	(segment
		(start 212.96757 -48.035972)
		(end 214.041228 -53.40985)
		(width 0.1016)
		(layer "In5.Cu")
		(net "PHY_IOC_TO_CON_B_3_DN")
	)
	(segment
		(start 159.876236 -29.761688)
		(end 160.19399 -30.079442)
		(width 0.1016)
		(layer "In5.Cu")
		(net "PHY_IOC_TO_CON_B_3_DN")
	)
	(segment
		(start 211.704936 -63.279782)
		(end 211.868258 -63.11646)
		(width 0.1016)
		(layer "In5.Cu")
		(net "PHY_IOC_TO_CON_B_3_DN")
	)
	(segment
		(start 160.19399 -30.079442)
		(end 160.19399 -30.607)
		(width 0.1016)
		(layer "In5.Cu")
		(net "PHY_IOC_TO_CON_B_3_DN")
	)
	(segment
		(start 160.19399 -30.607)
		(end 161.110422 -32.017462)
		(width 0.1016)
		(layer "In5.Cu")
		(net "PHY_IOC_TO_CON_B_3_DN")
	)
	(segment
		(start 165.00602 -34.547302)
		(end 206.80045 -42.883074)
		(width 0.1016)
		(layer "In5.Cu")
		(net "PHY_IOC_TO_CON_B_3_DN")
	)
	(segment
		(start 214.041228 -53.40985)
		(end 212.41258 -61.55182)
		(width 0.1016)
		(layer "In5.Cu")
		(net "PHY_IOC_TO_CON_B_3_DN")
	)
	(segment
		(start 211.2518 -63.092584)
		(end 211.438998 -63.279782)
		(width 0.1016)
		(layer "In5.Cu")
		(net "PHY_IOC_TO_CON_B_3_DN")
	)
	(segment
		(start 212.41258 -61.55182)
		(end 211.2518 -62.7126)
		(width 0.1016)
		(layer "In5.Cu")
		(net "PHY_IOC_TO_CON_B_3_DN")
	)
	(segment
		(start 206.80045 -42.883074)
		(end 211.717128 -46.16069)
		(width 0.1016)
		(layer "In5.Cu")
		(net "PHY_IOC_TO_CON_B_3_DN")
	)
	(segment
		(start 159.744664 -29.576268)
		(end 159.786574 -29.713682)
		(width 0.1016)
		(layer "In5.Cu")
		(net "PHY_IOC_TO_CON_B_3_DN")
	)
	(arc
		(start 211.438998 -63.279782)
		(mid 211.572004 -63.334912)
		(end 211.704936 -63.279782)
		(width 0.1016)
		(layer "In5.Cu")
		(net "PHY_IOC_TO_CON_B_3_DN")
	)
	(segment
		(start 207.776572 -66.6496)
		(end 207.701896 -66.574924)
		(width 0.12446)
		(layer "F.Cu")
		(net "PHY_IOC_TO_CON_B_2_DP_C")
	)
	(segment
		(start 207.701896 -66.574924)
		(end 206.97571 -66.574924)
		(width 0.12446)
		(layer "F.Cu")
		(net "PHY_IOC_TO_CON_B_2_DP_C")
	)
	(segment
		(start 205.650846 -67.899788)
		(end 204.40015 -67.899788)
		(width 0.12446)
		(layer "F.Cu")
		(net "PHY_IOC_TO_CON_B_2_DP_C")
	)
	(segment
		(start 204.40015 -67.899788)
		(end 204.399896 -67.900042)
		(width 0.12446)
		(layer "F.Cu")
		(net "PHY_IOC_TO_CON_B_2_DP_C")
	)
	(segment
		(start 206.97571 -66.574924)
		(end 205.650846 -67.899788)
		(width 0.12446)
		(layer "F.Cu")
		(net "PHY_IOC_TO_CON_B_2_DP_C")
	)
	(segment
		(start 208.42605 -66.558922)
		(end 208.335372 -66.6496)
		(width 0.12446)
		(layer "F.Cu")
		(net "PHY_IOC_TO_CON_B_2_DP")
	)
	(segment
		(start 211.056728 -65.67551)
		(end 210.42249 -65.67551)
		(width 0.12446)
		(layer "F.Cu")
		(net "PHY_IOC_TO_CON_B_2_DP")
	)
	(segment
		(start 211.228686 -66.367914)
		(end 211.399882 -66.196718)
		(width 0.12446)
		(layer "F.Cu")
		(net "PHY_IOC_TO_CON_B_2_DP")
	)
	(segment
		(start 210.42249 -65.67551)
		(end 209.539078 -66.558922)
		(width 0.12446)
		(layer "F.Cu")
		(net "PHY_IOC_TO_CON_B_2_DP")
	)
	(segment
		(start 211.399882 -66.018664)
		(end 211.056728 -65.67551)
		(width 0.12446)
		(layer "F.Cu")
		(net "PHY_IOC_TO_CON_B_2_DP")
	)
	(segment
		(start 209.539078 -66.558922)
		(end 208.42605 -66.558922)
		(width 0.12446)
		(layer "F.Cu")
		(net "PHY_IOC_TO_CON_B_2_DP")
	)
	(arc
		(start 211.399882 -66.196718)
		(mid 211.436706 -66.107728)
		(end 211.399882 -66.018664)
		(width 0.12446)
		(layer "F.Cu")
		(net "PHY_IOC_TO_CON_B_2_DP")
	)
	(segment
		(start 206.840582 -42.043858)
		(end 212.038946 -45.515022)
		(width 0.1016)
		(layer "In5.Cu")
		(net "PHY_IOC_TO_CON_B_2_DP")
	)
	(segment
		(start 161.892742 -29.98216)
		(end 161.894012 -29.982922)
		(width 0.1016)
		(layer "In5.Cu")
		(net "PHY_IOC_TO_CON_B_2_DP")
	)
	(segment
		(start 161.899092 -29.985716)
		(end 161.900362 -29.986478)
		(width 0.1016)
		(layer "In5.Cu")
		(net "PHY_IOC_TO_CON_B_2_DP")
	)
	(segment
		(start 161.91484 -29.994098)
		(end 161.916872 -29.995114)
		(width 0.1016)
		(layer "In5.Cu")
		(net "PHY_IOC_TO_CON_B_2_DP")
	)
	(segment
		(start 166.75608 -31.561024)
		(end 168.21912 -31.845504)
		(width 0.1016)
		(layer "In5.Cu")
		(net "PHY_IOC_TO_CON_B_2_DP")
	)
	(segment
		(start 214.877904 -54.421024)
		(end 213.190582 -62.857126)
		(width 0.1016)
		(layer "In5.Cu")
		(net "PHY_IOC_TO_CON_B_2_DP")
	)
	(segment
		(start 165.110668 -31.241238)
		(end 165.26129 -31.464504)
		(width 0.1016)
		(layer "In5.Cu")
		(net "PHY_IOC_TO_CON_B_2_DP")
	)
	(segment
		(start 161.917634 -29.995622)
		(end 161.918904 -29.996384)
		(width 0.1016)
		(layer "In5.Cu")
		(net "PHY_IOC_TO_CON_B_2_DP")
	)
	(segment
		(start 166.08298 -31.430214)
		(end 166.233602 -31.65348)
		(width 0.1016)
		(layer "In5.Cu")
		(net "PHY_IOC_TO_CON_B_2_DP")
	)
	(segment
		(start 161.906458 -29.98978)
		(end 161.912554 -29.992828)
		(width 0.1016)
		(layer "In5.Cu")
		(net "PHY_IOC_TO_CON_B_2_DP")
	)
	(segment
		(start 165.560502 -31.52267)
		(end 165.783768 -31.372048)
		(width 0.1016)
		(layer "In5.Cu")
		(net "PHY_IOC_TO_CON_B_2_DP")
	)
	(segment
		(start 172.094398 -34.689034)
		(end 172.358812 -34.637726)
		(width 0.1016)
		(layer "In5.Cu")
		(net "PHY_IOC_TO_CON_B_2_DP")
	)
	(segment
		(start 171.841668 -34.5186)
		(end 172.094398 -34.689034)
		(width 0.1016)
		(layer "In5.Cu")
		(net "PHY_IOC_TO_CON_B_2_DP")
	)
	(segment
		(start 163.615624 -31.144464)
		(end 163.83889 -30.993842)
		(width 0.1016)
		(layer "In5.Cu")
		(net "PHY_IOC_TO_CON_B_2_DP")
	)
	(segment
		(start 166.532814 -31.711646)
		(end 166.75608 -31.561024)
		(width 0.1016)
		(layer "In5.Cu")
		(net "PHY_IOC_TO_CON_B_2_DP")
	)
	(segment
		(start 168.21912 -31.845504)
		(end 169.32656 -32.592518)
		(width 0.1016)
		(layer "In5.Cu")
		(net "PHY_IOC_TO_CON_B_2_DP")
	)
	(segment
		(start 170.968924 -33.700212)
		(end 171.020486 -33.96488)
		(width 0.1016)
		(layer "In5.Cu")
		(net "PHY_IOC_TO_CON_B_2_DP")
	)
	(segment
		(start 164.811456 -31.183072)
		(end 165.110668 -31.241238)
		(width 0.1016)
		(layer "In5.Cu")
		(net "PHY_IOC_TO_CON_B_2_DP")
	)
	(segment
		(start 170.716194 -33.529778)
		(end 170.968924 -33.700212)
		(width 0.1016)
		(layer "In5.Cu")
		(net "PHY_IOC_TO_CON_B_2_DP")
	)
	(segment
		(start 171.79036 -34.254186)
		(end 171.841668 -34.5186)
		(width 0.1016)
		(layer "In5.Cu")
		(net "PHY_IOC_TO_CON_B_2_DP")
	)
	(segment
		(start 161.925 -29.999686)
		(end 161.9377 -30.006036)
		(width 0.1016)
		(layer "In5.Cu")
		(net "PHY_IOC_TO_CON_B_2_DP")
	)
	(segment
		(start 164.587936 -31.333694)
		(end 164.811456 -31.183072)
		(width 0.1016)
		(layer "In5.Cu")
		(net "PHY_IOC_TO_CON_B_2_DP")
	)
	(segment
		(start 166.233602 -31.65348)
		(end 166.532814 -31.711646)
		(width 0.1016)
		(layer "In5.Cu")
		(net "PHY_IOC_TO_CON_B_2_DP")
	)
	(segment
		(start 211.168996 -65.715896)
		(end 211.391754 -65.938654)
		(width 0.1016)
		(layer "In5.Cu")
		(net "PHY_IOC_TO_CON_B_2_DP")
	)
	(segment
		(start 161.755328 -30.023562)
		(end 161.892742 -29.98216)
		(width 0.1016)
		(layer "In5.Cu")
		(net "PHY_IOC_TO_CON_B_2_DP")
	)
	(segment
		(start 211.391754 -66.204846)
		(end 211.228686 -66.367914)
		(width 0.1016)
		(layer "In5.Cu")
		(net "PHY_IOC_TO_CON_B_2_DP")
	)
	(segment
		(start 169.895012 -32.976058)
		(end 170.147742 -33.146492)
		(width 0.1016)
		(layer "In5.Cu")
		(net "PHY_IOC_TO_CON_B_2_DP")
	)
	(segment
		(start 169.630598 -33.027366)
		(end 169.895012 -32.976058)
		(width 0.1016)
		(layer "In5.Cu")
		(net "PHY_IOC_TO_CON_B_2_DP")
	)
	(segment
		(start 212.038946 -45.515022)
		(end 213.595204 -47.822104)
		(width 0.1016)
		(layer "In5.Cu")
		(net "PHY_IOC_TO_CON_B_2_DP")
	)
	(segment
		(start 161.924238 -29.999178)
		(end 161.925 -29.999686)
		(width 0.1016)
		(layer "In5.Cu")
		(net "PHY_IOC_TO_CON_B_2_DP")
	)
	(segment
		(start 164.138102 -31.052008)
		(end 164.288724 -31.275528)
		(width 0.1016)
		(layer "In5.Cu")
		(net "PHY_IOC_TO_CON_B_2_DP")
	)
	(segment
		(start 163.83889 -30.993842)
		(end 164.138102 -31.052008)
		(width 0.1016)
		(layer "In5.Cu")
		(net "PHY_IOC_TO_CON_B_2_DP")
	)
	(segment
		(start 161.500058 -30.500066)
		(end 161.755328 -30.023562)
		(width 0.1016)
		(layer "In5.Cu")
		(net "PHY_IOC_TO_CON_B_2_DP")
	)
	(segment
		(start 161.912554 -29.992828)
		(end 161.91484 -29.994098)
		(width 0.1016)
		(layer "In5.Cu")
		(net "PHY_IOC_TO_CON_B_2_DP")
	)
	(segment
		(start 161.918904 -29.996384)
		(end 161.924238 -29.999178)
		(width 0.1016)
		(layer "In5.Cu")
		(net "PHY_IOC_TO_CON_B_2_DP")
	)
	(segment
		(start 161.900362 -29.986478)
		(end 161.902394 -29.987494)
		(width 0.1016)
		(layer "In5.Cu")
		(net "PHY_IOC_TO_CON_B_2_DP")
	)
	(segment
		(start 162.866578 -30.804866)
		(end 163.16579 -30.863032)
		(width 0.1016)
		(layer "In5.Cu")
		(net "PHY_IOC_TO_CON_B_2_DP")
	)
	(segment
		(start 171.272962 -34.135314)
		(end 171.53763 -34.083752)
		(width 0.1016)
		(layer "In5.Cu")
		(net "PHY_IOC_TO_CON_B_2_DP")
	)
	(segment
		(start 173.432724 -35.362134)
		(end 206.840582 -42.043858)
		(width 0.1016)
		(layer "In5.Cu")
		(net "PHY_IOC_TO_CON_B_2_DP")
	)
	(segment
		(start 161.916872 -29.995114)
		(end 161.917634 -29.995622)
		(width 0.1016)
		(layer "In5.Cu")
		(net "PHY_IOC_TO_CON_B_2_DP")
	)
	(segment
		(start 161.894012 -29.982922)
		(end 161.895536 -29.983684)
		(width 0.1016)
		(layer "In5.Cu")
		(net "PHY_IOC_TO_CON_B_2_DP")
	)
	(segment
		(start 170.45178 -33.58134)
		(end 170.716194 -33.529778)
		(width 0.1016)
		(layer "In5.Cu")
		(net "PHY_IOC_TO_CON_B_2_DP")
	)
	(segment
		(start 172.91558 -35.243008)
		(end 173.179994 -35.1917)
		(width 0.1016)
		(layer "In5.Cu")
		(net "PHY_IOC_TO_CON_B_2_DP")
	)
	(segment
		(start 213.595204 -47.822104)
		(end 214.877904 -54.421024)
		(width 0.1016)
		(layer "In5.Cu")
		(net "PHY_IOC_TO_CON_B_2_DP")
	)
	(segment
		(start 165.783768 -31.372048)
		(end 166.08298 -31.430214)
		(width 0.1016)
		(layer "In5.Cu")
		(net "PHY_IOC_TO_CON_B_2_DP")
	)
	(segment
		(start 161.98342 -30.030928)
		(end 162.530028 -30.57779)
		(width 0.1016)
		(layer "In5.Cu")
		(net "PHY_IOC_TO_CON_B_2_DP")
	)
	(segment
		(start 161.902394 -29.987494)
		(end 161.904172 -29.98851)
		(width 0.1016)
		(layer "In5.Cu")
		(net "PHY_IOC_TO_CON_B_2_DP")
	)
	(segment
		(start 172.66285 -35.072574)
		(end 172.91558 -35.243008)
		(width 0.1016)
		(layer "In5.Cu")
		(net "PHY_IOC_TO_CON_B_2_DP")
	)
	(segment
		(start 170.147742 -33.146492)
		(end 170.19905 -33.410906)
		(width 0.1016)
		(layer "In5.Cu")
		(net "PHY_IOC_TO_CON_B_2_DP")
	)
	(segment
		(start 163.16579 -30.863032)
		(end 163.316412 -31.086298)
		(width 0.1016)
		(layer "In5.Cu")
		(net "PHY_IOC_TO_CON_B_2_DP")
	)
	(segment
		(start 161.9377 -30.006036)
		(end 161.98342 -30.030928)
		(width 0.1016)
		(layer "In5.Cu")
		(net "PHY_IOC_TO_CON_B_2_DP")
	)
	(segment
		(start 169.377868 -32.856932)
		(end 169.630598 -33.027366)
		(width 0.1016)
		(layer "In5.Cu")
		(net "PHY_IOC_TO_CON_B_2_DP")
	)
	(segment
		(start 161.897568 -29.984954)
		(end 161.899092 -29.985716)
		(width 0.1016)
		(layer "In5.Cu")
		(net "PHY_IOC_TO_CON_B_2_DP")
	)
	(segment
		(start 163.316412 -31.086298)
		(end 163.615624 -31.144464)
		(width 0.1016)
		(layer "In5.Cu")
		(net "PHY_IOC_TO_CON_B_2_DP")
	)
	(segment
		(start 172.358812 -34.637726)
		(end 172.611542 -34.80816)
		(width 0.1016)
		(layer "In5.Cu")
		(net "PHY_IOC_TO_CON_B_2_DP")
	)
	(segment
		(start 211.168996 -64.878712)
		(end 211.168996 -65.715896)
		(width 0.1016)
		(layer "In5.Cu")
		(net "PHY_IOC_TO_CON_B_2_DP")
	)
	(segment
		(start 161.904172 -29.98851)
		(end 161.906458 -29.98978)
		(width 0.1016)
		(layer "In5.Cu")
		(net "PHY_IOC_TO_CON_B_2_DP")
	)
	(segment
		(start 161.895536 -29.983684)
		(end 161.896298 -29.984192)
		(width 0.1016)
		(layer "In5.Cu")
		(net "PHY_IOC_TO_CON_B_2_DP")
	)
	(segment
		(start 172.611542 -34.80816)
		(end 172.66285 -35.072574)
		(width 0.1016)
		(layer "In5.Cu")
		(net "PHY_IOC_TO_CON_B_2_DP")
	)
	(segment
		(start 171.020486 -33.96488)
		(end 171.272962 -34.135314)
		(width 0.1016)
		(layer "In5.Cu")
		(net "PHY_IOC_TO_CON_B_2_DP")
	)
	(segment
		(start 171.53763 -34.083752)
		(end 171.79036 -34.254186)
		(width 0.1016)
		(layer "In5.Cu")
		(net "PHY_IOC_TO_CON_B_2_DP")
	)
	(segment
		(start 164.288724 -31.275528)
		(end 164.587936 -31.333694)
		(width 0.1016)
		(layer "In5.Cu")
		(net "PHY_IOC_TO_CON_B_2_DP")
	)
	(segment
		(start 170.19905 -33.410906)
		(end 170.45178 -33.58134)
		(width 0.1016)
		(layer "In5.Cu")
		(net "PHY_IOC_TO_CON_B_2_DP")
	)
	(segment
		(start 165.26129 -31.464504)
		(end 165.560502 -31.52267)
		(width 0.1016)
		(layer "In5.Cu")
		(net "PHY_IOC_TO_CON_B_2_DP")
	)
	(segment
		(start 213.190582 -62.857126)
		(end 211.168996 -64.878712)
		(width 0.1016)
		(layer "In5.Cu")
		(net "PHY_IOC_TO_CON_B_2_DP")
	)
	(segment
		(start 169.32656 -32.592518)
		(end 169.377868 -32.856932)
		(width 0.1016)
		(layer "In5.Cu")
		(net "PHY_IOC_TO_CON_B_2_DP")
	)
	(segment
		(start 161.896298 -29.984192)
		(end 161.897568 -29.984954)
		(width 0.1016)
		(layer "In5.Cu")
		(net "PHY_IOC_TO_CON_B_2_DP")
	)
	(segment
		(start 162.530028 -30.57779)
		(end 162.866578 -30.804866)
		(width 0.1016)
		(layer "In5.Cu")
		(net "PHY_IOC_TO_CON_B_2_DP")
	)
	(segment
		(start 173.179994 -35.1917)
		(end 173.432724 -35.362134)
		(width 0.1016)
		(layer "In5.Cu")
		(net "PHY_IOC_TO_CON_B_2_DP")
	)
	(arc
		(start 211.391754 -65.938654)
		(mid 211.446884 -66.07175)
		(end 211.391754 -66.204846)
		(width 0.1016)
		(layer "In5.Cu")
		(net "PHY_IOC_TO_CON_B_2_DP")
	)
	(segment
		(start 205.482444 -67.493388)
		(end 206.807308 -66.168524)
		(width 0.12446)
		(layer "F.Cu")
		(net "PHY_IOC_TO_CON_B_2_DN_C")
	)
	(segment
		(start 204.231748 -67.493388)
		(end 205.482444 -67.493388)
		(width 0.12446)
		(layer "F.Cu")
		(net "PHY_IOC_TO_CON_B_2_DN_C")
	)
	(segment
		(start 204.166724 -67.558412)
		(end 204.231748 -67.493388)
		(width 0.12446)
		(layer "F.Cu")
		(net "PHY_IOC_TO_CON_B_2_DN_C")
	)
	(segment
		(start 206.807308 -66.168524)
		(end 207.698848 -66.168524)
		(width 0.12446)
		(layer "F.Cu")
		(net "PHY_IOC_TO_CON_B_2_DN_C")
	)
	(segment
		(start 203.60005 -67.900042)
		(end 203.60005 -67.79895)
		(width 0.12446)
		(layer "F.Cu")
		(net "PHY_IOC_TO_CON_B_2_DN_C")
	)
	(segment
		(start 203.60005 -67.79895)
		(end 203.840588 -67.558412)
		(width 0.12446)
		(layer "F.Cu")
		(net "PHY_IOC_TO_CON_B_2_DN_C")
	)
	(segment
		(start 207.698848 -66.168524)
		(end 207.776572 -66.0908)
		(width 0.12446)
		(layer "F.Cu")
		(net "PHY_IOC_TO_CON_B_2_DN_C")
	)
	(segment
		(start 203.840588 -67.558412)
		(end 204.166724 -67.558412)
		(width 0.12446)
		(layer "F.Cu")
		(net "PHY_IOC_TO_CON_B_2_DN_C")
	)
	(segment
		(start 212.036914 -65.559686)
		(end 211.86521 -65.73139)
		(width 0.12446)
		(layer "F.Cu")
		(net "PHY_IOC_TO_CON_B_2_DN")
	)
	(segment
		(start 209.370676 -66.152522)
		(end 208.397094 -66.152522)
		(width 0.12446)
		(layer "F.Cu")
		(net "PHY_IOC_TO_CON_B_2_DN")
	)
	(segment
		(start 210.254088 -65.26911)
		(end 209.370676 -66.152522)
		(width 0.12446)
		(layer "F.Cu")
		(net "PHY_IOC_TO_CON_B_2_DN")
	)
	(segment
		(start 208.397094 -66.152522)
		(end 208.335372 -66.0908)
		(width 0.12446)
		(layer "F.Cu")
		(net "PHY_IOC_TO_CON_B_2_DN")
	)
	(segment
		(start 211.22513 -65.26911)
		(end 210.254088 -65.26911)
		(width 0.12446)
		(layer "F.Cu")
		(net "PHY_IOC_TO_CON_B_2_DN")
	)
	(segment
		(start 211.68741 -65.73139)
		(end 211.22513 -65.26911)
		(width 0.12446)
		(layer "F.Cu")
		(net "PHY_IOC_TO_CON_B_2_DN")
	)
	(arc
		(start 211.86521 -65.73139)
		(mid 211.77631 -65.768214)
		(end 211.68741 -65.73139)
		(width 0.12446)
		(layer "F.Cu")
		(net "PHY_IOC_TO_CON_B_2_DN")
	)
	(segment
		(start 162.047936 -29.71927)
		(end 162.048698 -29.719778)
		(width 0.1016)
		(layer "In5.Cu")
		(net "PHY_IOC_TO_CON_B_2_DN")
	)
	(segment
		(start 162.037014 -29.713428)
		(end 162.038284 -29.71419)
		(width 0.1016)
		(layer "In5.Cu")
		(net "PHY_IOC_TO_CON_B_2_DN")
	)
	(segment
		(start 161.995104 -29.576014)
		(end 162.037014 -29.713428)
		(width 0.1016)
		(layer "In5.Cu")
		(net "PHY_IOC_TO_CON_B_2_DN")
	)
	(segment
		(start 162.25012 -29.100018)
		(end 161.995104 -29.576014)
		(width 0.1016)
		(layer "In5.Cu")
		(net "PHY_IOC_TO_CON_B_2_DN")
	)
	(segment
		(start 213.882732 -47.702978)
		(end 215.1888 -54.421786)
		(width 0.1016)
		(layer "In5.Cu")
		(net "PHY_IOC_TO_CON_B_2_DN")
	)
	(segment
		(start 168.338246 -31.557976)
		(end 173.552612 -35.075114)
		(width 0.1016)
		(layer "In5.Cu")
		(net "PHY_IOC_TO_CON_B_2_DN")
	)
	(segment
		(start 162.039808 -29.715206)
		(end 162.047936 -29.71927)
		(width 0.1016)
		(layer "In5.Cu")
		(net "PHY_IOC_TO_CON_B_2_DN")
	)
	(segment
		(start 206.959708 -41.756838)
		(end 212.258148 -45.294804)
		(width 0.1016)
		(layer "In5.Cu")
		(net "PHY_IOC_TO_CON_B_2_DN")
	)
	(segment
		(start 211.473796 -65.589404)
		(end 211.6074 -65.723008)
		(width 0.1016)
		(layer "In5.Cu")
		(net "PHY_IOC_TO_CON_B_2_DN")
	)
	(segment
		(start 215.1888 -54.421786)
		(end 213.471506 -63.007494)
		(width 0.1016)
		(layer "In5.Cu")
		(net "PHY_IOC_TO_CON_B_2_DN")
	)
	(segment
		(start 162.059366 -29.725366)
		(end 162.06343 -29.727906)
		(width 0.1016)
		(layer "In5.Cu")
		(net "PHY_IOC_TO_CON_B_2_DN")
	)
	(segment
		(start 162.080194 -29.736288)
		(end 162.168078 -29.78404)
		(width 0.1016)
		(layer "In5.Cu")
		(net "PHY_IOC_TO_CON_B_2_DN")
	)
	(segment
		(start 162.054032 -29.722318)
		(end 162.058096 -29.724604)
		(width 0.1016)
		(layer "In5.Cu")
		(net "PHY_IOC_TO_CON_B_2_DN")
	)
	(segment
		(start 211.473796 -65.005204)
		(end 211.473796 -65.589404)
		(width 0.1016)
		(layer "In5.Cu")
		(net "PHY_IOC_TO_CON_B_2_DN")
	)
	(segment
		(start 212.258148 -45.294804)
		(end 213.882732 -47.702978)
		(width 0.1016)
		(layer "In5.Cu")
		(net "PHY_IOC_TO_CON_B_2_DN")
	)
	(segment
		(start 173.552612 -35.075114)
		(end 206.959708 -41.756838)
		(width 0.1016)
		(layer "In5.Cu")
		(net "PHY_IOC_TO_CON_B_2_DN")
	)
	(segment
		(start 162.050984 -29.720794)
		(end 162.054032 -29.722318)
		(width 0.1016)
		(layer "In5.Cu")
		(net "PHY_IOC_TO_CON_B_2_DN")
	)
	(segment
		(start 162.985704 -30.517338)
		(end 168.338246 -31.557976)
		(width 0.1016)
		(layer "In5.Cu")
		(net "PHY_IOC_TO_CON_B_2_DN")
	)
	(segment
		(start 213.471506 -63.007494)
		(end 211.473796 -65.005204)
		(width 0.1016)
		(layer "In5.Cu")
		(net "PHY_IOC_TO_CON_B_2_DN")
	)
	(segment
		(start 211.873592 -65.723008)
		(end 212.036914 -65.559686)
		(width 0.1016)
		(layer "In5.Cu")
		(net "PHY_IOC_TO_CON_B_2_DN")
	)
	(segment
		(start 162.7251 -30.341316)
		(end 162.985704 -30.517338)
		(width 0.1016)
		(layer "In5.Cu")
		(net "PHY_IOC_TO_CON_B_2_DN")
	)
	(segment
		(start 162.058096 -29.724604)
		(end 162.059366 -29.725366)
		(width 0.1016)
		(layer "In5.Cu")
		(net "PHY_IOC_TO_CON_B_2_DN")
	)
	(segment
		(start 162.168078 -29.78404)
		(end 162.7251 -30.341316)
		(width 0.1016)
		(layer "In5.Cu")
		(net "PHY_IOC_TO_CON_B_2_DN")
	)
	(segment
		(start 162.06343 -29.727906)
		(end 162.080194 -29.736288)
		(width 0.1016)
		(layer "In5.Cu")
		(net "PHY_IOC_TO_CON_B_2_DN")
	)
	(segment
		(start 162.048698 -29.719778)
		(end 162.050984 -29.720794)
		(width 0.1016)
		(layer "In5.Cu")
		(net "PHY_IOC_TO_CON_B_2_DN")
	)
	(segment
		(start 162.038284 -29.71419)
		(end 162.039808 -29.715206)
		(width 0.1016)
		(layer "In5.Cu")
		(net "PHY_IOC_TO_CON_B_2_DN")
	)
	(arc
		(start 211.6074 -65.723008)
		(mid 211.740496 -65.778138)
		(end 211.873592 -65.723008)
		(width 0.1016)
		(layer "In5.Cu")
		(net "PHY_IOC_TO_CON_B_2_DN")
	)
	(segment
		(start 207.196944 -68.2498)
		(end 207.041496 -68.405248)
		(width 0.12446)
		(layer "F.Cu")
		(net "PHY_IOC_TO_CON_B_1_DP_C")
	)
	(segment
		(start 207.041496 -68.845938)
		(end 206.124556 -69.762878)
		(width 0.12446)
		(layer "F.Cu")
		(net "PHY_IOC_TO_CON_B_1_DP_C")
	)
	(segment
		(start 207.776572 -68.326)
		(end 207.700372 -68.2498)
		(width 0.12446)
		(layer "F.Cu")
		(net "PHY_IOC_TO_CON_B_1_DP_C")
	)
	(segment
		(start 206.124556 -69.762878)
		(end 205.456028 -69.762878)
		(width 0.12446)
		(layer "F.Cu")
		(net "PHY_IOC_TO_CON_B_1_DP_C")
	)
	(segment
		(start 207.700372 -68.2498)
		(end 207.196944 -68.2498)
		(width 0.12446)
		(layer "F.Cu")
		(net "PHY_IOC_TO_CON_B_1_DP_C")
	)
	(segment
		(start 207.041496 -68.405248)
		(end 207.041496 -68.845938)
		(width 0.12446)
		(layer "F.Cu")
		(net "PHY_IOC_TO_CON_B_1_DP_C")
	)
	(segment
		(start 205.192884 -69.499734)
		(end 204.40015 -69.499734)
		(width 0.12446)
		(layer "F.Cu")
		(net "PHY_IOC_TO_CON_B_1_DP_C")
	)
	(segment
		(start 205.456028 -69.762878)
		(end 205.192884 -69.499734)
		(width 0.12446)
		(layer "F.Cu")
		(net "PHY_IOC_TO_CON_B_1_DP_C")
	)
	(segment
		(start 204.40015 -69.499734)
		(end 204.399896 -69.499988)
		(width 0.12446)
		(layer "F.Cu")
		(net "PHY_IOC_TO_CON_B_1_DP_C")
	)
	(segment
		(start 208.335372 -68.326)
		(end 208.449672 -68.2117)
		(width 0.12446)
		(layer "F.Cu")
		(net "PHY_IOC_TO_CON_B_1_DP")
	)
	(segment
		(start 212.09 -67.31)
		(end 212.514434 -67.31)
		(width 0.12446)
		(layer "F.Cu")
		(net "PHY_IOC_TO_CON_B_1_DP")
	)
	(segment
		(start 211.1883 -68.2117)
		(end 212.09 -67.31)
		(width 0.12446)
		(layer "F.Cu")
		(net "PHY_IOC_TO_CON_B_1_DP")
	)
	(segment
		(start 212.514434 -67.31)
		(end 212.835744 -67.63131)
		(width 0.12446)
		(layer "F.Cu")
		(net "PHY_IOC_TO_CON_B_1_DP")
	)
	(segment
		(start 208.449672 -68.2117)
		(end 211.1883 -68.2117)
		(width 0.12446)
		(layer "F.Cu")
		(net "PHY_IOC_TO_CON_B_1_DP")
	)
	(segment
		(start 212.835744 -67.885056)
		(end 212.701886 -68.018914)
		(width 0.12446)
		(layer "F.Cu")
		(net "PHY_IOC_TO_CON_B_1_DP")
	)
	(arc
		(start 212.835744 -67.63131)
		(mid 212.888424 -67.75822)
		(end 212.835744 -67.885056)
		(width 0.12446)
		(layer "F.Cu")
		(net "PHY_IOC_TO_CON_B_1_DP")
	)
	(segment
		(start 214.688674 -47.702216)
		(end 216.07272 -54.82209)
		(width 0.1016)
		(layer "In5.Cu")
		(net "PHY_IOC_TO_CON_B_1_DP")
	)
	(segment
		(start 171.31538 -32.450278)
		(end 171.368212 -32.714438)
		(width 0.1016)
		(layer "In5.Cu")
		(net "PHY_IOC_TO_CON_B_1_DP")
	)
	(segment
		(start 167.259254 -29.975302)
		(end 167.523414 -29.92247)
		(width 0.1016)
		(layer "In5.Cu")
		(net "PHY_IOC_TO_CON_B_1_DP")
	)
	(segment
		(start 212.5853 -66.561208)
		(end 212.5853 -67.31)
		(width 0.1016)
		(layer "In5.Cu")
		(net "PHY_IOC_TO_CON_B_1_DP")
	)
	(segment
		(start 215.04148 -59.979306)
		(end 215.04148 -59.97956)
		(width 0.1016)
		(layer "In5.Cu")
		(net "PHY_IOC_TO_CON_B_1_DP")
	)
	(segment
		(start 167.829992 -30.35554)
		(end 168.083484 -30.524704)
		(width 0.1016)
		(layer "In5.Cu")
		(net "PHY_IOC_TO_CON_B_1_DP")
	)
	(segment
		(start 174.6123 -34.64814)
		(end 207.570832 -41.239694)
		(width 0.1016)
		(layer "In5.Cu")
		(net "PHY_IOC_TO_CON_B_1_DP")
	)
	(segment
		(start 173.840902 -34.362898)
		(end 174.094394 -34.531808)
		(width 0.1016)
		(layer "In5.Cu")
		(net "PHY_IOC_TO_CON_B_1_DP")
	)
	(segment
		(start 173.78807 -34.098738)
		(end 173.840902 -34.362898)
		(width 0.1016)
		(layer "In5.Cu")
		(net "PHY_IOC_TO_CON_B_1_DP")
	)
	(segment
		(start 172.13961 -32.99968)
		(end 172.192442 -33.26384)
		(width 0.1016)
		(layer "In5.Cu")
		(net "PHY_IOC_TO_CON_B_1_DP")
	)
	(segment
		(start 168.347644 -30.471872)
		(end 168.60139 -30.640782)
		(width 0.1016)
		(layer "In5.Cu")
		(net "PHY_IOC_TO_CON_B_1_DP")
	)
	(segment
		(start 159.642556 -26.18232)
		(end 159.692848 -26.209752)
		(width 0.1016)
		(layer "In5.Cu")
		(net "PHY_IOC_TO_CON_B_1_DP")
	)
	(segment
		(start 207.570832 -41.239694)
		(end 212.590888 -44.59224)
		(width 0.1016)
		(layer "In5.Cu")
		(net "PHY_IOC_TO_CON_B_1_DP")
	)
	(segment
		(start 172.445934 -33.433004)
		(end 172.710094 -33.380172)
		(width 0.1016)
		(layer "In5.Cu")
		(net "PHY_IOC_TO_CON_B_1_DP")
	)
	(segment
		(start 174.358808 -34.478976)
		(end 174.6123 -34.64814)
		(width 0.1016)
		(layer "In5.Cu")
		(net "PHY_IOC_TO_CON_B_1_DP")
	)
	(segment
		(start 213.639654 -46.146974)
		(end 213.639654 -46.147228)
		(width 0.1016)
		(layer "In5.Cu")
		(net "PHY_IOC_TO_CON_B_1_DP")
	)
	(segment
		(start 215.04148 -59.97956)
		(end 214.01024 -65.136268)
		(width 0.1016)
		(layer "In5.Cu")
		(net "PHY_IOC_TO_CON_B_1_DP")
	)
	(segment
		(start 166.181532 -29.256736)
		(end 166.435024 -29.425646)
		(width 0.1016)
		(layer "In5.Cu")
		(net "PHY_IOC_TO_CON_B_1_DP")
	)
	(segment
		(start 212.5853 -67.31)
		(end 212.864954 -67.589654)
		(width 0.1016)
		(layer "In5.Cu")
		(net "PHY_IOC_TO_CON_B_1_DP")
	)
	(segment
		(start 172.710094 -33.380172)
		(end 172.96384 -33.549082)
		(width 0.1016)
		(layer "In5.Cu")
		(net "PHY_IOC_TO_CON_B_1_DP")
	)
	(segment
		(start 174.094394 -34.531808)
		(end 174.358808 -34.478976)
		(width 0.1016)
		(layer "In5.Cu")
		(net "PHY_IOC_TO_CON_B_1_DP")
	)
	(segment
		(start 169.171874 -31.021274)
		(end 171.31538 -32.450278)
		(width 0.1016)
		(layer "In5.Cu")
		(net "PHY_IOC_TO_CON_B_1_DP")
	)
	(segment
		(start 167.523414 -29.92247)
		(end 167.77716 -30.09138)
		(width 0.1016)
		(layer "In5.Cu")
		(net "PHY_IOC_TO_CON_B_1_DP")
	)
	(segment
		(start 168.60139 -30.640782)
		(end 168.654222 -30.904942)
		(width 0.1016)
		(layer "In5.Cu")
		(net "PHY_IOC_TO_CON_B_1_DP")
	)
	(segment
		(start 159.692848 -26.209752)
		(end 159.93999 -26.45664)
		(width 0.1016)
		(layer "In5.Cu")
		(net "PHY_IOC_TO_CON_B_1_DP")
	)
	(segment
		(start 166.699184 -29.372814)
		(end 166.95293 -29.541978)
		(width 0.1016)
		(layer "In5.Cu")
		(net "PHY_IOC_TO_CON_B_1_DP")
	)
	(segment
		(start 173.534324 -33.929574)
		(end 173.78807 -34.098738)
		(width 0.1016)
		(layer "In5.Cu")
		(net "PHY_IOC_TO_CON_B_1_DP")
	)
	(segment
		(start 173.016672 -33.813496)
		(end 173.270164 -33.982406)
		(width 0.1016)
		(layer "In5.Cu")
		(net "PHY_IOC_TO_CON_B_1_DP")
	)
	(segment
		(start 168.907714 -31.074106)
		(end 169.171874 -31.021274)
		(width 0.1016)
		(layer "In5.Cu")
		(net "PHY_IOC_TO_CON_B_1_DP")
	)
	(segment
		(start 166.128446 -28.992576)
		(end 166.181532 -29.256736)
		(width 0.1016)
		(layer "In5.Cu")
		(net "PHY_IOC_TO_CON_B_1_DP")
	)
	(segment
		(start 168.654222 -30.904942)
		(end 168.907714 -31.074106)
		(width 0.1016)
		(layer "In5.Cu")
		(net "PHY_IOC_TO_CON_B_1_DP")
	)
	(segment
		(start 168.083484 -30.524704)
		(end 168.347644 -30.471872)
		(width 0.1016)
		(layer "In5.Cu")
		(net "PHY_IOC_TO_CON_B_1_DP")
	)
	(segment
		(start 172.192442 -33.26384)
		(end 172.445934 -33.433004)
		(width 0.1016)
		(layer "In5.Cu")
		(net "PHY_IOC_TO_CON_B_1_DP")
	)
	(segment
		(start 173.270164 -33.982406)
		(end 173.534324 -33.929574)
		(width 0.1016)
		(layer "In5.Cu")
		(net "PHY_IOC_TO_CON_B_1_DP")
	)
	(segment
		(start 171.368212 -32.714438)
		(end 171.621704 -32.883602)
		(width 0.1016)
		(layer "In5.Cu")
		(net "PHY_IOC_TO_CON_B_1_DP")
	)
	(segment
		(start 216.07272 -54.82209)
		(end 215.04148 -59.979306)
		(width 0.1016)
		(layer "In5.Cu")
		(net "PHY_IOC_TO_CON_B_1_DP")
	)
	(segment
		(start 214.01024 -65.136268)
		(end 212.5853 -66.561208)
		(width 0.1016)
		(layer "In5.Cu")
		(net "PHY_IOC_TO_CON_B_1_DP")
	)
	(segment
		(start 159.505142 -26.223722)
		(end 159.642556 -26.18232)
		(width 0.1016)
		(layer "In5.Cu")
		(net "PHY_IOC_TO_CON_B_1_DP")
	)
	(segment
		(start 171.621704 -32.883602)
		(end 171.885864 -32.83077)
		(width 0.1016)
		(layer "In5.Cu")
		(net "PHY_IOC_TO_CON_B_1_DP")
	)
	(segment
		(start 167.77716 -30.09138)
		(end 167.829992 -30.35554)
		(width 0.1016)
		(layer "In5.Cu")
		(net "PHY_IOC_TO_CON_B_1_DP")
	)
	(segment
		(start 159.93999 -26.930604)
		(end 160.82264 -27.813508)
		(width 0.1016)
		(layer "In5.Cu")
		(net "PHY_IOC_TO_CON_B_1_DP")
	)
	(segment
		(start 166.435024 -29.425646)
		(end 166.699184 -29.372814)
		(width 0.1016)
		(layer "In5.Cu")
		(net "PHY_IOC_TO_CON_B_1_DP")
	)
	(segment
		(start 213.639654 -46.147228)
		(end 214.688674 -47.702216)
		(width 0.1016)
		(layer "In5.Cu")
		(net "PHY_IOC_TO_CON_B_1_DP")
	)
	(segment
		(start 159.250126 -26.699972)
		(end 159.505142 -26.223722)
		(width 0.1016)
		(layer "In5.Cu")
		(net "PHY_IOC_TO_CON_B_1_DP")
	)
	(segment
		(start 171.885864 -32.83077)
		(end 172.13961 -32.99968)
		(width 0.1016)
		(layer "In5.Cu")
		(net "PHY_IOC_TO_CON_B_1_DP")
	)
	(segment
		(start 160.82264 -27.813508)
		(end 165.874954 -28.823412)
		(width 0.1016)
		(layer "In5.Cu")
		(net "PHY_IOC_TO_CON_B_1_DP")
	)
	(segment
		(start 166.95293 -29.541978)
		(end 167.005762 -29.806138)
		(width 0.1016)
		(layer "In5.Cu")
		(net "PHY_IOC_TO_CON_B_1_DP")
	)
	(segment
		(start 212.864954 -67.855846)
		(end 212.701886 -68.018914)
		(width 0.1016)
		(layer "In5.Cu")
		(net "PHY_IOC_TO_CON_B_1_DP")
	)
	(segment
		(start 165.874954 -28.823412)
		(end 166.128446 -28.992576)
		(width 0.1016)
		(layer "In5.Cu")
		(net "PHY_IOC_TO_CON_B_1_DP")
	)
	(segment
		(start 159.93999 -26.45664)
		(end 159.93999 -26.930604)
		(width 0.1016)
		(layer "In5.Cu")
		(net "PHY_IOC_TO_CON_B_1_DP")
	)
	(segment
		(start 212.590888 -44.59224)
		(end 213.639654 -46.146974)
		(width 0.1016)
		(layer "In5.Cu")
		(net "PHY_IOC_TO_CON_B_1_DP")
	)
	(segment
		(start 167.005762 -29.806138)
		(end 167.259254 -29.975302)
		(width 0.1016)
		(layer "In5.Cu")
		(net "PHY_IOC_TO_CON_B_1_DP")
	)
	(segment
		(start 172.96384 -33.549082)
		(end 173.016672 -33.813496)
		(width 0.1016)
		(layer "In5.Cu")
		(net "PHY_IOC_TO_CON_B_1_DP")
	)
	(arc
		(start 212.864954 -67.589654)
		(mid 212.920084 -67.72275)
		(end 212.864954 -67.855846)
		(width 0.1016)
		(layer "In5.Cu")
		(net "PHY_IOC_TO_CON_B_1_DP")
	)
	(segment
		(start 205.62443 -69.356478)
		(end 205.956154 -69.356478)
		(width 0.12446)
		(layer "F.Cu")
		(net "PHY_IOC_TO_CON_B_1_DN_C")
	)
	(segment
		(start 205.361286 -69.093334)
		(end 205.62443 -69.356478)
		(width 0.12446)
		(layer "F.Cu")
		(net "PHY_IOC_TO_CON_B_1_DN_C")
	)
	(segment
		(start 206.635096 -68.236846)
		(end 207.028542 -67.8434)
		(width 0.12446)
		(layer "F.Cu")
		(net "PHY_IOC_TO_CON_B_1_DN_C")
	)
	(segment
		(start 203.60005 -69.499988)
		(end 204.343 -69.093334)
		(width 0.12446)
		(layer "F.Cu")
		(net "PHY_IOC_TO_CON_B_1_DN_C")
	)
	(segment
		(start 207.028542 -67.8434)
		(end 207.700372 -67.8434)
		(width 0.12446)
		(layer "F.Cu")
		(net "PHY_IOC_TO_CON_B_1_DN_C")
	)
	(segment
		(start 204.343 -69.093334)
		(end 205.361286 -69.093334)
		(width 0.12446)
		(layer "F.Cu")
		(net "PHY_IOC_TO_CON_B_1_DN_C")
	)
	(segment
		(start 206.635096 -68.677536)
		(end 206.635096 -68.236846)
		(width 0.12446)
		(layer "F.Cu")
		(net "PHY_IOC_TO_CON_B_1_DN_C")
	)
	(segment
		(start 207.700372 -67.8434)
		(end 207.776572 -67.7672)
		(width 0.12446)
		(layer "F.Cu")
		(net "PHY_IOC_TO_CON_B_1_DN_C")
	)
	(segment
		(start 205.956154 -69.356478)
		(end 206.635096 -68.677536)
		(width 0.12446)
		(layer "F.Cu")
		(net "PHY_IOC_TO_CON_B_1_DN_C")
	)
	(segment
		(start 211.921598 -66.9036)
		(end 212.682836 -66.9036)
		(width 0.12446)
		(layer "F.Cu")
		(net "PHY_IOC_TO_CON_B_1_DN")
	)
	(segment
		(start 211.019898 -67.8053)
		(end 211.921598 -66.9036)
		(width 0.12446)
		(layer "F.Cu")
		(net "PHY_IOC_TO_CON_B_1_DN")
	)
	(segment
		(start 212.682836 -66.9036)
		(end 213.123018 -67.343782)
		(width 0.12446)
		(layer "F.Cu")
		(net "PHY_IOC_TO_CON_B_1_DN")
	)
	(segment
		(start 213.377018 -67.343782)
		(end 213.510114 -67.210686)
		(width 0.12446)
		(layer "F.Cu")
		(net "PHY_IOC_TO_CON_B_1_DN")
	)
	(segment
		(start 208.373472 -67.8053)
		(end 211.019898 -67.8053)
		(width 0.12446)
		(layer "F.Cu")
		(net "PHY_IOC_TO_CON_B_1_DN")
	)
	(segment
		(start 208.335372 -67.7672)
		(end 208.373472 -67.8053)
		(width 0.12446)
		(layer "F.Cu")
		(net "PHY_IOC_TO_CON_B_1_DN")
	)
	(arc
		(start 213.123018 -67.343782)
		(mid 213.250018 -67.396387)
		(end 213.377018 -67.343782)
		(width 0.12446)
		(layer "F.Cu")
		(net "PHY_IOC_TO_CON_B_1_DN")
	)
	(segment
		(start 207.689958 -40.952674)
		(end 212.81009 -44.372022)
		(width 0.1016)
		(layer "In5.Cu")
		(net "PHY_IOC_TO_CON_B_1_DN")
	)
	(segment
		(start 159.999934 -25.299924)
		(end 159.744664 -25.776174)
		(width 0.1016)
		(layer "In5.Cu")
		(net "PHY_IOC_TO_CON_B_1_DN")
	)
	(segment
		(start 216.383616 -54.822852)
		(end 214.291164 -65.286636)
		(width 0.1016)
		(layer "In5.Cu")
		(net "PHY_IOC_TO_CON_B_1_DN")
	)
	(segment
		(start 160.24479 -26.804112)
		(end 160.973008 -27.53233)
		(width 0.1016)
		(layer "In5.Cu")
		(net "PHY_IOC_TO_CON_B_1_DN")
	)
	(segment
		(start 159.744664 -25.776174)
		(end 159.786574 -25.913588)
		(width 0.1016)
		(layer "In5.Cu")
		(net "PHY_IOC_TO_CON_B_1_DN")
	)
	(segment
		(start 214.291164 -65.286636)
		(end 212.8901 -66.6877)
		(width 0.1016)
		(layer "In5.Cu")
		(net "PHY_IOC_TO_CON_B_1_DN")
	)
	(segment
		(start 160.973008 -27.53233)
		(end 165.993826 -28.536138)
		(width 0.1016)
		(layer "In5.Cu")
		(net "PHY_IOC_TO_CON_B_1_DN")
	)
	(segment
		(start 159.786574 -25.913588)
		(end 159.876236 -25.961594)
		(width 0.1016)
		(layer "In5.Cu")
		(net "PHY_IOC_TO_CON_B_1_DN")
	)
	(segment
		(start 214.976202 -47.58309)
		(end 216.383616 -54.822852)
		(width 0.1016)
		(layer "In5.Cu")
		(net "PHY_IOC_TO_CON_B_1_DN")
	)
	(segment
		(start 213.346792 -67.374008)
		(end 213.510114 -67.210686)
		(width 0.1016)
		(layer "In5.Cu")
		(net "PHY_IOC_TO_CON_B_1_DN")
	)
	(segment
		(start 165.993826 -28.536138)
		(end 174.731172 -34.360866)
		(width 0.1016)
		(layer "In5.Cu")
		(net "PHY_IOC_TO_CON_B_1_DN")
	)
	(segment
		(start 174.731172 -34.360866)
		(end 207.689958 -40.952674)
		(width 0.1016)
		(layer "In5.Cu")
		(net "PHY_IOC_TO_CON_B_1_DN")
	)
	(segment
		(start 212.8901 -67.183508)
		(end 213.0806 -67.374008)
		(width 0.1016)
		(layer "In5.Cu")
		(net "PHY_IOC_TO_CON_B_1_DN")
	)
	(segment
		(start 212.8901 -66.6877)
		(end 212.8901 -67.183508)
		(width 0.1016)
		(layer "In5.Cu")
		(net "PHY_IOC_TO_CON_B_1_DN")
	)
	(segment
		(start 159.876236 -25.961594)
		(end 160.24479 -26.330148)
		(width 0.1016)
		(layer "In5.Cu")
		(net "PHY_IOC_TO_CON_B_1_DN")
	)
	(segment
		(start 212.81009 -44.372022)
		(end 214.976202 -47.58309)
		(width 0.1016)
		(layer "In5.Cu")
		(net "PHY_IOC_TO_CON_B_1_DN")
	)
	(segment
		(start 160.24479 -26.330148)
		(end 160.24479 -26.804112)
		(width 0.1016)
		(layer "In5.Cu")
		(net "PHY_IOC_TO_CON_B_1_DN")
	)
	(arc
		(start 213.0806 -67.374008)
		(mid 213.213696 -67.429138)
		(end 213.346792 -67.374008)
		(width 0.1016)
		(layer "In5.Cu")
		(net "PHY_IOC_TO_CON_B_1_DN")
	)
	(segment
		(start 207.16494 -69.941694)
		(end 206.71155 -70.395338)
		(width 0.12446)
		(layer "F.Cu")
		(net "PHY_IOC_TO_CON_B_0_DP_C")
	)
	(segment
		(start 207.715866 -69.941694)
		(end 207.16494 -69.941694)
		(width 0.12446)
		(layer "F.Cu")
		(net "PHY_IOC_TO_CON_B_0_DP_C")
	)
	(segment
		(start 204.4954 -70.395338)
		(end 204.399896 -70.299834)
		(width 0.12446)
		(layer "F.Cu")
		(net "PHY_IOC_TO_CON_B_0_DP_C")
	)
	(segment
		(start 207.776572 -70.0024)
		(end 207.715866 -69.941694)
		(width 0.12446)
		(layer "F.Cu")
		(net "PHY_IOC_TO_CON_B_0_DP_C")
	)
	(segment
		(start 206.71155 -70.395338)
		(end 204.4954 -70.395338)
		(width 0.12446)
		(layer "F.Cu")
		(net "PHY_IOC_TO_CON_B_0_DP_C")
	)
	(segment
		(start 214.359744 -69.358256)
		(end 214.225886 -69.492114)
		(width 0.12446)
		(layer "F.Cu")
		(net "PHY_IOC_TO_CON_B_0_DP")
	)
	(segment
		(start 214.138002 -68.882768)
		(end 214.359744 -69.10451)
		(width 0.12446)
		(layer "F.Cu")
		(net "PHY_IOC_TO_CON_B_0_DP")
	)
	(segment
		(start 212.572346 -69.9008)
		(end 213.590378 -68.882768)
		(width 0.12446)
		(layer "F.Cu")
		(net "PHY_IOC_TO_CON_B_0_DP")
	)
	(segment
		(start 208.335372 -70.0024)
		(end 208.436972 -69.9008)
		(width 0.12446)
		(layer "F.Cu")
		(net "PHY_IOC_TO_CON_B_0_DP")
	)
	(segment
		(start 208.436972 -69.9008)
		(end 212.572346 -69.9008)
		(width 0.12446)
		(layer "F.Cu")
		(net "PHY_IOC_TO_CON_B_0_DP")
	)
	(segment
		(start 213.590378 -68.882768)
		(end 214.138002 -68.882768)
		(width 0.12446)
		(layer "F.Cu")
		(net "PHY_IOC_TO_CON_B_0_DP")
	)
	(arc
		(start 214.359744 -69.10451)
		(mid 214.412424 -69.23142)
		(end 214.359744 -69.358256)
		(width 0.12446)
		(layer "F.Cu")
		(net "PHY_IOC_TO_CON_B_0_DP")
	)
	(segment
		(start 163.63061 -27.126184)
		(end 163.780216 -27.350466)
		(width 0.1016)
		(layer "In5.Cu")
		(net "PHY_IOC_TO_CON_B_0_DP")
	)
	(segment
		(start 169.270934 -29.526738)
		(end 169.323766 -29.790898)
		(width 0.1016)
		(layer "In5.Cu")
		(net "PHY_IOC_TO_CON_B_0_DP")
	)
	(segment
		(start 161.755328 -26.223468)
		(end 161.892742 -26.182066)
		(width 0.1016)
		(layer "In5.Cu")
		(net "PHY_IOC_TO_CON_B_0_DP")
	)
	(segment
		(start 175.887634 -33.937956)
		(end 207.605884 -40.277542)
		(width 0.1016)
		(layer "In5.Cu")
		(net "PHY_IOC_TO_CON_B_0_DP")
	)
	(segment
		(start 215.616028 -47.295308)
		(end 217.291412 -55.672482)
		(width 0.1016)
		(layer "In5.Cu")
		(net "PHY_IOC_TO_CON_B_0_DP")
	)
	(segment
		(start 214.996268 -67.14744)
		(end 214.064596 -68.079112)
		(width 0.1016)
		(layer "In5.Cu")
		(net "PHY_IOC_TO_CON_B_0_DP")
	)
	(segment
		(start 161.892742 -26.182066)
		(end 162.141916 -26.315416)
		(width 0.1016)
		(layer "In5.Cu")
		(net "PHY_IOC_TO_CON_B_0_DP")
	)
	(segment
		(start 175.063404 -33.388554)
		(end 175.116236 -33.652714)
		(width 0.1016)
		(layer "In5.Cu")
		(net "PHY_IOC_TO_CON_B_0_DP")
	)
	(segment
		(start 169.323766 -29.790898)
		(end 169.577512 -29.960062)
		(width 0.1016)
		(layer "In5.Cu")
		(net "PHY_IOC_TO_CON_B_0_DP")
	)
	(segment
		(start 175.634142 -33.768792)
		(end 175.887634 -33.937956)
		(width 0.1016)
		(layer "In5.Cu")
		(net "PHY_IOC_TO_CON_B_0_DP")
	)
	(segment
		(start 214.064596 -68.079112)
		(end 214.064596 -68.738496)
		(width 0.1016)
		(layer "In5.Cu")
		(net "PHY_IOC_TO_CON_B_0_DP")
	)
	(segment
		(start 172.897292 -32.173164)
		(end 173.161452 -32.120332)
		(width 0.1016)
		(layer "In5.Cu")
		(net "PHY_IOC_TO_CON_B_0_DP")
	)
	(segment
		(start 168.499536 -29.241242)
		(end 168.753282 -29.410406)
		(width 0.1016)
		(layer "In5.Cu")
		(net "PHY_IOC_TO_CON_B_0_DP")
	)
	(segment
		(start 166.544752 -27.709114)
		(end 168.446704 -28.977082)
		(width 0.1016)
		(layer "In5.Cu")
		(net "PHY_IOC_TO_CON_B_0_DP")
	)
	(segment
		(start 165.05047 -27.604466)
		(end 165.274498 -27.455114)
		(width 0.1016)
		(layer "In5.Cu")
		(net "PHY_IOC_TO_CON_B_0_DP")
	)
	(segment
		(start 174.239174 -32.838898)
		(end 174.292006 -33.103058)
		(width 0.1016)
		(layer "In5.Cu")
		(net "PHY_IOC_TO_CON_B_0_DP")
	)
	(segment
		(start 174.545752 -33.272222)
		(end 174.809912 -33.21939)
		(width 0.1016)
		(layer "In5.Cu")
		(net "PHY_IOC_TO_CON_B_0_DP")
	)
	(segment
		(start 175.116236 -33.652714)
		(end 175.369728 -33.821624)
		(width 0.1016)
		(layer "In5.Cu")
		(net "PHY_IOC_TO_CON_B_0_DP")
	)
	(segment
		(start 173.467776 -32.553656)
		(end 173.721522 -32.72282)
		(width 0.1016)
		(layer "In5.Cu")
		(net "PHY_IOC_TO_CON_B_0_DP")
	)
	(segment
		(start 173.414944 -32.289496)
		(end 173.467776 -32.553656)
		(width 0.1016)
		(layer "In5.Cu")
		(net "PHY_IOC_TO_CON_B_0_DP")
	)
	(segment
		(start 169.577512 -29.960062)
		(end 169.841672 -29.90723)
		(width 0.1016)
		(layer "In5.Cu")
		(net "PHY_IOC_TO_CON_B_0_DP")
	)
	(segment
		(start 214.388954 -69.329046)
		(end 214.225886 -69.492114)
		(width 0.1016)
		(layer "In5.Cu")
		(net "PHY_IOC_TO_CON_B_0_DP")
	)
	(segment
		(start 161.500058 -26.699972)
		(end 161.755328 -26.223468)
		(width 0.1016)
		(layer "In5.Cu")
		(net "PHY_IOC_TO_CON_B_0_DP")
	)
	(segment
		(start 164.303202 -27.260804)
		(end 164.60216 -27.320494)
		(width 0.1016)
		(layer "In5.Cu")
		(net "PHY_IOC_TO_CON_B_0_DP")
	)
	(segment
		(start 163.780216 -27.350466)
		(end 164.07892 -27.410156)
		(width 0.1016)
		(layer "In5.Cu")
		(net "PHY_IOC_TO_CON_B_0_DP")
	)
	(segment
		(start 169.017442 -29.357574)
		(end 169.270934 -29.526738)
		(width 0.1016)
		(layer "In5.Cu")
		(net "PHY_IOC_TO_CON_B_0_DP")
	)
	(segment
		(start 162.141916 -26.315416)
		(end 162.536124 -26.907236)
		(width 0.1016)
		(layer "In5.Cu")
		(net "PHY_IOC_TO_CON_B_0_DP")
	)
	(segment
		(start 217.291412 -55.672482)
		(end 214.996268 -67.14744)
		(width 0.1016)
		(layer "In5.Cu")
		(net "PHY_IOC_TO_CON_B_0_DP")
	)
	(segment
		(start 172.590714 -31.73984)
		(end 172.643546 -32.004254)
		(width 0.1016)
		(layer "In5.Cu")
		(net "PHY_IOC_TO_CON_B_0_DP")
	)
	(segment
		(start 207.605884 -40.277542)
		(end 213.60257 -44.274994)
		(width 0.1016)
		(layer "In5.Cu")
		(net "PHY_IOC_TO_CON_B_0_DP")
	)
	(segment
		(start 174.809912 -33.21939)
		(end 175.063404 -33.388554)
		(width 0.1016)
		(layer "In5.Cu")
		(net "PHY_IOC_TO_CON_B_0_DP")
	)
	(segment
		(start 164.07892 -27.410156)
		(end 164.303202 -27.260804)
		(width 0.1016)
		(layer "In5.Cu")
		(net "PHY_IOC_TO_CON_B_0_DP")
	)
	(segment
		(start 213.60257 -44.274994)
		(end 215.616028 -47.295308)
		(width 0.1016)
		(layer "In5.Cu")
		(net "PHY_IOC_TO_CON_B_0_DP")
	)
	(segment
		(start 169.841672 -29.90723)
		(end 172.590714 -31.73984)
		(width 0.1016)
		(layer "In5.Cu")
		(net "PHY_IOC_TO_CON_B_0_DP")
	)
	(segment
		(start 165.573456 -27.514804)
		(end 165.722808 -27.739086)
		(width 0.1016)
		(layer "In5.Cu")
		(net "PHY_IOC_TO_CON_B_0_DP")
	)
	(segment
		(start 168.753282 -29.410406)
		(end 169.017442 -29.357574)
		(width 0.1016)
		(layer "In5.Cu")
		(net "PHY_IOC_TO_CON_B_0_DP")
	)
	(segment
		(start 168.446704 -28.977082)
		(end 168.499536 -29.241242)
		(width 0.1016)
		(layer "In5.Cu")
		(net "PHY_IOC_TO_CON_B_0_DP")
	)
	(segment
		(start 164.751512 -27.544776)
		(end 165.05047 -27.604466)
		(width 0.1016)
		(layer "In5.Cu")
		(net "PHY_IOC_TO_CON_B_0_DP")
	)
	(segment
		(start 166.245794 -27.649424)
		(end 166.544752 -27.709114)
		(width 0.1016)
		(layer "In5.Cu")
		(net "PHY_IOC_TO_CON_B_0_DP")
	)
	(segment
		(start 173.985682 -32.669988)
		(end 174.239174 -32.838898)
		(width 0.1016)
		(layer "In5.Cu")
		(net "PHY_IOC_TO_CON_B_0_DP")
	)
	(segment
		(start 162.536124 -26.907236)
		(end 163.63061 -27.126184)
		(width 0.1016)
		(layer "In5.Cu")
		(net "PHY_IOC_TO_CON_B_0_DP")
	)
	(segment
		(start 173.721522 -32.72282)
		(end 173.985682 -32.669988)
		(width 0.1016)
		(layer "In5.Cu")
		(net "PHY_IOC_TO_CON_B_0_DP")
	)
	(segment
		(start 165.722808 -27.739086)
		(end 166.021766 -27.798776)
		(width 0.1016)
		(layer "In5.Cu")
		(net "PHY_IOC_TO_CON_B_0_DP")
	)
	(segment
		(start 164.60216 -27.320494)
		(end 164.751512 -27.544776)
		(width 0.1016)
		(layer "In5.Cu")
		(net "PHY_IOC_TO_CON_B_0_DP")
	)
	(segment
		(start 173.161452 -32.120332)
		(end 173.414944 -32.289496)
		(width 0.1016)
		(layer "In5.Cu")
		(net "PHY_IOC_TO_CON_B_0_DP")
	)
	(segment
		(start 165.274498 -27.455114)
		(end 165.573456 -27.514804)
		(width 0.1016)
		(layer "In5.Cu")
		(net "PHY_IOC_TO_CON_B_0_DP")
	)
	(segment
		(start 174.292006 -33.103058)
		(end 174.545752 -33.272222)
		(width 0.1016)
		(layer "In5.Cu")
		(net "PHY_IOC_TO_CON_B_0_DP")
	)
	(segment
		(start 214.064596 -68.738496)
		(end 214.388954 -69.062854)
		(width 0.1016)
		(layer "In5.Cu")
		(net "PHY_IOC_TO_CON_B_0_DP")
	)
	(segment
		(start 172.643546 -32.004254)
		(end 172.897292 -32.173164)
		(width 0.1016)
		(layer "In5.Cu")
		(net "PHY_IOC_TO_CON_B_0_DP")
	)
	(segment
		(start 175.369728 -33.821624)
		(end 175.634142 -33.768792)
		(width 0.1016)
		(layer "In5.Cu")
		(net "PHY_IOC_TO_CON_B_0_DP")
	)
	(segment
		(start 166.021766 -27.798776)
		(end 166.245794 -27.649424)
		(width 0.1016)
		(layer "In5.Cu")
		(net "PHY_IOC_TO_CON_B_0_DP")
	)
	(arc
		(start 214.388954 -69.062854)
		(mid 214.444084 -69.19595)
		(end 214.388954 -69.329046)
		(width 0.1016)
		(layer "In5.Cu")
		(net "PHY_IOC_TO_CON_B_0_DP")
	)
	(segment
		(start 206.996284 -69.535294)
		(end 207.684878 -69.535294)
		(width 0.12446)
		(layer "F.Cu")
		(net "PHY_IOC_TO_CON_B_0_DN_C")
	)
	(segment
		(start 206.542894 -69.988938)
		(end 206.996284 -69.535294)
		(width 0.12446)
		(layer "F.Cu")
		(net "PHY_IOC_TO_CON_B_0_DN_C")
	)
	(segment
		(start 203.94422 -69.89318)
		(end 204.568044 -69.89318)
		(width 0.12446)
		(layer "F.Cu")
		(net "PHY_IOC_TO_CON_B_0_DN_C")
	)
	(segment
		(start 203.60005 -70.23735)
		(end 203.94422 -69.89318)
		(width 0.12446)
		(layer "F.Cu")
		(net "PHY_IOC_TO_CON_B_0_DN_C")
	)
	(segment
		(start 204.663802 -69.988938)
		(end 206.542894 -69.988938)
		(width 0.12446)
		(layer "F.Cu")
		(net "PHY_IOC_TO_CON_B_0_DN_C")
	)
	(segment
		(start 203.60005 -70.299834)
		(end 203.60005 -70.23735)
		(width 0.12446)
		(layer "F.Cu")
		(net "PHY_IOC_TO_CON_B_0_DN_C")
	)
	(segment
		(start 207.684878 -69.535294)
		(end 207.776572 -69.4436)
		(width 0.12446)
		(layer "F.Cu")
		(net "PHY_IOC_TO_CON_B_0_DN_C")
	)
	(segment
		(start 204.568044 -69.89318)
		(end 204.663802 -69.988938)
		(width 0.12446)
		(layer "F.Cu")
		(net "PHY_IOC_TO_CON_B_0_DN_C")
	)
	(segment
		(start 214.901018 -68.816982)
		(end 215.034114 -68.683886)
		(width 0.12446)
		(layer "F.Cu")
		(net "PHY_IOC_TO_CON_B_0_DN")
	)
	(segment
		(start 208.335372 -69.4436)
		(end 208.386172 -69.4944)
		(width 0.12446)
		(layer "F.Cu")
		(net "PHY_IOC_TO_CON_B_0_DN")
	)
	(segment
		(start 212.403944 -69.4944)
		(end 213.421976 -68.476368)
		(width 0.12446)
		(layer "F.Cu")
		(net "PHY_IOC_TO_CON_B_0_DN")
	)
	(segment
		(start 214.306404 -68.476368)
		(end 214.647018 -68.816982)
		(width 0.12446)
		(layer "F.Cu")
		(net "PHY_IOC_TO_CON_B_0_DN")
	)
	(segment
		(start 213.421976 -68.476368)
		(end 214.306404 -68.476368)
		(width 0.12446)
		(layer "F.Cu")
		(net "PHY_IOC_TO_CON_B_0_DN")
	)
	(segment
		(start 208.386172 -69.4944)
		(end 212.403944 -69.4944)
		(width 0.12446)
		(layer "F.Cu")
		(net "PHY_IOC_TO_CON_B_0_DN")
	)
	(arc
		(start 214.647018 -68.816982)
		(mid 214.774018 -68.869587)
		(end 214.901018 -68.816982)
		(width 0.12446)
		(layer "F.Cu")
		(net "PHY_IOC_TO_CON_B_0_DN")
	)
	(segment
		(start 161.995104 -25.77592)
		(end 162.037014 -25.913334)
		(width 0.1016)
		(layer "In5.Cu")
		(net "PHY_IOC_TO_CON_B_0_DN")
	)
	(segment
		(start 166.663878 -27.42184)
		(end 176.006506 -33.650682)
		(width 0.1016)
		(layer "In5.Cu")
		(net "PHY_IOC_TO_CON_B_0_DN")
	)
	(segment
		(start 215.903302 -47.176436)
		(end 217.602308 -55.672482)
		(width 0.1016)
		(layer "In5.Cu")
		(net "PHY_IOC_TO_CON_B_0_DN")
	)
	(segment
		(start 214.870792 -68.847208)
		(end 215.034114 -68.683886)
		(width 0.1016)
		(layer "In5.Cu")
		(net "PHY_IOC_TO_CON_B_0_DN")
	)
	(segment
		(start 214.863172 -45.61586)
		(end 215.903302 -47.176436)
		(width 0.1016)
		(layer "In5.Cu")
		(net "PHY_IOC_TO_CON_B_0_DN")
	)
	(segment
		(start 162.25012 -25.299924)
		(end 161.995104 -25.77592)
		(width 0.1016)
		(layer "In5.Cu")
		(net "PHY_IOC_TO_CON_B_0_DN")
	)
	(segment
		(start 214.369396 -68.205604)
		(end 214.369396 -68.612004)
		(width 0.1016)
		(layer "In5.Cu")
		(net "PHY_IOC_TO_CON_B_0_DN")
	)
	(segment
		(start 176.006506 -33.650682)
		(end 207.724756 -39.990268)
		(width 0.1016)
		(layer "In5.Cu")
		(net "PHY_IOC_TO_CON_B_0_DN")
	)
	(segment
		(start 214.369396 -68.612004)
		(end 214.6046 -68.847208)
		(width 0.1016)
		(layer "In5.Cu")
		(net "PHY_IOC_TO_CON_B_0_DN")
	)
	(segment
		(start 215.277192 -67.297808)
		(end 214.369396 -68.205604)
		(width 0.1016)
		(layer "In5.Cu")
		(net "PHY_IOC_TO_CON_B_0_DN")
	)
	(segment
		(start 162.72002 -26.632916)
		(end 166.663878 -27.42184)
		(width 0.1016)
		(layer "In5.Cu")
		(net "PHY_IOC_TO_CON_B_0_DN")
	)
	(segment
		(start 162.037014 -25.913334)
		(end 162.353244 -26.082244)
		(width 0.1016)
		(layer "In5.Cu")
		(net "PHY_IOC_TO_CON_B_0_DN")
	)
	(segment
		(start 162.353244 -26.082244)
		(end 162.72002 -26.632916)
		(width 0.1016)
		(layer "In5.Cu")
		(net "PHY_IOC_TO_CON_B_0_DN")
	)
	(segment
		(start 217.602308 -55.672482)
		(end 215.277192 -67.297808)
		(width 0.1016)
		(layer "In5.Cu")
		(net "PHY_IOC_TO_CON_B_0_DN")
	)
	(segment
		(start 207.724756 -39.990268)
		(end 213.822534 -44.05503)
		(width 0.1016)
		(layer "In5.Cu")
		(net "PHY_IOC_TO_CON_B_0_DN")
	)
	(segment
		(start 214.862918 -45.61586)
		(end 214.863172 -45.61586)
		(width 0.1016)
		(layer "In5.Cu")
		(net "PHY_IOC_TO_CON_B_0_DN")
	)
	(segment
		(start 213.822534 -44.05503)
		(end 214.862918 -45.61586)
		(width 0.1016)
		(layer "In5.Cu")
		(net "PHY_IOC_TO_CON_B_0_DN")
	)
	(arc
		(start 214.6046 -68.847208)
		(mid 214.737696 -68.902338)
		(end 214.870792 -68.847208)
		(width 0.1016)
		(layer "In5.Cu")
		(net "PHY_IOC_TO_CON_B_0_DN")
	)
	(segment
		(start 206.902558 -71.982076)
		(end 204.727302 -71.982076)
		(width 0.12446)
		(layer "F.Cu")
		(net "PHY_IOC_TO_CON_A_3_DP_C")
	)
	(segment
		(start 207.668622 -71.57085)
		(end 207.313784 -71.57085)
		(width 0.12446)
		(layer "F.Cu")
		(net "PHY_IOC_TO_CON_A_3_DP_C")
	)
	(segment
		(start 207.313784 -71.57085)
		(end 206.902558 -71.982076)
		(width 0.12446)
		(layer "F.Cu")
		(net "PHY_IOC_TO_CON_A_3_DP_C")
	)
	(segment
		(start 207.776572 -71.6788)
		(end 207.668622 -71.57085)
		(width 0.12446)
		(layer "F.Cu")
		(net "PHY_IOC_TO_CON_A_3_DP_C")
	)
	(segment
		(start 204.64526 -71.900034)
		(end 204.399896 -71.900034)
		(width 0.12446)
		(layer "F.Cu")
		(net "PHY_IOC_TO_CON_A_3_DP_C")
	)
	(segment
		(start 204.727302 -71.982076)
		(end 204.64526 -71.900034)
		(width 0.12446)
		(layer "F.Cu")
		(net "PHY_IOC_TO_CON_A_3_DP_C")
	)
	(segment
		(start 213.717886 -72.794114)
		(end 213.85149 -72.66051)
		(width 0.12446)
		(layer "F.Cu")
		(net "PHY_IOC_TO_CON_A_3_DP")
	)
	(segment
		(start 213.049612 -71.604378)
		(end 208.409794 -71.604378)
		(width 0.12446)
		(layer "F.Cu")
		(net "PHY_IOC_TO_CON_A_3_DP")
	)
	(segment
		(start 208.409794 -71.604378)
		(end 208.335372 -71.6788)
		(width 0.12446)
		(layer "F.Cu")
		(net "PHY_IOC_TO_CON_A_3_DP")
	)
	(segment
		(start 213.85149 -72.406256)
		(end 213.049612 -71.604378)
		(width 0.12446)
		(layer "F.Cu")
		(net "PHY_IOC_TO_CON_A_3_DP")
	)
	(arc
		(start 213.85149 -72.66051)
		(mid 213.904095 -72.53342)
		(end 213.85149 -72.406256)
		(width 0.12446)
		(layer "F.Cu")
		(net "PHY_IOC_TO_CON_A_3_DP")
	)
	(segment
		(start 216.32545 -68.612258)
		(end 213.556596 -71.381112)
		(width 0.1016)
		(layer "In5.Cu")
		(net "PHY_IOC_TO_CON_A_3_DP")
	)
	(segment
		(start 184.789572 -34.720276)
		(end 185.013854 -34.570924)
		(width 0.1016)
		(layer "In5.Cu")
		(net "PHY_IOC_TO_CON_A_3_DP")
	)
	(segment
		(start 184.490614 -34.660586)
		(end 184.789572 -34.720276)
		(width 0.1016)
		(layer "In5.Cu")
		(net "PHY_IOC_TO_CON_A_3_DP")
	)
	(segment
		(start 206.25943 -38.819582)
		(end 206.408782 -39.043864)
		(width 0.1016)
		(layer "In5.Cu")
		(net "PHY_IOC_TO_CON_A_3_DP")
	)
	(segment
		(start 203.345288 -38.236906)
		(end 203.49464 -38.460934)
		(width 0.1016)
		(layer "In5.Cu")
		(net "PHY_IOC_TO_CON_A_3_DP")
	)
	(segment
		(start 181.24932 -31.94812)
		(end 181.464966 -32.163512)
		(width 0.1016)
		(layer "In5.Cu")
		(net "PHY_IOC_TO_CON_A_3_DP")
	)
	(segment
		(start 185.312558 -34.630614)
		(end 185.462164 -34.854642)
		(width 0.1016)
		(layer "In5.Cu")
		(net "PHY_IOC_TO_CON_A_3_DP")
	)
	(segment
		(start 204.017626 -38.371272)
		(end 204.316584 -38.431216)
		(width 0.1016)
		(layer "In5.Cu")
		(net "PHY_IOC_TO_CON_A_3_DP")
	)
	(segment
		(start 213.880954 -72.631046)
		(end 213.717886 -72.794114)
		(width 0.1016)
		(layer "In5.Cu")
		(net "PHY_IOC_TO_CON_A_3_DP")
	)
	(segment
		(start 205.437486 -38.849554)
		(end 205.736444 -38.909244)
		(width 0.1016)
		(layer "In5.Cu")
		(net "PHY_IOC_TO_CON_A_3_DP")
	)
	(segment
		(start 216.666064 -47.026068)
		(end 218.653868 -56.968898)
		(width 0.1016)
		(layer "In5.Cu")
		(net "PHY_IOC_TO_CON_A_3_DP")
	)
	(segment
		(start 204.989176 -38.565582)
		(end 205.28788 -38.625272)
		(width 0.1016)
		(layer "In5.Cu")
		(net "PHY_IOC_TO_CON_A_3_DP")
	)
	(segment
		(start 180.764434 -31.732474)
		(end 180.98008 -31.94812)
		(width 0.1016)
		(layer "In5.Cu")
		(net "PHY_IOC_TO_CON_A_3_DP")
	)
	(segment
		(start 205.28788 -38.625272)
		(end 205.437486 -38.849554)
		(width 0.1016)
		(layer "In5.Cu")
		(net "PHY_IOC_TO_CON_A_3_DP")
	)
	(segment
		(start 207.230726 -39.013892)
		(end 214.599774 -43.92676)
		(width 0.1016)
		(layer "In5.Cu")
		(net "PHY_IOC_TO_CON_A_3_DP")
	)
	(segment
		(start 213.556596 -72.040496)
		(end 213.880954 -72.364854)
		(width 0.1016)
		(layer "In5.Cu")
		(net "PHY_IOC_TO_CON_A_3_DP")
	)
	(segment
		(start 203.49464 -38.460934)
		(end 203.793598 -38.520878)
		(width 0.1016)
		(layer "In5.Cu")
		(net "PHY_IOC_TO_CON_A_3_DP")
	)
	(segment
		(start 179.505356 -30.023816)
		(end 179.64277 -29.982414)
		(width 0.1016)
		(layer "In5.Cu")
		(net "PHY_IOC_TO_CON_A_3_DP")
	)
	(segment
		(start 186.732418 -35.108896)
		(end 186.956446 -34.95929)
		(width 0.1016)
		(layer "In5.Cu")
		(net "PHY_IOC_TO_CON_A_3_DP")
	)
	(segment
		(start 206.408782 -39.043864)
		(end 206.70774 -39.103554)
		(width 0.1016)
		(layer "In5.Cu")
		(net "PHY_IOC_TO_CON_A_3_DP")
	)
	(segment
		(start 185.013854 -34.570924)
		(end 185.312558 -34.630614)
		(width 0.1016)
		(layer "In5.Cu")
		(net "PHY_IOC_TO_CON_A_3_DP")
	)
	(segment
		(start 205.960472 -38.759892)
		(end 206.25943 -38.819582)
		(width 0.1016)
		(layer "In5.Cu")
		(net "PHY_IOC_TO_CON_A_3_DP")
	)
	(segment
		(start 186.956446 -34.95929)
		(end 203.345288 -38.236906)
		(width 0.1016)
		(layer "In5.Cu")
		(net "PHY_IOC_TO_CON_A_3_DP")
	)
	(segment
		(start 206.931768 -38.954202)
		(end 207.230726 -39.013892)
		(width 0.1016)
		(layer "In5.Cu")
		(net "PHY_IOC_TO_CON_A_3_DP")
	)
	(segment
		(start 213.556596 -71.381112)
		(end 213.556596 -72.040496)
		(width 0.1016)
		(layer "In5.Cu")
		(net "PHY_IOC_TO_CON_A_3_DP")
	)
	(segment
		(start 179.90439 -30.602936)
		(end 180.764434 -31.46298)
		(width 0.1016)
		(layer "In5.Cu")
		(net "PHY_IOC_TO_CON_A_3_DP")
	)
	(segment
		(start 179.250086 -30.500066)
		(end 179.505356 -30.023816)
		(width 0.1016)
		(layer "In5.Cu")
		(net "PHY_IOC_TO_CON_A_3_DP")
	)
	(segment
		(start 204.46619 -38.655244)
		(end 204.764894 -38.714934)
		(width 0.1016)
		(layer "In5.Cu")
		(net "PHY_IOC_TO_CON_A_3_DP")
	)
	(segment
		(start 203.793598 -38.520878)
		(end 204.017626 -38.371272)
		(width 0.1016)
		(layer "In5.Cu")
		(net "PHY_IOC_TO_CON_A_3_DP")
	)
	(segment
		(start 185.462164 -34.854642)
		(end 185.760868 -34.914586)
		(width 0.1016)
		(layer "In5.Cu")
		(net "PHY_IOC_TO_CON_A_3_DP")
	)
	(segment
		(start 183.586882 -34.285682)
		(end 184.341262 -34.436304)
		(width 0.1016)
		(layer "In5.Cu")
		(net "PHY_IOC_TO_CON_A_3_DP")
	)
	(segment
		(start 181.680358 -32.648398)
		(end 181.949852 -32.648398)
		(width 0.1016)
		(layer "In5.Cu")
		(net "PHY_IOC_TO_CON_A_3_DP")
	)
	(segment
		(start 185.760868 -34.914586)
		(end 185.98515 -34.76498)
		(width 0.1016)
		(layer "In5.Cu")
		(net "PHY_IOC_TO_CON_A_3_DP")
	)
	(segment
		(start 204.764894 -38.714934)
		(end 204.989176 -38.565582)
		(width 0.1016)
		(layer "In5.Cu")
		(net "PHY_IOC_TO_CON_A_3_DP")
	)
	(segment
		(start 181.949852 -32.648398)
		(end 183.586882 -34.285682)
		(width 0.1016)
		(layer "In5.Cu")
		(net "PHY_IOC_TO_CON_A_3_DP")
	)
	(segment
		(start 185.98515 -34.76498)
		(end 186.284108 -34.824924)
		(width 0.1016)
		(layer "In5.Cu")
		(net "PHY_IOC_TO_CON_A_3_DP")
	)
	(segment
		(start 179.64277 -29.982414)
		(end 179.732686 -30.030674)
		(width 0.1016)
		(layer "In5.Cu")
		(net "PHY_IOC_TO_CON_A_3_DP")
	)
	(segment
		(start 186.43346 -35.048952)
		(end 186.732418 -35.108896)
		(width 0.1016)
		(layer "In5.Cu")
		(net "PHY_IOC_TO_CON_A_3_DP")
	)
	(segment
		(start 180.98008 -31.94812)
		(end 181.24932 -31.94812)
		(width 0.1016)
		(layer "In5.Cu")
		(net "PHY_IOC_TO_CON_A_3_DP")
	)
	(segment
		(start 218.653868 -56.968898)
		(end 216.32545 -68.612258)
		(width 0.1016)
		(layer "In5.Cu")
		(net "PHY_IOC_TO_CON_A_3_DP")
	)
	(segment
		(start 214.599774 -43.92676)
		(end 216.666064 -47.026068)
		(width 0.1016)
		(layer "In5.Cu")
		(net "PHY_IOC_TO_CON_A_3_DP")
	)
	(segment
		(start 205.736444 -38.909244)
		(end 205.960472 -38.759892)
		(width 0.1016)
		(layer "In5.Cu")
		(net "PHY_IOC_TO_CON_A_3_DP")
	)
	(segment
		(start 206.70774 -39.103554)
		(end 206.931768 -38.954202)
		(width 0.1016)
		(layer "In5.Cu")
		(net "PHY_IOC_TO_CON_A_3_DP")
	)
	(segment
		(start 179.732686 -30.030674)
		(end 179.90439 -30.202124)
		(width 0.1016)
		(layer "In5.Cu")
		(net "PHY_IOC_TO_CON_A_3_DP")
	)
	(segment
		(start 184.341262 -34.436304)
		(end 184.490614 -34.660586)
		(width 0.1016)
		(layer "In5.Cu")
		(net "PHY_IOC_TO_CON_A_3_DP")
	)
	(segment
		(start 180.764434 -31.46298)
		(end 180.764434 -31.732474)
		(width 0.1016)
		(layer "In5.Cu")
		(net "PHY_IOC_TO_CON_A_3_DP")
	)
	(segment
		(start 204.316584 -38.431216)
		(end 204.46619 -38.655244)
		(width 0.1016)
		(layer "In5.Cu")
		(net "PHY_IOC_TO_CON_A_3_DP")
	)
	(segment
		(start 179.90439 -30.202124)
		(end 179.90439 -30.602936)
		(width 0.1016)
		(layer "In5.Cu")
		(net "PHY_IOC_TO_CON_A_3_DP")
	)
	(segment
		(start 181.464966 -32.163512)
		(end 181.464966 -32.433006)
		(width 0.1016)
		(layer "In5.Cu")
		(net "PHY_IOC_TO_CON_A_3_DP")
	)
	(segment
		(start 186.284108 -34.824924)
		(end 186.43346 -35.048952)
		(width 0.1016)
		(layer "In5.Cu")
		(net "PHY_IOC_TO_CON_A_3_DP")
	)
	(segment
		(start 181.464966 -32.433006)
		(end 181.680358 -32.648398)
		(width 0.1016)
		(layer "In5.Cu")
		(net "PHY_IOC_TO_CON_A_3_DP")
	)
	(arc
		(start 213.880954 -72.364854)
		(mid 213.936084 -72.49795)
		(end 213.880954 -72.631046)
		(width 0.1016)
		(layer "In5.Cu")
		(net "PHY_IOC_TO_CON_A_3_DP")
	)
	(segment
		(start 203.60005 -71.81215)
		(end 203.91882 -71.49338)
		(width 0.12446)
		(layer "F.Cu")
		(net "PHY_IOC_TO_CON_A_3_DN_C")
	)
	(segment
		(start 207.145636 -71.164196)
		(end 207.732376 -71.164196)
		(width 0.12446)
		(layer "F.Cu")
		(net "PHY_IOC_TO_CON_A_3_DN_C")
	)
	(segment
		(start 203.60005 -71.900034)
		(end 203.60005 -71.81215)
		(width 0.12446)
		(layer "F.Cu")
		(net "PHY_IOC_TO_CON_A_3_DN_C")
	)
	(segment
		(start 204.895704 -71.575676)
		(end 206.734156 -71.575676)
		(width 0.12446)
		(layer "F.Cu")
		(net "PHY_IOC_TO_CON_A_3_DN_C")
	)
	(segment
		(start 207.732376 -71.164196)
		(end 207.776572 -71.12)
		(width 0.12446)
		(layer "F.Cu")
		(net "PHY_IOC_TO_CON_A_3_DN_C")
	)
	(segment
		(start 203.91882 -71.49338)
		(end 204.813408 -71.49338)
		(width 0.12446)
		(layer "F.Cu")
		(net "PHY_IOC_TO_CON_A_3_DN_C")
	)
	(segment
		(start 204.813408 -71.49338)
		(end 204.895704 -71.575676)
		(width 0.12446)
		(layer "F.Cu")
		(net "PHY_IOC_TO_CON_A_3_DN_C")
	)
	(segment
		(start 206.734156 -71.575676)
		(end 207.145636 -71.164196)
		(width 0.12446)
		(layer "F.Cu")
		(net "PHY_IOC_TO_CON_A_3_DN_C")
	)
	(segment
		(start 214.526114 -71.985886)
		(end 214.393018 -72.118982)
		(width 0.12446)
		(layer "F.Cu")
		(net "PHY_IOC_TO_CON_A_3_DN")
	)
	(segment
		(start 208.41335 -71.197978)
		(end 208.335372 -71.12)
		(width 0.12446)
		(layer "F.Cu")
		(net "PHY_IOC_TO_CON_A_3_DN")
	)
	(segment
		(start 213.218014 -71.197978)
		(end 208.41335 -71.197978)
		(width 0.12446)
		(layer "F.Cu")
		(net "PHY_IOC_TO_CON_A_3_DN")
	)
	(segment
		(start 214.139018 -72.118982)
		(end 213.218014 -71.197978)
		(width 0.12446)
		(layer "F.Cu")
		(net "PHY_IOC_TO_CON_A_3_DN")
	)
	(arc
		(start 214.393018 -72.118982)
		(mid 214.266018 -72.171587)
		(end 214.139018 -72.118982)
		(width 0.12446)
		(layer "F.Cu")
		(net "PHY_IOC_TO_CON_A_3_DN")
	)
	(segment
		(start 214.819738 -43.706796)
		(end 216.953338 -46.907196)
		(width 0.1016)
		(layer "In5.Cu")
		(net "PHY_IOC_TO_CON_A_3_DN")
	)
	(segment
		(start 213.861396 -71.914004)
		(end 214.0966 -72.149208)
		(width 0.1016)
		(layer "In5.Cu")
		(net "PHY_IOC_TO_CON_A_3_DN")
	)
	(segment
		(start 180.20919 -30.075632)
		(end 180.20919 -30.476444)
		(width 0.1016)
		(layer "In5.Cu")
		(net "PHY_IOC_TO_CON_A_3_DN")
	)
	(segment
		(start 214.362792 -72.149208)
		(end 214.526114 -71.985886)
		(width 0.1016)
		(layer "In5.Cu")
		(net "PHY_IOC_TO_CON_A_3_DN")
	)
	(segment
		(start 183.73725 -34.004504)
		(end 207.349852 -38.726618)
		(width 0.1016)
		(layer "In5.Cu")
		(net "PHY_IOC_TO_CON_A_3_DN")
	)
	(segment
		(start 207.349852 -38.726618)
		(end 214.819738 -43.706796)
		(width 0.1016)
		(layer "In5.Cu")
		(net "PHY_IOC_TO_CON_A_3_DN")
	)
	(segment
		(start 216.606374 -68.762626)
		(end 213.861396 -71.507604)
		(width 0.1016)
		(layer "In5.Cu")
		(net "PHY_IOC_TO_CON_A_3_DN")
	)
	(segment
		(start 218.964764 -56.968898)
		(end 216.606374 -68.762626)
		(width 0.1016)
		(layer "In5.Cu")
		(net "PHY_IOC_TO_CON_A_3_DN")
	)
	(segment
		(start 179.916328 -29.78277)
		(end 180.20919 -30.075632)
		(width 0.1016)
		(layer "In5.Cu")
		(net "PHY_IOC_TO_CON_A_3_DN")
	)
	(segment
		(start 179.744878 -29.576268)
		(end 179.786788 -29.713682)
		(width 0.1016)
		(layer "In5.Cu")
		(net "PHY_IOC_TO_CON_A_3_DN")
	)
	(segment
		(start 180.20919 -30.476444)
		(end 183.73725 -34.004504)
		(width 0.1016)
		(layer "In5.Cu")
		(net "PHY_IOC_TO_CON_A_3_DN")
	)
	(segment
		(start 216.953338 -46.907196)
		(end 218.964764 -56.968898)
		(width 0.1016)
		(layer "In5.Cu")
		(net "PHY_IOC_TO_CON_A_3_DN")
	)
	(segment
		(start 179.999894 -29.100018)
		(end 179.744878 -29.576268)
		(width 0.1016)
		(layer "In5.Cu")
		(net "PHY_IOC_TO_CON_A_3_DN")
	)
	(segment
		(start 179.786788 -29.713682)
		(end 179.916328 -29.78277)
		(width 0.1016)
		(layer "In5.Cu")
		(net "PHY_IOC_TO_CON_A_3_DN")
	)
	(segment
		(start 213.861396 -71.507604)
		(end 213.861396 -71.914004)
		(width 0.1016)
		(layer "In5.Cu")
		(net "PHY_IOC_TO_CON_A_3_DN")
	)
	(arc
		(start 214.0966 -72.149208)
		(mid 214.229696 -72.204338)
		(end 214.362792 -72.149208)
		(width 0.1016)
		(layer "In5.Cu")
		(net "PHY_IOC_TO_CON_A_3_DN")
	)
	(segment
		(start 205.493366 -72.69988)
		(end 204.399896 -72.69988)
		(width 0.12446)
		(layer "F.Cu")
		(net "PHY_IOC_TO_CON_A_2_DP_C")
	)
	(segment
		(start 206.078074 -73.284588)
		(end 205.493366 -72.69988)
		(width 0.12446)
		(layer "F.Cu")
		(net "PHY_IOC_TO_CON_A_2_DP_C")
	)
	(segment
		(start 207.70596 -73.284588)
		(end 206.078074 -73.284588)
		(width 0.12446)
		(layer "F.Cu")
		(net "PHY_IOC_TO_CON_A_2_DP_C")
	)
	(segment
		(start 207.776572 -73.3552)
		(end 207.70596 -73.284588)
		(width 0.12446)
		(layer "F.Cu")
		(net "PHY_IOC_TO_CON_A_2_DP_C")
	)
	(segment
		(start 215.248744 -73.80351)
		(end 215.027002 -73.581768)
		(width 0.12446)
		(layer "F.Cu")
		(net "PHY_IOC_TO_CON_A_2_DP")
	)
	(segment
		(start 212.09 -74.7268)
		(end 210.643216 -73.280016)
		(width 0.12446)
		(layer "F.Cu")
		(net "PHY_IOC_TO_CON_A_2_DP")
	)
	(segment
		(start 208.410556 -73.280016)
		(end 208.335372 -73.3552)
		(width 0.12446)
		(layer "F.Cu")
		(net "PHY_IOC_TO_CON_A_2_DP")
	)
	(segment
		(start 214.682832 -73.581768)
		(end 213.5378 -74.7268)
		(width 0.12446)
		(layer "F.Cu")
		(net "PHY_IOC_TO_CON_A_2_DP")
	)
	(segment
		(start 215.027002 -73.581768)
		(end 214.682832 -73.581768)
		(width 0.12446)
		(layer "F.Cu")
		(net "PHY_IOC_TO_CON_A_2_DP")
	)
	(segment
		(start 210.643216 -73.280016)
		(end 208.410556 -73.280016)
		(width 0.12446)
		(layer "F.Cu")
		(net "PHY_IOC_TO_CON_A_2_DP")
	)
	(segment
		(start 213.5378 -74.7268)
		(end 212.09 -74.7268)
		(width 0.12446)
		(layer "F.Cu")
		(net "PHY_IOC_TO_CON_A_2_DP")
	)
	(segment
		(start 215.114886 -74.191114)
		(end 215.248744 -74.057256)
		(width 0.12446)
		(layer "F.Cu")
		(net "PHY_IOC_TO_CON_A_2_DP")
	)
	(arc
		(start 215.248744 -74.057256)
		(mid 215.301244 -73.93042)
		(end 215.248744 -73.80351)
		(width 0.12446)
		(layer "F.Cu")
		(net "PHY_IOC_TO_CON_A_2_DP")
	)
	(segment
		(start 216.885012 -70.446138)
		(end 216.185496 -71.495412)
		(width 0.1016)
		(layer "In5.Cu")
		(net "PHY_IOC_TO_CON_A_2_DP")
	)
	(segment
		(start 189.697106 -34.521902)
		(end 189.99581 -34.581592)
		(width 0.1016)
		(layer "In5.Cu")
		(net "PHY_IOC_TO_CON_A_2_DP")
	)
	(segment
		(start 190.668402 -34.715958)
		(end 190.96736 -34.775902)
		(width 0.1016)
		(layer "In5.Cu")
		(net "PHY_IOC_TO_CON_A_2_DP")
	)
	(segment
		(start 181.97703 -30.027118)
		(end 181.977792 -30.027626)
		(width 0.1016)
		(layer "In5.Cu")
		(net "PHY_IOC_TO_CON_A_2_DP")
	)
	(segment
		(start 184.285382 -31.820612)
		(end 187.75426 -34.133282)
		(width 0.1016)
		(layer "In5.Cu")
		(net "PHY_IOC_TO_CON_A_2_DP")
	)
	(segment
		(start 189.99581 -34.581592)
		(end 190.145416 -34.80562)
		(width 0.1016)
		(layer "In5.Cu")
		(net "PHY_IOC_TO_CON_A_2_DP")
	)
	(segment
		(start 205.729078 -37.9222)
		(end 205.953106 -37.772848)
		(width 0.1016)
		(layer "In5.Cu")
		(net "PHY_IOC_TO_CON_A_2_DP")
	)
	(segment
		(start 214.953596 -73.437496)
		(end 215.277954 -73.761854)
		(width 0.1016)
		(layer "In5.Cu")
		(net "PHY_IOC_TO_CON_A_2_DP")
	)
	(segment
		(start 188.20257 -34.417254)
		(end 188.501528 -34.476944)
		(width 0.1016)
		(layer "In5.Cu")
		(net "PHY_IOC_TO_CON_A_2_DP")
	)
	(segment
		(start 183.767476 -31.704534)
		(end 184.021222 -31.873444)
		(width 0.1016)
		(layer "In5.Cu")
		(net "PHY_IOC_TO_CON_A_2_DP")
	)
	(segment
		(start 206.700374 -38.11651)
		(end 206.924402 -37.967158)
		(width 0.1016)
		(layer "In5.Cu")
		(net "PHY_IOC_TO_CON_A_2_DP")
	)
	(segment
		(start 190.44412 -34.865564)
		(end 190.668402 -34.715958)
		(width 0.1016)
		(layer "In5.Cu")
		(net "PHY_IOC_TO_CON_A_2_DP")
	)
	(segment
		(start 204.01026 -37.384228)
		(end 204.309218 -37.444172)
		(width 0.1016)
		(layer "In5.Cu")
		(net "PHY_IOC_TO_CON_A_2_DP")
	)
	(segment
		(start 181.96306 -30.019752)
		(end 181.97703 -30.027118)
		(width 0.1016)
		(layer "In5.Cu")
		(net "PHY_IOC_TO_CON_A_2_DP")
	)
	(segment
		(start 191.41567 -35.059874)
		(end 191.639698 -34.910268)
		(width 0.1016)
		(layer "In5.Cu")
		(net "PHY_IOC_TO_CON_A_2_DP")
	)
	(segment
		(start 181.977792 -30.027626)
		(end 181.982618 -30.03042)
		(width 0.1016)
		(layer "In5.Cu")
		(net "PHY_IOC_TO_CON_A_2_DP")
	)
	(segment
		(start 206.252064 -37.832538)
		(end 206.401416 -38.05682)
		(width 0.1016)
		(layer "In5.Cu")
		(net "PHY_IOC_TO_CON_A_2_DP")
	)
	(segment
		(start 216.885012 -70.445884)
		(end 216.885012 -70.446138)
		(width 0.1016)
		(layer "In5.Cu")
		(net "PHY_IOC_TO_CON_A_2_DP")
	)
	(segment
		(start 181.958996 -30.01772)
		(end 181.96306 -30.019752)
		(width 0.1016)
		(layer "In5.Cu")
		(net "PHY_IOC_TO_CON_A_2_DP")
	)
	(segment
		(start 216.185496 -71.495412)
		(end 214.953596 -72.727312)
		(width 0.1016)
		(layer "In5.Cu")
		(net "PHY_IOC_TO_CON_A_2_DP")
	)
	(segment
		(start 188.501528 -34.476944)
		(end 188.725556 -34.327592)
		(width 0.1016)
		(layer "In5.Cu")
		(net "PHY_IOC_TO_CON_A_2_DP")
	)
	(segment
		(start 205.953106 -37.772848)
		(end 206.252064 -37.832538)
		(width 0.1016)
		(layer "In5.Cu")
		(net "PHY_IOC_TO_CON_A_2_DP")
	)
	(segment
		(start 182.748936 -30.796484)
		(end 183.714644 -31.440374)
		(width 0.1016)
		(layer "In5.Cu")
		(net "PHY_IOC_TO_CON_A_2_DP")
	)
	(segment
		(start 204.458824 -37.6682)
		(end 204.757528 -37.72789)
		(width 0.1016)
		(layer "In5.Cu")
		(net "PHY_IOC_TO_CON_A_2_DP")
	)
	(segment
		(start 205.43012 -37.86251)
		(end 205.729078 -37.9222)
		(width 0.1016)
		(layer "In5.Cu")
		(net "PHY_IOC_TO_CON_A_2_DP")
	)
	(segment
		(start 187.75426 -34.133282)
		(end 188.053218 -34.192972)
		(width 0.1016)
		(layer "In5.Cu")
		(net "PHY_IOC_TO_CON_A_2_DP")
	)
	(segment
		(start 181.892702 -29.98216)
		(end 181.893464 -29.982668)
		(width 0.1016)
		(layer "In5.Cu")
		(net "PHY_IOC_TO_CON_A_2_DP")
	)
	(segment
		(start 203.487274 -37.47389)
		(end 203.786232 -37.533834)
		(width 0.1016)
		(layer "In5.Cu")
		(net "PHY_IOC_TO_CON_A_2_DP")
	)
	(segment
		(start 203.337922 -37.249862)
		(end 203.487274 -37.47389)
		(width 0.1016)
		(layer "In5.Cu")
		(net "PHY_IOC_TO_CON_A_2_DP")
	)
	(segment
		(start 204.309218 -37.444172)
		(end 204.458824 -37.6682)
		(width 0.1016)
		(layer "In5.Cu")
		(net "PHY_IOC_TO_CON_A_2_DP")
	)
	(segment
		(start 181.893464 -29.982668)
		(end 181.958996 -30.01772)
		(width 0.1016)
		(layer "In5.Cu")
		(net "PHY_IOC_TO_CON_A_2_DP")
	)
	(segment
		(start 190.145416 -34.80562)
		(end 190.44412 -34.865564)
		(width 0.1016)
		(layer "In5.Cu")
		(net "PHY_IOC_TO_CON_A_2_DP")
	)
	(segment
		(start 191.116712 -34.99993)
		(end 191.41567 -35.059874)
		(width 0.1016)
		(layer "In5.Cu")
		(net "PHY_IOC_TO_CON_A_2_DP")
	)
	(segment
		(start 206.924402 -37.967158)
		(end 207.22336 -38.026848)
		(width 0.1016)
		(layer "In5.Cu")
		(net "PHY_IOC_TO_CON_A_2_DP")
	)
	(segment
		(start 205.280514 -37.638228)
		(end 205.43012 -37.86251)
		(width 0.1016)
		(layer "In5.Cu")
		(net "PHY_IOC_TO_CON_A_2_DP")
	)
	(segment
		(start 215.521286 -43.558714)
		(end 217.656918 -46.761908)
		(width 0.1016)
		(layer "In5.Cu")
		(net "PHY_IOC_TO_CON_A_2_DP")
	)
	(segment
		(start 181.755288 -30.023562)
		(end 181.892702 -29.98216)
		(width 0.1016)
		(layer "In5.Cu")
		(net "PHY_IOC_TO_CON_A_2_DP")
	)
	(segment
		(start 189.472824 -34.671254)
		(end 189.697106 -34.521902)
		(width 0.1016)
		(layer "In5.Cu")
		(net "PHY_IOC_TO_CON_A_2_DP")
	)
	(segment
		(start 214.953596 -72.727312)
		(end 214.953596 -73.437496)
		(width 0.1016)
		(layer "In5.Cu")
		(net "PHY_IOC_TO_CON_A_2_DP")
	)
	(segment
		(start 191.639698 -34.910268)
		(end 203.337922 -37.249862)
		(width 0.1016)
		(layer "In5.Cu")
		(net "PHY_IOC_TO_CON_A_2_DP")
	)
	(segment
		(start 184.021222 -31.873444)
		(end 184.285382 -31.820612)
		(width 0.1016)
		(layer "In5.Cu")
		(net "PHY_IOC_TO_CON_A_2_DP")
	)
	(segment
		(start 204.757528 -37.72789)
		(end 204.98181 -37.578538)
		(width 0.1016)
		(layer "In5.Cu")
		(net "PHY_IOC_TO_CON_A_2_DP")
	)
	(segment
		(start 207.22336 -38.026848)
		(end 215.521286 -43.558714)
		(width 0.1016)
		(layer "In5.Cu")
		(net "PHY_IOC_TO_CON_A_2_DP")
	)
	(segment
		(start 219.88399 -57.899554)
		(end 217.584782 -69.396356)
		(width 0.1016)
		(layer "In5.Cu")
		(net "PHY_IOC_TO_CON_A_2_DP")
	)
	(segment
		(start 183.714644 -31.440374)
		(end 183.767476 -31.704534)
		(width 0.1016)
		(layer "In5.Cu")
		(net "PHY_IOC_TO_CON_A_2_DP")
	)
	(segment
		(start 206.401416 -38.05682)
		(end 206.700374 -38.11651)
		(width 0.1016)
		(layer "In5.Cu")
		(net "PHY_IOC_TO_CON_A_2_DP")
	)
	(segment
		(start 181.982618 -30.03042)
		(end 182.748936 -30.796484)
		(width 0.1016)
		(layer "In5.Cu")
		(net "PHY_IOC_TO_CON_A_2_DP")
	)
	(segment
		(start 217.656918 -46.761908)
		(end 219.88399 -57.899554)
		(width 0.1016)
		(layer "In5.Cu")
		(net "PHY_IOC_TO_CON_A_2_DP")
	)
	(segment
		(start 181.500018 -30.500066)
		(end 181.755288 -30.023562)
		(width 0.1016)
		(layer "In5.Cu")
		(net "PHY_IOC_TO_CON_A_2_DP")
	)
	(segment
		(start 188.725556 -34.327592)
		(end 189.024514 -34.387282)
		(width 0.1016)
		(layer "In5.Cu")
		(net "PHY_IOC_TO_CON_A_2_DP")
	)
	(segment
		(start 189.024514 -34.387282)
		(end 189.173866 -34.611564)
		(width 0.1016)
		(layer "In5.Cu")
		(net "PHY_IOC_TO_CON_A_2_DP")
	)
	(segment
		(start 203.786232 -37.533834)
		(end 204.01026 -37.384228)
		(width 0.1016)
		(layer "In5.Cu")
		(net "PHY_IOC_TO_CON_A_2_DP")
	)
	(segment
		(start 204.98181 -37.578538)
		(end 205.280514 -37.638228)
		(width 0.1016)
		(layer "In5.Cu")
		(net "PHY_IOC_TO_CON_A_2_DP")
	)
	(segment
		(start 189.173866 -34.611564)
		(end 189.472824 -34.671254)
		(width 0.1016)
		(layer "In5.Cu")
		(net "PHY_IOC_TO_CON_A_2_DP")
	)
	(segment
		(start 217.584782 -69.396356)
		(end 216.885012 -70.445884)
		(width 0.1016)
		(layer "In5.Cu")
		(net "PHY_IOC_TO_CON_A_2_DP")
	)
	(segment
		(start 190.96736 -34.775902)
		(end 191.116712 -34.99993)
		(width 0.1016)
		(layer "In5.Cu")
		(net "PHY_IOC_TO_CON_A_2_DP")
	)
	(segment
		(start 215.277954 -74.028046)
		(end 215.114886 -74.191114)
		(width 0.1016)
		(layer "In5.Cu")
		(net "PHY_IOC_TO_CON_A_2_DP")
	)
	(segment
		(start 188.053218 -34.192972)
		(end 188.20257 -34.417254)
		(width 0.1016)
		(layer "In5.Cu")
		(net "PHY_IOC_TO_CON_A_2_DP")
	)
	(arc
		(start 215.277954 -73.761854)
		(mid 215.333084 -73.89495)
		(end 215.277954 -74.028046)
		(width 0.1016)
		(layer "In5.Cu")
		(net "PHY_IOC_TO_CON_A_2_DP")
	)
	(segment
		(start 206.246476 -72.878188)
		(end 207.694784 -72.878188)
		(width 0.12446)
		(layer "F.Cu")
		(net "PHY_IOC_TO_CON_A_2_DN_C")
	)
	(segment
		(start 203.60005 -72.69988)
		(end 203.60005 -72.599296)
		(width 0.12446)
		(layer "F.Cu")
		(net "PHY_IOC_TO_CON_A_2_DN_C")
	)
	(segment
		(start 205.661768 -72.29348)
		(end 206.246476 -72.878188)
		(width 0.12446)
		(layer "F.Cu")
		(net "PHY_IOC_TO_CON_A_2_DN_C")
	)
	(segment
		(start 207.694784 -72.878188)
		(end 207.776572 -72.7964)
		(width 0.12446)
		(layer "F.Cu")
		(net "PHY_IOC_TO_CON_A_2_DN_C")
	)
	(segment
		(start 203.60005 -72.599296)
		(end 203.905866 -72.29348)
		(width 0.12446)
		(layer "F.Cu")
		(net "PHY_IOC_TO_CON_A_2_DN_C")
	)
	(segment
		(start 203.905866 -72.29348)
		(end 205.661768 -72.29348)
		(width 0.12446)
		(layer "F.Cu")
		(net "PHY_IOC_TO_CON_A_2_DN_C")
	)
	(segment
		(start 208.412588 -72.873616)
		(end 208.335372 -72.7964)
		(width 0.12446)
		(layer "F.Cu")
		(net "PHY_IOC_TO_CON_A_2_DN")
	)
	(segment
		(start 210.811618 -72.873616)
		(end 208.412588 -72.873616)
		(width 0.12446)
		(layer "F.Cu")
		(net "PHY_IOC_TO_CON_A_2_DN")
	)
	(segment
		(start 215.195404 -73.175368)
		(end 214.51443 -73.175368)
		(width 0.12446)
		(layer "F.Cu")
		(net "PHY_IOC_TO_CON_A_2_DN")
	)
	(segment
		(start 213.369398 -74.3204)
		(end 212.258402 -74.3204)
		(width 0.12446)
		(layer "F.Cu")
		(net "PHY_IOC_TO_CON_A_2_DN")
	)
	(segment
		(start 215.923114 -73.382886)
		(end 215.790018 -73.515982)
		(width 0.12446)
		(layer "F.Cu")
		(net "PHY_IOC_TO_CON_A_2_DN")
	)
	(segment
		(start 212.258402 -74.3204)
		(end 210.811618 -72.873616)
		(width 0.12446)
		(layer "F.Cu")
		(net "PHY_IOC_TO_CON_A_2_DN")
	)
	(segment
		(start 215.536018 -73.515982)
		(end 215.195404 -73.175368)
		(width 0.12446)
		(layer "F.Cu")
		(net "PHY_IOC_TO_CON_A_2_DN")
	)
	(segment
		(start 214.51443 -73.175368)
		(end 213.369398 -74.3204)
		(width 0.12446)
		(layer "F.Cu")
		(net "PHY_IOC_TO_CON_A_2_DN")
	)
	(arc
		(start 215.790018 -73.515982)
		(mid 215.663018 -73.568587)
		(end 215.536018 -73.515982)
		(width 0.12446)
		(layer "F.Cu")
		(net "PHY_IOC_TO_CON_A_2_DN")
	)
	(segment
		(start 187.873132 -33.846008)
		(end 207.342232 -37.739574)
		(width 0.1016)
		(layer "In5.Cu")
		(net "PHY_IOC_TO_CON_A_2_DN")
	)
	(segment
		(start 182.102252 -29.747972)
		(end 182.10403 -29.748988)
		(width 0.1016)
		(layer "In5.Cu")
		(net "PHY_IOC_TO_CON_A_2_DN")
	)
	(segment
		(start 216.422478 -71.689722)
		(end 215.258396 -72.853804)
		(width 0.1016)
		(layer "In5.Cu")
		(net "PHY_IOC_TO_CON_A_2_DN")
	)
	(segment
		(start 215.258396 -72.853804)
		(end 215.258396 -73.311004)
		(width 0.1016)
		(layer "In5.Cu")
		(net "PHY_IOC_TO_CON_A_2_DN")
	)
	(segment
		(start 182.104792 -29.74975)
		(end 182.106062 -29.750512)
		(width 0.1016)
		(layer "In5.Cu")
		(net "PHY_IOC_TO_CON_A_2_DN")
	)
	(segment
		(start 182.103776 -29.749242)
		(end 182.104792 -29.74975)
		(width 0.1016)
		(layer "In5.Cu")
		(net "PHY_IOC_TO_CON_A_2_DN")
	)
	(segment
		(start 220.194886 -57.899554)
		(end 217.872056 -69.515482)
		(width 0.1016)
		(layer "In5.Cu")
		(net "PHY_IOC_TO_CON_A_2_DN")
	)
	(segment
		(start 182.106062 -29.750512)
		(end 182.106824 -29.75102)
		(width 0.1016)
		(layer "In5.Cu")
		(net "PHY_IOC_TO_CON_A_2_DN")
	)
	(segment
		(start 217.944192 -46.642782)
		(end 220.194886 -57.899554)
		(width 0.1016)
		(layer "In5.Cu")
		(net "PHY_IOC_TO_CON_A_2_DN")
	)
	(segment
		(start 182.943246 -30.559502)
		(end 187.873132 -33.846008)
		(width 0.1016)
		(layer "In5.Cu")
		(net "PHY_IOC_TO_CON_A_2_DN")
	)
	(segment
		(start 182.25008 -29.100018)
		(end 181.995064 -29.576014)
		(width 0.1016)
		(layer "In5.Cu")
		(net "PHY_IOC_TO_CON_A_2_DN")
	)
	(segment
		(start 182.16626 -29.782516)
		(end 182.943246 -30.559502)
		(width 0.1016)
		(layer "In5.Cu")
		(net "PHY_IOC_TO_CON_A_2_DN")
	)
	(segment
		(start 182.10403 -29.748988)
		(end 182.103776 -29.749242)
		(width 0.1016)
		(layer "In5.Cu")
		(net "PHY_IOC_TO_CON_A_2_DN")
	)
	(segment
		(start 182.081678 -29.737304)
		(end 182.102252 -29.747972)
		(width 0.1016)
		(layer "In5.Cu")
		(net "PHY_IOC_TO_CON_A_2_DN")
	)
	(segment
		(start 182.036974 -29.713428)
		(end 182.081678 -29.737304)
		(width 0.1016)
		(layer "In5.Cu")
		(net "PHY_IOC_TO_CON_A_2_DN")
	)
	(segment
		(start 182.106824 -29.75102)
		(end 182.16626 -29.782516)
		(width 0.1016)
		(layer "In5.Cu")
		(net "PHY_IOC_TO_CON_A_2_DN")
	)
	(segment
		(start 207.342232 -37.739574)
		(end 215.74125 -43.33875)
		(width 0.1016)
		(layer "In5.Cu")
		(net "PHY_IOC_TO_CON_A_2_DN")
	)
	(segment
		(start 215.258396 -73.311004)
		(end 215.4936 -73.546208)
		(width 0.1016)
		(layer "In5.Cu")
		(net "PHY_IOC_TO_CON_A_2_DN")
	)
	(segment
		(start 215.759792 -73.546208)
		(end 215.923114 -73.382886)
		(width 0.1016)
		(layer "In5.Cu")
		(net "PHY_IOC_TO_CON_A_2_DN")
	)
	(segment
		(start 181.995064 -29.576014)
		(end 182.036974 -29.713428)
		(width 0.1016)
		(layer "In5.Cu")
		(net "PHY_IOC_TO_CON_A_2_DN")
	)
	(segment
		(start 215.74125 -43.33875)
		(end 217.944192 -46.642782)
		(width 0.1016)
		(layer "In5.Cu")
		(net "PHY_IOC_TO_CON_A_2_DN")
	)
	(segment
		(start 217.872056 -69.515482)
		(end 216.422478 -71.689722)
		(width 0.1016)
		(layer "In5.Cu")
		(net "PHY_IOC_TO_CON_A_2_DN")
	)
	(arc
		(start 215.4936 -73.546208)
		(mid 215.626696 -73.601338)
		(end 215.759792 -73.546208)
		(width 0.1016)
		(layer "In5.Cu")
		(net "PHY_IOC_TO_CON_A_2_DN")
	)
	(segment
		(start 205.588108 -74.92365)
		(end 204.937106 -74.272648)
		(width 0.12446)
		(layer "F.Cu")
		(net "PHY_IOC_TO_CON_A_1_DP_C")
	)
	(segment
		(start 207.668622 -74.92365)
		(end 205.588108 -74.92365)
		(width 0.12446)
		(layer "F.Cu")
		(net "PHY_IOC_TO_CON_A_1_DP_C")
	)
	(segment
		(start 207.776572 -75.0316)
		(end 207.668622 -74.92365)
		(width 0.12446)
		(layer "F.Cu")
		(net "PHY_IOC_TO_CON_A_1_DP_C")
	)
	(segment
		(start 204.937106 -74.272648)
		(end 204.427074 -74.272648)
		(width 0.12446)
		(layer "F.Cu")
		(net "PHY_IOC_TO_CON_A_1_DP_C")
	)
	(segment
		(start 204.427074 -74.272648)
		(end 204.399896 -74.299826)
		(width 0.12446)
		(layer "F.Cu")
		(net "PHY_IOC_TO_CON_A_1_DP_C")
	)
	(segment
		(start 208.335372 -75.0316)
		(end 208.436972 -74.93)
		(width 0.12446)
		(layer "F.Cu")
		(net "PHY_IOC_TO_CON_A_1_DP")
	)
	(segment
		(start 208.436972 -74.93)
		(end 210.312 -74.93)
		(width 0.12446)
		(layer "F.Cu")
		(net "PHY_IOC_TO_CON_A_1_DP")
	)
	(segment
		(start 216.0524 -75.0316)
		(end 216.476834 -75.0316)
		(width 0.12446)
		(layer "F.Cu")
		(net "PHY_IOC_TO_CON_A_1_DP")
	)
	(segment
		(start 210.312 -74.93)
		(end 211.8106 -76.4286)
		(width 0.12446)
		(layer "F.Cu")
		(net "PHY_IOC_TO_CON_A_1_DP")
	)
	(segment
		(start 214.6554 -76.4286)
		(end 216.0524 -75.0316)
		(width 0.12446)
		(layer "F.Cu")
		(net "PHY_IOC_TO_CON_A_1_DP")
	)
	(segment
		(start 216.77249 -75.58151)
		(end 216.638886 -75.715114)
		(width 0.12446)
		(layer "F.Cu")
		(net "PHY_IOC_TO_CON_A_1_DP")
	)
	(segment
		(start 211.8106 -76.4286)
		(end 214.6554 -76.4286)
		(width 0.12446)
		(layer "F.Cu")
		(net "PHY_IOC_TO_CON_A_1_DP")
	)
	(segment
		(start 216.476834 -75.0316)
		(end 216.77249 -75.327256)
		(width 0.12446)
		(layer "F.Cu")
		(net "PHY_IOC_TO_CON_A_1_DP")
	)
	(arc
		(start 216.77249 -75.327256)
		(mid 216.825275 -75.45442)
		(end 216.77249 -75.58151)
		(width 0.12446)
		(layer "F.Cu")
		(net "PHY_IOC_TO_CON_A_1_DP")
	)
	(segment
		(start 204.547724 -36.564316)
		(end 204.772006 -36.414964)
		(width 0.1016)
		(layer "In5.Cu")
		(net "PHY_IOC_TO_CON_A_1_DP")
	)
	(segment
		(start 190.84163 -33.627314)
		(end 190.990982 -33.851596)
		(width 0.1016)
		(layer "In5.Cu")
		(net "PHY_IOC_TO_CON_A_1_DP")
	)
	(segment
		(start 191.812926 -33.821878)
		(end 191.962278 -34.045906)
		(width 0.1016)
		(layer "In5.Cu")
		(net "PHY_IOC_TO_CON_A_1_DP")
	)
	(segment
		(start 217.756994 -72.730106)
		(end 217.756994 -72.73036)
		(width 0.1016)
		(layer "In5.Cu")
		(net "PHY_IOC_TO_CON_A_1_DP")
	)
	(segment
		(start 181.29631 -28.13431)
		(end 182.86222 -28.447238)
		(width 0.1016)
		(layer "In5.Cu")
		(net "PHY_IOC_TO_CON_A_1_DP")
	)
	(segment
		(start 217.476578 -73.15073)
		(end 216.477596 -74.149712)
		(width 0.1016)
		(layer "In5.Cu")
		(net "PHY_IOC_TO_CON_A_1_DP")
	)
	(segment
		(start 204.099414 -36.280344)
		(end 204.24902 -36.504626)
		(width 0.1016)
		(layer "In5.Cu")
		(net "PHY_IOC_TO_CON_A_1_DP")
	)
	(segment
		(start 203.128118 -36.086034)
		(end 203.277724 -36.310316)
		(width 0.1016)
		(layer "In5.Cu")
		(net "PHY_IOC_TO_CON_A_1_DP")
	)
	(segment
		(start 194.42811 -34.345118)
		(end 203.128118 -36.086034)
		(width 0.1016)
		(layer "In5.Cu")
		(net "PHY_IOC_TO_CON_A_1_DP")
	)
	(segment
		(start 194.203828 -34.49447)
		(end 194.42811 -34.345118)
		(width 0.1016)
		(layer "In5.Cu")
		(net "PHY_IOC_TO_CON_A_1_DP")
	)
	(segment
		(start 192.933574 -34.24047)
		(end 193.232532 -34.30016)
		(width 0.1016)
		(layer "In5.Cu")
		(net "PHY_IOC_TO_CON_A_1_DP")
	)
	(segment
		(start 205.519274 -36.75888)
		(end 205.743302 -36.609274)
		(width 0.1016)
		(layer "In5.Cu")
		(net "PHY_IOC_TO_CON_A_1_DP")
	)
	(segment
		(start 220.894656 -58.029094)
		(end 218.037664 -72.309228)
		(width 0.1016)
		(layer "In5.Cu")
		(net "PHY_IOC_TO_CON_A_1_DP")
	)
	(segment
		(start 204.24902 -36.504626)
		(end 204.547724 -36.564316)
		(width 0.1016)
		(layer "In5.Cu")
		(net "PHY_IOC_TO_CON_A_1_DP")
	)
	(segment
		(start 191.28994 -33.91154)
		(end 191.513968 -33.761934)
		(width 0.1016)
		(layer "In5.Cu")
		(net "PHY_IOC_TO_CON_A_1_DP")
	)
	(segment
		(start 179.64277 -26.18232)
		(end 179.732432 -26.230326)
		(width 0.1016)
		(layer "In5.Cu")
		(net "PHY_IOC_TO_CON_A_1_DP")
	)
	(segment
		(start 217.756994 -72.73036)
		(end 217.476578 -73.15073)
		(width 0.1016)
		(layer "In5.Cu")
		(net "PHY_IOC_TO_CON_A_1_DP")
	)
	(segment
		(start 206.714598 -36.803838)
		(end 207.013556 -36.863528)
		(width 0.1016)
		(layer "In5.Cu")
		(net "PHY_IOC_TO_CON_A_1_DP")
	)
	(segment
		(start 193.755518 -34.210498)
		(end 193.90487 -34.43478)
		(width 0.1016)
		(layer "In5.Cu")
		(net "PHY_IOC_TO_CON_A_1_DP")
	)
	(segment
		(start 205.220316 -36.698936)
		(end 205.519274 -36.75888)
		(width 0.1016)
		(layer "In5.Cu")
		(net "PHY_IOC_TO_CON_A_1_DP")
	)
	(segment
		(start 207.013556 -36.863528)
		(end 216.368884 -43.09999)
		(width 0.1016)
		(layer "In5.Cu")
		(net "PHY_IOC_TO_CON_A_1_DP")
	)
	(segment
		(start 205.743302 -36.609274)
		(end 206.04226 -36.669218)
		(width 0.1016)
		(layer "In5.Cu")
		(net "PHY_IOC_TO_CON_A_1_DP")
	)
	(segment
		(start 192.485264 -33.956498)
		(end 192.784222 -34.016188)
		(width 0.1016)
		(layer "In5.Cu")
		(net "PHY_IOC_TO_CON_A_1_DP")
	)
	(segment
		(start 179.732432 -26.230326)
		(end 180.1876 -26.685494)
		(width 0.1016)
		(layer "In5.Cu")
		(net "PHY_IOC_TO_CON_A_1_DP")
	)
	(segment
		(start 193.232532 -34.30016)
		(end 193.456814 -34.150808)
		(width 0.1016)
		(layer "In5.Cu")
		(net "PHY_IOC_TO_CON_A_1_DP")
	)
	(segment
		(start 193.456814 -34.150808)
		(end 193.755518 -34.210498)
		(width 0.1016)
		(layer "In5.Cu")
		(net "PHY_IOC_TO_CON_A_1_DP")
	)
	(segment
		(start 180.1876 -26.685494)
		(end 180.1876 -27.0256)
		(width 0.1016)
		(layer "In5.Cu")
		(net "PHY_IOC_TO_CON_A_1_DP")
	)
	(segment
		(start 203.576428 -36.370006)
		(end 203.80071 -36.220654)
		(width 0.1016)
		(layer "In5.Cu")
		(net "PHY_IOC_TO_CON_A_1_DP")
	)
	(segment
		(start 191.962278 -34.045906)
		(end 192.261236 -34.10585)
		(width 0.1016)
		(layer "In5.Cu")
		(net "PHY_IOC_TO_CON_A_1_DP")
	)
	(segment
		(start 190.542672 -33.567624)
		(end 190.84163 -33.627314)
		(width 0.1016)
		(layer "In5.Cu")
		(net "PHY_IOC_TO_CON_A_1_DP")
	)
	(segment
		(start 206.191612 -36.893246)
		(end 206.49057 -36.95319)
		(width 0.1016)
		(layer "In5.Cu")
		(net "PHY_IOC_TO_CON_A_1_DP")
	)
	(segment
		(start 180.1876 -27.0256)
		(end 181.29631 -28.13431)
		(width 0.1016)
		(layer "In5.Cu")
		(net "PHY_IOC_TO_CON_A_1_DP")
	)
	(segment
		(start 193.90487 -34.43478)
		(end 194.203828 -34.49447)
		(width 0.1016)
		(layer "In5.Cu")
		(net "PHY_IOC_TO_CON_A_1_DP")
	)
	(segment
		(start 192.261236 -34.10585)
		(end 192.485264 -33.956498)
		(width 0.1016)
		(layer "In5.Cu")
		(net "PHY_IOC_TO_CON_A_1_DP")
	)
	(segment
		(start 182.86222 -28.447238)
		(end 190.542672 -33.567624)
		(width 0.1016)
		(layer "In5.Cu")
		(net "PHY_IOC_TO_CON_A_1_DP")
	)
	(segment
		(start 206.49057 -36.95319)
		(end 206.714598 -36.803838)
		(width 0.1016)
		(layer "In5.Cu")
		(net "PHY_IOC_TO_CON_A_1_DP")
	)
	(segment
		(start 204.772006 -36.414964)
		(end 205.070964 -36.474654)
		(width 0.1016)
		(layer "In5.Cu")
		(net "PHY_IOC_TO_CON_A_1_DP")
	)
	(segment
		(start 203.80071 -36.220654)
		(end 204.099414 -36.280344)
		(width 0.1016)
		(layer "In5.Cu")
		(net "PHY_IOC_TO_CON_A_1_DP")
	)
	(segment
		(start 191.513968 -33.761934)
		(end 191.812926 -33.821878)
		(width 0.1016)
		(layer "In5.Cu")
		(net "PHY_IOC_TO_CON_A_1_DP")
	)
	(segment
		(start 190.990982 -33.851596)
		(end 191.28994 -33.91154)
		(width 0.1016)
		(layer "In5.Cu")
		(net "PHY_IOC_TO_CON_A_1_DP")
	)
	(segment
		(start 216.801954 -75.552046)
		(end 216.638886 -75.715114)
		(width 0.1016)
		(layer "In5.Cu")
		(net "PHY_IOC_TO_CON_A_1_DP")
	)
	(segment
		(start 218.568524 -46.399196)
		(end 220.894656 -58.029094)
		(width 0.1016)
		(layer "In5.Cu")
		(net "PHY_IOC_TO_CON_A_1_DP")
	)
	(segment
		(start 216.368884 -43.09999)
		(end 218.568524 -46.399196)
		(width 0.1016)
		(layer "In5.Cu")
		(net "PHY_IOC_TO_CON_A_1_DP")
	)
	(segment
		(start 216.477596 -74.149712)
		(end 216.477596 -74.961496)
		(width 0.1016)
		(layer "In5.Cu")
		(net "PHY_IOC_TO_CON_A_1_DP")
	)
	(segment
		(start 192.784222 -34.016188)
		(end 192.933574 -34.24047)
		(width 0.1016)
		(layer "In5.Cu")
		(net "PHY_IOC_TO_CON_A_1_DP")
	)
	(segment
		(start 179.250086 -26.699972)
		(end 179.505356 -26.223722)
		(width 0.1016)
		(layer "In5.Cu")
		(net "PHY_IOC_TO_CON_A_1_DP")
	)
	(segment
		(start 218.037664 -72.309228)
		(end 217.756994 -72.730106)
		(width 0.1016)
		(layer "In5.Cu")
		(net "PHY_IOC_TO_CON_A_1_DP")
	)
	(segment
		(start 205.070964 -36.474654)
		(end 205.220316 -36.698936)
		(width 0.1016)
		(layer "In5.Cu")
		(net "PHY_IOC_TO_CON_A_1_DP")
	)
	(segment
		(start 203.277724 -36.310316)
		(end 203.576428 -36.370006)
		(width 0.1016)
		(layer "In5.Cu")
		(net "PHY_IOC_TO_CON_A_1_DP")
	)
	(segment
		(start 216.477596 -74.961496)
		(end 216.801954 -75.285854)
		(width 0.1016)
		(layer "In5.Cu")
		(net "PHY_IOC_TO_CON_A_1_DP")
	)
	(segment
		(start 206.04226 -36.669218)
		(end 206.191612 -36.893246)
		(width 0.1016)
		(layer "In5.Cu")
		(net "PHY_IOC_TO_CON_A_1_DP")
	)
	(segment
		(start 179.505356 -26.223722)
		(end 179.64277 -26.18232)
		(width 0.1016)
		(layer "In5.Cu")
		(net "PHY_IOC_TO_CON_A_1_DP")
	)
	(arc
		(start 216.801954 -75.285854)
		(mid 216.857084 -75.41895)
		(end 216.801954 -75.552046)
		(width 0.1016)
		(layer "In5.Cu")
		(net "PHY_IOC_TO_CON_A_1_DP")
	)
	(segment
		(start 205.75651 -74.51725)
		(end 207.732122 -74.51725)
		(width 0.12446)
		(layer "F.Cu")
		(net "PHY_IOC_TO_CON_A_1_DN_C")
	)
	(segment
		(start 204.2922 -73.866248)
		(end 205.105508 -73.866248)
		(width 0.12446)
		(layer "F.Cu")
		(net "PHY_IOC_TO_CON_A_1_DN_C")
	)
	(segment
		(start 205.105508 -73.866248)
		(end 205.75651 -74.51725)
		(width 0.12446)
		(layer "F.Cu")
		(net "PHY_IOC_TO_CON_A_1_DN_C")
	)
	(segment
		(start 203.60005 -74.299826)
		(end 204.2922 -73.866248)
		(width 0.12446)
		(layer "F.Cu")
		(net "PHY_IOC_TO_CON_A_1_DN_C")
	)
	(segment
		(start 207.732122 -74.51725)
		(end 207.776572 -74.4728)
		(width 0.12446)
		(layer "F.Cu")
		(net "PHY_IOC_TO_CON_A_1_DN_C")
	)
	(segment
		(start 215.883998 -74.6252)
		(end 214.486998 -76.0222)
		(width 0.12446)
		(layer "F.Cu")
		(net "PHY_IOC_TO_CON_A_1_DN")
	)
	(segment
		(start 210.480402 -74.5236)
		(end 208.386172 -74.5236)
		(width 0.12446)
		(layer "F.Cu")
		(net "PHY_IOC_TO_CON_A_1_DN")
	)
	(segment
		(start 217.447114 -74.906886)
		(end 217.314018 -75.039982)
		(width 0.12446)
		(layer "F.Cu")
		(net "PHY_IOC_TO_CON_A_1_DN")
	)
	(segment
		(start 211.979002 -76.0222)
		(end 210.480402 -74.5236)
		(width 0.12446)
		(layer "F.Cu")
		(net "PHY_IOC_TO_CON_A_1_DN")
	)
	(segment
		(start 208.386172 -74.5236)
		(end 208.335372 -74.4728)
		(width 0.12446)
		(layer "F.Cu")
		(net "PHY_IOC_TO_CON_A_1_DN")
	)
	(segment
		(start 217.060018 -75.039982)
		(end 216.645236 -74.6252)
		(width 0.12446)
		(layer "F.Cu")
		(net "PHY_IOC_TO_CON_A_1_DN")
	)
	(segment
		(start 216.645236 -74.6252)
		(end 215.883998 -74.6252)
		(width 0.12446)
		(layer "F.Cu")
		(net "PHY_IOC_TO_CON_A_1_DN")
	)
	(segment
		(start 214.486998 -76.0222)
		(end 211.979002 -76.0222)
		(width 0.12446)
		(layer "F.Cu")
		(net "PHY_IOC_TO_CON_A_1_DN")
	)
	(arc
		(start 217.314018 -75.039982)
		(mid 217.187018 -75.092587)
		(end 217.060018 -75.039982)
		(width 0.12446)
		(layer "F.Cu")
		(net "PHY_IOC_TO_CON_A_1_DN")
	)
	(segment
		(start 218.324938 -72.428354)
		(end 217.71356 -73.34504)
		(width 0.1016)
		(layer "In5.Cu")
		(net "PHY_IOC_TO_CON_A_1_DN")
	)
	(segment
		(start 217.283792 -75.070208)
		(end 217.447114 -74.906886)
		(width 0.1016)
		(layer "In5.Cu")
		(net "PHY_IOC_TO_CON_A_1_DN")
	)
	(segment
		(start 216.588848 -42.880026)
		(end 218.855798 -46.28007)
		(width 0.1016)
		(layer "In5.Cu")
		(net "PHY_IOC_TO_CON_A_1_DN")
	)
	(segment
		(start 179.744878 -25.776174)
		(end 179.786788 -25.913588)
		(width 0.1016)
		(layer "In5.Cu")
		(net "PHY_IOC_TO_CON_A_1_DN")
	)
	(segment
		(start 217.71356 -73.34504)
		(end 216.782396 -74.276204)
		(width 0.1016)
		(layer "In5.Cu")
		(net "PHY_IOC_TO_CON_A_1_DN")
	)
	(segment
		(start 180.4924 -26.899108)
		(end 181.446678 -27.853386)
		(width 0.1016)
		(layer "In5.Cu")
		(net "PHY_IOC_TO_CON_A_1_DN")
	)
	(segment
		(start 216.782396 -74.276204)
		(end 216.782396 -74.835004)
		(width 0.1016)
		(layer "In5.Cu")
		(net "PHY_IOC_TO_CON_A_1_DN")
	)
	(segment
		(start 179.916328 -25.982676)
		(end 180.4924 -26.559002)
		(width 0.1016)
		(layer "In5.Cu")
		(net "PHY_IOC_TO_CON_A_1_DN")
	)
	(segment
		(start 179.786788 -25.913588)
		(end 179.916328 -25.982676)
		(width 0.1016)
		(layer "In5.Cu")
		(net "PHY_IOC_TO_CON_A_1_DN")
	)
	(segment
		(start 180.4924 -26.559002)
		(end 180.4924 -26.899108)
		(width 0.1016)
		(layer "In5.Cu")
		(net "PHY_IOC_TO_CON_A_1_DN")
	)
	(segment
		(start 182.981092 -28.159964)
		(end 190.661798 -33.28035)
		(width 0.1016)
		(layer "In5.Cu")
		(net "PHY_IOC_TO_CON_A_1_DN")
	)
	(segment
		(start 181.446678 -27.853386)
		(end 182.981092 -28.159964)
		(width 0.1016)
		(layer "In5.Cu")
		(net "PHY_IOC_TO_CON_A_1_DN")
	)
	(segment
		(start 216.782396 -74.835004)
		(end 217.0176 -75.070208)
		(width 0.1016)
		(layer "In5.Cu")
		(net "PHY_IOC_TO_CON_A_1_DN")
	)
	(segment
		(start 207.132682 -36.576254)
		(end 216.588848 -42.880026)
		(width 0.1016)
		(layer "In5.Cu")
		(net "PHY_IOC_TO_CON_A_1_DN")
	)
	(segment
		(start 221.205552 -58.029094)
		(end 218.324938 -72.428354)
		(width 0.1016)
		(layer "In5.Cu")
		(net "PHY_IOC_TO_CON_A_1_DN")
	)
	(segment
		(start 218.855798 -46.28007)
		(end 221.205552 -58.029094)
		(width 0.1016)
		(layer "In5.Cu")
		(net "PHY_IOC_TO_CON_A_1_DN")
	)
	(segment
		(start 190.661798 -33.28035)
		(end 207.132682 -36.576254)
		(width 0.1016)
		(layer "In5.Cu")
		(net "PHY_IOC_TO_CON_A_1_DN")
	)
	(segment
		(start 179.999894 -25.299924)
		(end 179.744878 -25.776174)
		(width 0.1016)
		(layer "In5.Cu")
		(net "PHY_IOC_TO_CON_A_1_DN")
	)
	(arc
		(start 217.0176 -75.070208)
		(mid 217.150696 -75.125338)
		(end 217.283792 -75.070208)
		(width 0.1016)
		(layer "In5.Cu")
		(net "PHY_IOC_TO_CON_A_1_DN")
	)
	(segment
		(start 207.694022 -76.62545)
		(end 207.776572 -76.708)
		(width 0.12446)
		(layer "F.Cu")
		(net "PHY_IOC_TO_CON_A_0_DP_C")
	)
	(segment
		(start 204.737208 -75.099926)
		(end 206.262732 -76.62545)
		(width 0.12446)
		(layer "F.Cu")
		(net "PHY_IOC_TO_CON_A_0_DP_C")
	)
	(segment
		(start 204.399896 -75.099926)
		(end 204.737208 -75.099926)
		(width 0.12446)
		(layer "F.Cu")
		(net "PHY_IOC_TO_CON_A_0_DP_C")
	)
	(segment
		(start 206.262732 -76.62545)
		(end 207.694022 -76.62545)
		(width 0.12446)
		(layer "F.Cu")
		(net "PHY_IOC_TO_CON_A_0_DP_C")
	)
	(segment
		(start 215.495886 -79.652114)
		(end 215.616282 -79.531718)
		(width 0.12446)
		(layer "F.Cu")
		(net "PHY_IOC_TO_CON_A_0_DP")
	)
	(segment
		(start 214.341964 -77.978)
		(end 211.201 -77.978)
		(width 0.12446)
		(layer "F.Cu")
		(net "PHY_IOC_TO_CON_A_0_DP")
	)
	(segment
		(start 215.616282 -79.252318)
		(end 214.341964 -77.978)
		(width 0.12446)
		(layer "F.Cu")
		(net "PHY_IOC_TO_CON_A_0_DP")
	)
	(segment
		(start 209.81797 -76.59497)
		(end 208.448402 -76.59497)
		(width 0.12446)
		(layer "F.Cu")
		(net "PHY_IOC_TO_CON_A_0_DP")
	)
	(segment
		(start 211.201 -77.978)
		(end 209.81797 -76.59497)
		(width 0.12446)
		(layer "F.Cu")
		(net "PHY_IOC_TO_CON_A_0_DP")
	)
	(segment
		(start 208.448402 -76.59497)
		(end 208.335372 -76.708)
		(width 0.12446)
		(layer "F.Cu")
		(net "PHY_IOC_TO_CON_A_0_DP")
	)
	(arc
		(start 215.616282 -79.531718)
		(mid 215.674148 -79.392018)
		(end 215.616282 -79.252318)
		(width 0.12446)
		(layer "F.Cu")
		(net "PHY_IOC_TO_CON_A_0_DP")
	)
	(segment
		(start 191.451738 -32.881316)
		(end 191.15278 -32.821626)
		(width 0.1016)
		(layer "In5.Cu")
		(net "PHY_IOC_TO_CON_A_0_DP")
	)
	(segment
		(start 204.615034 -35.319716)
		(end 204.391006 -35.469068)
		(width 0.1016)
		(layer "In5.Cu")
		(net "PHY_IOC_TO_CON_A_0_DP")
	)
	(segment
		(start 194.36588 -33.464246)
		(end 194.066922 -33.404302)
		(width 0.1016)
		(layer "In5.Cu")
		(net "PHY_IOC_TO_CON_A_0_DP")
	)
	(segment
		(start 215.495886 -79.652114)
		(end 215.658954 -79.489046)
		(width 0.1016)
		(layer "In5.Cu")
		(net "PHY_IOC_TO_CON_A_0_DP")
	)
	(segment
		(start 219.082112 -73.869804)
		(end 222.11792 -58.694066)
		(width 0.1016)
		(layer "In5.Cu")
		(net "PHY_IOC_TO_CON_A_0_DP")
	)
	(segment
		(start 181.982364 -26.230072)
		(end 181.976014 -26.226516)
		(width 0.1016)
		(layer "In5.Cu")
		(net "PHY_IOC_TO_CON_A_0_DP")
	)
	(segment
		(start 205.063344 -35.603688)
		(end 204.913992 -35.379406)
		(width 0.1016)
		(layer "In5.Cu")
		(net "PHY_IOC_TO_CON_A_0_DP")
	)
	(segment
		(start 205.586584 -35.514026)
		(end 205.362302 -35.663378)
		(width 0.1016)
		(layer "In5.Cu")
		(net "PHY_IOC_TO_CON_A_0_DP")
	)
	(segment
		(start 206.034894 -35.797998)
		(end 205.885288 -35.573716)
		(width 0.1016)
		(layer "In5.Cu")
		(net "PHY_IOC_TO_CON_A_0_DP")
	)
	(segment
		(start 191.15278 -32.821626)
		(end 191.003428 -32.597344)
		(width 0.1016)
		(layer "In5.Cu")
		(net "PHY_IOC_TO_CON_A_0_DP")
	)
	(segment
		(start 217.685874 -75.964034)
		(end 219.082112 -73.869804)
		(width 0.1016)
		(layer "In5.Cu")
		(net "PHY_IOC_TO_CON_A_0_DP")
	)
	(segment
		(start 206.55788 -35.708336)
		(end 206.333598 -35.857688)
		(width 0.1016)
		(layer "In5.Cu")
		(net "PHY_IOC_TO_CON_A_0_DP")
	)
	(segment
		(start 181.755288 -26.223468)
		(end 181.500018 -26.699972)
		(width 0.1016)
		(layer "In5.Cu")
		(net "PHY_IOC_TO_CON_A_0_DP")
	)
	(segment
		(start 181.893464 -26.182574)
		(end 181.892702 -26.182066)
		(width 0.1016)
		(layer "In5.Cu")
		(net "PHY_IOC_TO_CON_A_0_DP")
	)
	(segment
		(start 192.423034 -33.075626)
		(end 192.124076 -33.015936)
		(width 0.1016)
		(layer "In5.Cu")
		(net "PHY_IOC_TO_CON_A_0_DP")
	)
	(segment
		(start 204.092048 -35.409378)
		(end 203.942696 -35.18535)
		(width 0.1016)
		(layer "In5.Cu")
		(net "PHY_IOC_TO_CON_A_0_DP")
	)
	(segment
		(start 203.643738 -35.125406)
		(end 203.419456 -35.275012)
		(width 0.1016)
		(layer "In5.Cu")
		(net "PHY_IOC_TO_CON_A_0_DP")
	)
	(segment
		(start 193.095626 -33.210246)
		(end 192.94602 -32.985964)
		(width 0.1016)
		(layer "In5.Cu")
		(net "PHY_IOC_TO_CON_A_0_DP")
	)
	(segment
		(start 193.39433 -33.269936)
		(end 193.095626 -33.210246)
		(width 0.1016)
		(layer "In5.Cu")
		(net "PHY_IOC_TO_CON_A_0_DP")
	)
	(segment
		(start 192.124076 -33.015936)
		(end 191.974724 -32.791654)
		(width 0.1016)
		(layer "In5.Cu")
		(net "PHY_IOC_TO_CON_A_0_DP")
	)
	(segment
		(start 203.942696 -35.18535)
		(end 203.643738 -35.125406)
		(width 0.1016)
		(layer "In5.Cu")
		(net "PHY_IOC_TO_CON_A_0_DP")
	)
	(segment
		(start 191.974724 -32.791654)
		(end 191.675766 -32.731964)
		(width 0.1016)
		(layer "In5.Cu")
		(net "PHY_IOC_TO_CON_A_0_DP")
	)
	(segment
		(start 192.94602 -32.985964)
		(end 192.647316 -32.926274)
		(width 0.1016)
		(layer "In5.Cu")
		(net "PHY_IOC_TO_CON_A_0_DP")
	)
	(segment
		(start 204.913992 -35.379406)
		(end 204.615034 -35.319716)
		(width 0.1016)
		(layer "In5.Cu")
		(net "PHY_IOC_TO_CON_A_0_DP")
	)
	(segment
		(start 205.362302 -35.663378)
		(end 205.063344 -35.603688)
		(width 0.1016)
		(layer "In5.Cu")
		(net "PHY_IOC_TO_CON_A_0_DP")
	)
	(segment
		(start 181.892702 -26.182066)
		(end 181.755288 -26.223468)
		(width 0.1016)
		(layer "In5.Cu")
		(net "PHY_IOC_TO_CON_A_0_DP")
	)
	(segment
		(start 215.271096 -78.378812)
		(end 217.685874 -75.964034)
		(width 0.1016)
		(layer "In5.Cu")
		(net "PHY_IOC_TO_CON_A_0_DP")
	)
	(segment
		(start 183.462422 -27.709876)
		(end 181.982364 -26.230072)
		(width 0.1016)
		(layer "In5.Cu")
		(net "PHY_IOC_TO_CON_A_0_DP")
	)
	(segment
		(start 194.589908 -33.31464)
		(end 194.36588 -33.464246)
		(width 0.1016)
		(layer "In5.Cu")
		(net "PHY_IOC_TO_CON_A_0_DP")
	)
	(segment
		(start 215.271096 -78.834996)
		(end 215.271096 -78.378812)
		(width 0.1016)
		(layer "In5.Cu")
		(net "PHY_IOC_TO_CON_A_0_DP")
	)
	(segment
		(start 205.885288 -35.573716)
		(end 205.586584 -35.514026)
		(width 0.1016)
		(layer "In5.Cu")
		(net "PHY_IOC_TO_CON_A_0_DP")
	)
	(segment
		(start 190.70447 -32.537654)
		(end 183.462422 -27.709876)
		(width 0.1016)
		(layer "In5.Cu")
		(net "PHY_IOC_TO_CON_A_0_DP")
	)
	(segment
		(start 206.982568 -35.793172)
		(end 206.55788 -35.708336)
		(width 0.1016)
		(layer "In5.Cu")
		(net "PHY_IOC_TO_CON_A_0_DP")
	)
	(segment
		(start 203.419456 -35.275012)
		(end 203.120752 -35.215068)
		(width 0.1016)
		(layer "In5.Cu")
		(net "PHY_IOC_TO_CON_A_0_DP")
	)
	(segment
		(start 181.973474 -26.225246)
		(end 181.893464 -26.182574)
		(width 0.1016)
		(layer "In5.Cu")
		(net "PHY_IOC_TO_CON_A_0_DP")
	)
	(segment
		(start 202.971146 -34.99104)
		(end 194.589908 -33.31464)
		(width 0.1016)
		(layer "In5.Cu")
		(net "PHY_IOC_TO_CON_A_0_DP")
	)
	(segment
		(start 203.120752 -35.215068)
		(end 202.971146 -34.99104)
		(width 0.1016)
		(layer "In5.Cu")
		(net "PHY_IOC_TO_CON_A_0_DP")
	)
	(segment
		(start 181.976014 -26.226516)
		(end 181.973474 -26.225246)
		(width 0.1016)
		(layer "In5.Cu")
		(net "PHY_IOC_TO_CON_A_0_DP")
	)
	(segment
		(start 191.003428 -32.597344)
		(end 190.70447 -32.537654)
		(width 0.1016)
		(layer "In5.Cu")
		(net "PHY_IOC_TO_CON_A_0_DP")
	)
	(segment
		(start 215.658954 -79.222854)
		(end 215.271096 -78.834996)
		(width 0.1016)
		(layer "In5.Cu")
		(net "PHY_IOC_TO_CON_A_0_DP")
	)
	(segment
		(start 206.333598 -35.857688)
		(end 206.034894 -35.797998)
		(width 0.1016)
		(layer "In5.Cu")
		(net "PHY_IOC_TO_CON_A_0_DP")
	)
	(segment
		(start 219.644976 -46.331378)
		(end 217.129614 -42.5577)
		(width 0.1016)
		(layer "In5.Cu")
		(net "PHY_IOC_TO_CON_A_0_DP")
	)
	(segment
		(start 192.647316 -32.926274)
		(end 192.423034 -33.075626)
		(width 0.1016)
		(layer "In5.Cu")
		(net "PHY_IOC_TO_CON_A_0_DP")
	)
	(segment
		(start 217.129614 -42.5577)
		(end 206.982568 -35.793172)
		(width 0.1016)
		(layer "In5.Cu")
		(net "PHY_IOC_TO_CON_A_0_DP")
	)
	(segment
		(start 191.675766 -32.731964)
		(end 191.451738 -32.881316)
		(width 0.1016)
		(layer "In5.Cu")
		(net "PHY_IOC_TO_CON_A_0_DP")
	)
	(segment
		(start 193.618612 -33.120584)
		(end 193.39433 -33.269936)
		(width 0.1016)
		(layer "In5.Cu")
		(net "PHY_IOC_TO_CON_A_0_DP")
	)
	(segment
		(start 194.066922 -33.404302)
		(end 193.917316 -33.180274)
		(width 0.1016)
		(layer "In5.Cu")
		(net "PHY_IOC_TO_CON_A_0_DP")
	)
	(segment
		(start 204.391006 -35.469068)
		(end 204.092048 -35.409378)
		(width 0.1016)
		(layer "In5.Cu")
		(net "PHY_IOC_TO_CON_A_0_DP")
	)
	(segment
		(start 222.11792 -58.694066)
		(end 219.644976 -46.331378)
		(width 0.1016)
		(layer "In5.Cu")
		(net "PHY_IOC_TO_CON_A_0_DP")
	)
	(segment
		(start 193.917316 -33.180274)
		(end 193.618612 -33.120584)
		(width 0.1016)
		(layer "In5.Cu")
		(net "PHY_IOC_TO_CON_A_0_DP")
	)
	(arc
		(start 215.658954 -79.489046)
		(mid 215.714084 -79.35595)
		(end 215.658954 -79.222854)
		(width 0.1016)
		(layer "In5.Cu")
		(net "PHY_IOC_TO_CON_A_0_DP")
	)
	(segment
		(start 203.60005 -75.099926)
		(end 204.2668 -74.693526)
		(width 0.12446)
		(layer "F.Cu")
		(net "PHY_IOC_TO_CON_A_0_DN_C")
	)
	(segment
		(start 204.2668 -74.693526)
		(end 204.90561 -74.693526)
		(width 0.12446)
		(layer "F.Cu")
		(net "PHY_IOC_TO_CON_A_0_DN_C")
	)
	(segment
		(start 204.90561 -74.693526)
		(end 206.431134 -76.21905)
		(width 0.12446)
		(layer "F.Cu")
		(net "PHY_IOC_TO_CON_A_0_DN_C")
	)
	(segment
		(start 206.431134 -76.21905)
		(end 207.706722 -76.21905)
		(width 0.12446)
		(layer "F.Cu")
		(net "PHY_IOC_TO_CON_A_0_DN_C")
	)
	(segment
		(start 207.706722 -76.21905)
		(end 207.776572 -76.1492)
		(width 0.12446)
		(layer "F.Cu")
		(net "PHY_IOC_TO_CON_A_0_DN_C")
	)
	(segment
		(start 215.052656 -78.11389)
		(end 214.510366 -77.5716)
		(width 0.12446)
		(layer "F.Cu")
		(net "PHY_IOC_TO_CON_A_0_DN")
	)
	(segment
		(start 214.510366 -77.5716)
		(end 211.369402 -77.5716)
		(width 0.12446)
		(layer "F.Cu")
		(net "PHY_IOC_TO_CON_A_0_DN")
	)
	(segment
		(start 215.05291 -78.11389)
		(end 215.052656 -78.11389)
		(width 0.12446)
		(layer "F.Cu")
		(net "PHY_IOC_TO_CON_A_0_DN")
	)
	(segment
		(start 208.374742 -76.18857)
		(end 208.335372 -76.1492)
		(width 0.12446)
		(layer "F.Cu")
		(net "PHY_IOC_TO_CON_A_0_DN")
	)
	(segment
		(start 209.986372 -76.18857)
		(end 208.374742 -76.18857)
		(width 0.12446)
		(layer "F.Cu")
		(net "PHY_IOC_TO_CON_A_0_DN")
	)
	(segment
		(start 215.90381 -78.96479)
		(end 215.05291 -78.11389)
		(width 0.12446)
		(layer "F.Cu")
		(net "PHY_IOC_TO_CON_A_0_DN")
	)
	(segment
		(start 211.369402 -77.5716)
		(end 209.986372 -76.18857)
		(width 0.12446)
		(layer "F.Cu")
		(net "PHY_IOC_TO_CON_A_0_DN")
	)
	(segment
		(start 216.304114 -78.843886)
		(end 216.18321 -78.96479)
		(width 0.12446)
		(layer "F.Cu")
		(net "PHY_IOC_TO_CON_A_0_DN")
	)
	(arc
		(start 216.18321 -78.96479)
		(mid 216.04351 -79.022656)
		(end 215.90381 -78.96479)
		(width 0.12446)
		(layer "F.Cu")
		(net "PHY_IOC_TO_CON_A_0_DN")
	)
	(segment
		(start 190.823342 -32.25038)
		(end 183.656732 -27.472894)
		(width 0.1016)
		(layer "In5.Cu")
		(net "PHY_IOC_TO_CON_A_0_DN")
	)
	(segment
		(start 222.428816 -58.694066)
		(end 219.93225 -46.212506)
		(width 0.1016)
		(layer "In5.Cu")
		(net "PHY_IOC_TO_CON_A_0_DN")
	)
	(segment
		(start 217.922856 -76.158344)
		(end 219.369386 -73.98893)
		(width 0.1016)
		(layer "In5.Cu")
		(net "PHY_IOC_TO_CON_A_0_DN")
	)
	(segment
		(start 182.120032 -25.95753)
		(end 182.118254 -25.956514)
		(width 0.1016)
		(layer "In5.Cu")
		(net "PHY_IOC_TO_CON_A_0_DN")
	)
	(segment
		(start 181.995064 -25.77592)
		(end 182.25008 -25.299924)
		(width 0.1016)
		(layer "In5.Cu")
		(net "PHY_IOC_TO_CON_A_0_DN")
	)
	(segment
		(start 215.8746 -79.007208)
		(end 215.575896 -78.708504)
		(width 0.1016)
		(layer "In5.Cu")
		(net "PHY_IOC_TO_CON_A_0_DN")
	)
	(segment
		(start 207.10144 -35.505898)
		(end 190.823342 -32.25038)
		(width 0.1016)
		(layer "In5.Cu")
		(net "PHY_IOC_TO_CON_A_0_DN")
	)
	(segment
		(start 183.656732 -27.472894)
		(end 182.16626 -25.982422)
		(width 0.1016)
		(layer "In5.Cu")
		(net "PHY_IOC_TO_CON_A_0_DN")
	)
	(segment
		(start 182.116984 -25.955752)
		(end 182.036974 -25.913334)
		(width 0.1016)
		(layer "In5.Cu")
		(net "PHY_IOC_TO_CON_A_0_DN")
	)
	(segment
		(start 219.369386 -73.98893)
		(end 222.428816 -58.694066)
		(width 0.1016)
		(layer "In5.Cu")
		(net "PHY_IOC_TO_CON_A_0_DN")
	)
	(segment
		(start 182.118254 -25.956514)
		(end 182.116984 -25.955752)
		(width 0.1016)
		(layer "In5.Cu")
		(net "PHY_IOC_TO_CON_A_0_DN")
	)
	(segment
		(start 219.93225 -46.212506)
		(end 217.349578 -42.337736)
		(width 0.1016)
		(layer "In5.Cu")
		(net "PHY_IOC_TO_CON_A_0_DN")
	)
	(segment
		(start 215.575896 -78.505304)
		(end 217.922856 -76.158344)
		(width 0.1016)
		(layer "In5.Cu")
		(net "PHY_IOC_TO_CON_A_0_DN")
	)
	(segment
		(start 182.036974 -25.913334)
		(end 181.995064 -25.77592)
		(width 0.1016)
		(layer "In5.Cu")
		(net "PHY_IOC_TO_CON_A_0_DN")
	)
	(segment
		(start 215.575896 -78.708504)
		(end 215.575896 -78.505304)
		(width 0.1016)
		(layer "In5.Cu")
		(net "PHY_IOC_TO_CON_A_0_DN")
	)
	(segment
		(start 182.120794 -25.958038)
		(end 182.120032 -25.95753)
		(width 0.1016)
		(layer "In5.Cu")
		(net "PHY_IOC_TO_CON_A_0_DN")
	)
	(segment
		(start 217.349578 -42.337736)
		(end 207.10144 -35.505898)
		(width 0.1016)
		(layer "In5.Cu")
		(net "PHY_IOC_TO_CON_A_0_DN")
	)
	(segment
		(start 216.304114 -78.843886)
		(end 216.140792 -79.007208)
		(width 0.1016)
		(layer "In5.Cu")
		(net "PHY_IOC_TO_CON_A_0_DN")
	)
	(segment
		(start 182.16626 -25.982422)
		(end 182.120794 -25.958038)
		(width 0.1016)
		(layer "In5.Cu")
		(net "PHY_IOC_TO_CON_A_0_DN")
	)
	(arc
		(start 216.140792 -79.007208)
		(mid 216.007696 -79.062338)
		(end 215.8746 -79.007208)
		(width 0.1016)
		(layer "In5.Cu")
		(net "PHY_IOC_TO_CON_A_0_DN")
	)
	(segment
		(start 159.470344 -22.488906)
		(end 159.250126 -22.899878)
		(width 0.12446)
		(layer "B.Cu")
		(net "PHY_CON_B_TO_IOC_3_DP_C")
	)
	(segment
		(start 165.324536 -38.137338)
		(end 165.426136 -38.035738)
		(width 0.12446)
		(layer "B.Cu")
		(net "PHY_CON_B_TO_IOC_3_DP_C")
	)
	(segment
		(start 165.426136 -31.798514)
		(end 165.426136 -27.217116)
		(width 0.12446)
		(layer "B.Cu")
		(net "PHY_CON_B_TO_IOC_3_DP_C")
	)
	(segment
		(start 159.639508 -22.43836)
		(end 159.639 -22.438106)
		(width 0.12446)
		(layer "B.Cu")
		(net "PHY_CON_B_TO_IOC_3_DP_C")
	)
	(segment
		(start 165.426136 -33.995614)
		(end 165.156896 -33.726374)
		(width 0.12446)
		(layer "B.Cu")
		(net "PHY_CON_B_TO_IOC_3_DP_C")
	)
	(segment
		(start 159.872934 -22.671786)
		(end 159.639508 -22.43836)
		(width 0.12446)
		(layer "B.Cu")
		(net "PHY_CON_B_TO_IOC_3_DP_C")
	)
	(segment
		(start 165.156896 -32.067754)
		(end 165.426136 -31.798514)
		(width 0.12446)
		(layer "B.Cu")
		(net "PHY_CON_B_TO_IOC_3_DP_C")
	)
	(segment
		(start 165.426136 -27.217116)
		(end 162.757612 -24.548592)
		(width 0.12446)
		(layer "B.Cu")
		(net "PHY_CON_B_TO_IOC_3_DP_C")
	)
	(segment
		(start 165.156896 -33.352994)
		(end 165.426136 -33.083754)
		(width 0.12446)
		(layer "B.Cu")
		(net "PHY_CON_B_TO_IOC_3_DP_C")
	)
	(segment
		(start 165.426136 -32.710374)
		(end 165.156896 -32.441134)
		(width 0.12446)
		(layer "B.Cu")
		(net "PHY_CON_B_TO_IOC_3_DP_C")
	)
	(segment
		(start 165.156896 -33.726374)
		(end 165.156896 -33.352994)
		(width 0.12446)
		(layer "B.Cu")
		(net "PHY_CON_B_TO_IOC_3_DP_C")
	)
	(segment
		(start 159.872934 -23.17623)
		(end 159.872934 -22.671786)
		(width 0.12446)
		(layer "B.Cu")
		(net "PHY_CON_B_TO_IOC_3_DP_C")
	)
	(segment
		(start 162.757612 -24.548592)
		(end 161.245296 -24.548592)
		(width 0.12446)
		(layer "B.Cu")
		(net "PHY_CON_B_TO_IOC_3_DP_C")
	)
	(segment
		(start 161.245296 -24.548592)
		(end 159.872934 -23.17623)
		(width 0.12446)
		(layer "B.Cu")
		(net "PHY_CON_B_TO_IOC_3_DP_C")
	)
	(segment
		(start 165.426136 -38.035738)
		(end 165.426136 -33.995614)
		(width 0.12446)
		(layer "B.Cu")
		(net "PHY_CON_B_TO_IOC_3_DP_C")
	)
	(segment
		(start 165.426136 -33.083754)
		(end 165.426136 -32.710374)
		(width 0.12446)
		(layer "B.Cu")
		(net "PHY_CON_B_TO_IOC_3_DP_C")
	)
	(segment
		(start 165.156896 -32.441134)
		(end 165.156896 -32.067754)
		(width 0.12446)
		(layer "B.Cu")
		(net "PHY_CON_B_TO_IOC_3_DP_C")
	)
	(arc
		(start 159.639 -22.438106)
		(mid 159.544151 -22.428576)
		(end 159.470344 -22.488906)
		(width 0.12446)
		(layer "B.Cu")
		(net "PHY_CON_B_TO_IOC_3_DP_C")
	)
	(segment
		(start 201.608944 -66.709036)
		(end 201.99985 -67.099942)
		(width 0.12446)
		(layer "F.Cu")
		(net "PHY_CON_B_TO_IOC_3_DP")
	)
	(segment
		(start 201.599546 -66.709036)
		(end 201.608944 -66.709036)
		(width 0.12446)
		(layer "F.Cu")
		(net "PHY_CON_B_TO_IOC_3_DP")
	)
	(via
		(at 201.599546 -66.709036)
		(size 0.508)
		(drill 0.254)
		(layers "F.Cu" "B.Cu")
		(net "PHY_CON_B_TO_IOC_3_DP")
	)
	(segment
		(start 209.296 -64.025272)
		(end 209.296 -65.05067)
		(width 0.12446)
		(layer "B.Cu")
		(net "PHY_CON_B_TO_IOC_3_DP")
	)
	(segment
		(start 188.137292 -41.441116)
		(end 190.289942 -41.022524)
		(width 0.12446)
		(layer "B.Cu")
		(net "PHY_CON_B_TO_IOC_3_DP")
	)
	(segment
		(start 207.169766 -66.812922)
		(end 206.56804 -66.812922)
		(width 0.0889)
		(layer "B.Cu")
		(net "PHY_CON_B_TO_IOC_3_DP")
	)
	(segment
		(start 182.465218 -42.817542)
		(end 182.67807 -42.50182)
		(width 0.12446)
		(layer "B.Cu")
		(net "PHY_CON_B_TO_IOC_3_DP")
	)
	(segment
		(start 165.324536 -38.696138)
		(end 165.426136 -38.797738)
		(width 0.12446)
		(layer "B.Cu")
		(net "PHY_CON_B_TO_IOC_3_DP")
	)
	(segment
		(start 181.782974 -42.67581)
		(end 182.098696 -42.888662)
		(width 0.12446)
		(layer "B.Cu")
		(net "PHY_CON_B_TO_IOC_3_DP")
	)
	(segment
		(start 211.913216 -61.22924)
		(end 211.902548 -61.281818)
		(width 0.12446)
		(layer "B.Cu")
		(net "PHY_CON_B_TO_IOC_3_DP")
	)
	(segment
		(start 206.56804 -66.812922)
		(end 206.05877 -67.322192)
		(width 0.0889)
		(layer "B.Cu")
		(net "PHY_CON_B_TO_IOC_3_DP")
	)
	(segment
		(start 185.201306 -42.0116)
		(end 188.137292 -41.441116)
		(width 0.12446)
		(layer "B.Cu")
		(net "PHY_CON_B_TO_IOC_3_DP")
	)
	(segment
		(start 184.30621 -42.185336)
		(end 184.621932 -42.398442)
		(width 0.12446)
		(layer "B.Cu")
		(net "PHY_CON_B_TO_IOC_3_DP")
	)
	(segment
		(start 165.426136 -38.797738)
		(end 165.426136 -40.87749)
		(width 0.12446)
		(layer "B.Cu")
		(net "PHY_CON_B_TO_IOC_3_DP")
	)
	(segment
		(start 209.296 -65.05067)
		(end 207.641698 -66.704972)
		(width 0.12446)
		(layer "B.Cu")
		(net "PHY_CON_B_TO_IOC_3_DP")
	)
	(segment
		(start 201.975974 -67.013074)
		(end 201.89952 -67.013074)
		(width 0.0889)
		(layer "B.Cu")
		(net "PHY_CON_B_TO_IOC_3_DP")
	)
	(segment
		(start 184.621932 -42.398442)
		(end 184.988454 -42.327068)
		(width 0.12446)
		(layer "B.Cu")
		(net "PHY_CON_B_TO_IOC_3_DP")
	)
	(segment
		(start 211.902548 -61.281818)
		(end 211.868512 -61.45276)
		(width 0.12446)
		(layer "B.Cu")
		(net "PHY_CON_B_TO_IOC_3_DP")
	)
	(segment
		(start 209.202528 -47.08652)
		(end 211.973922 -60.925202)
		(width 0.12446)
		(layer "B.Cu")
		(net "PHY_CON_B_TO_IOC_3_DP")
	)
	(segment
		(start 201.599546 -66.889376)
		(end 201.599546 -66.709036)
		(width 0.0889)
		(layer "B.Cu")
		(net "PHY_CON_B_TO_IOC_3_DP")
	)
	(segment
		(start 211.973922 -60.925202)
		(end 211.913216 -61.22924)
		(width 0.12446)
		(layer "B.Cu")
		(net "PHY_CON_B_TO_IOC_3_DP")
	)
	(segment
		(start 168.389046 -43.8404)
		(end 175.788574 -43.8404)
		(width 0.12446)
		(layer "B.Cu")
		(net "PHY_CON_B_TO_IOC_3_DP")
	)
	(segment
		(start 201.645266 -66.986658)
		(end 201.635106 -66.976244)
		(width 0.0889)
		(layer "B.Cu")
		(net "PHY_CON_B_TO_IOC_3_DP")
	)
	(segment
		(start 165.426136 -40.87749)
		(end 168.389046 -43.8404)
		(width 0.12446)
		(layer "B.Cu")
		(net "PHY_CON_B_TO_IOC_3_DP")
	)
	(segment
		(start 175.788574 -43.8404)
		(end 181.782974 -42.67581)
		(width 0.12446)
		(layer "B.Cu")
		(net "PHY_CON_B_TO_IOC_3_DP")
	)
	(segment
		(start 183.939688 -42.25671)
		(end 184.30621 -42.185336)
		(width 0.12446)
		(layer "B.Cu")
		(net "PHY_CON_B_TO_IOC_3_DP")
	)
	(segment
		(start 182.098696 -42.888662)
		(end 182.465218 -42.817542)
		(width 0.12446)
		(layer "B.Cu")
		(net "PHY_CON_B_TO_IOC_3_DP")
	)
	(segment
		(start 184.988454 -42.327068)
		(end 185.201306 -42.0116)
		(width 0.12446)
		(layer "B.Cu")
		(net "PHY_CON_B_TO_IOC_3_DP")
	)
	(segment
		(start 206.05877 -67.322192)
		(end 202.285092 -67.322192)
		(width 0.0889)
		(layer "B.Cu")
		(net "PHY_CON_B_TO_IOC_3_DP")
	)
	(segment
		(start 204.446632 -43.876976)
		(end 209.202528 -47.08652)
		(width 0.12446)
		(layer "B.Cu")
		(net "PHY_CON_B_TO_IOC_3_DP")
	)
	(segment
		(start 201.898504 -67.013074)
		(end 201.708512 -67.013074)
		(width 0.0889)
		(layer "B.Cu")
		(net "PHY_CON_B_TO_IOC_3_DP")
	)
	(segment
		(start 207.299814 -66.704972)
		(end 207.277716 -66.704972)
		(width 0.0889)
		(layer "B.Cu")
		(net "PHY_CON_B_TO_IOC_3_DP")
	)
	(segment
		(start 190.289942 -41.022524)
		(end 204.446632 -43.876976)
		(width 0.12446)
		(layer "B.Cu")
		(net "PHY_CON_B_TO_IOC_3_DP")
	)
	(segment
		(start 182.67807 -42.50182)
		(end 183.044592 -42.4307)
		(width 0.12446)
		(layer "B.Cu")
		(net "PHY_CON_B_TO_IOC_3_DP")
	)
	(segment
		(start 211.868512 -61.45276)
		(end 209.296 -64.025272)
		(width 0.12446)
		(layer "B.Cu")
		(net "PHY_CON_B_TO_IOC_3_DP")
	)
	(segment
		(start 183.360314 -42.643552)
		(end 183.726836 -42.572432)
		(width 0.12446)
		(layer "B.Cu")
		(net "PHY_CON_B_TO_IOC_3_DP")
	)
	(segment
		(start 183.726836 -42.572432)
		(end 183.939688 -42.25671)
		(width 0.12446)
		(layer "B.Cu")
		(net "PHY_CON_B_TO_IOC_3_DP")
	)
	(segment
		(start 202.285092 -67.322192)
		(end 201.975974 -67.013074)
		(width 0.0889)
		(layer "B.Cu")
		(net "PHY_CON_B_TO_IOC_3_DP")
	)
	(segment
		(start 183.044592 -42.4307)
		(end 183.360314 -42.643552)
		(width 0.12446)
		(layer "B.Cu")
		(net "PHY_CON_B_TO_IOC_3_DP")
	)
	(segment
		(start 207.641698 -66.704972)
		(end 207.299814 -66.704972)
		(width 0.12446)
		(layer "B.Cu")
		(net "PHY_CON_B_TO_IOC_3_DP")
	)
	(segment
		(start 207.277716 -66.704972)
		(end 207.169766 -66.812922)
		(width 0.0889)
		(layer "B.Cu")
		(net "PHY_CON_B_TO_IOC_3_DP")
	)
	(arc
		(start 201.89952 -67.013074)
		(mid 201.899012 -67.013073)
		(end 201.898504 -67.013074)
		(width 0.0889)
		(layer "B.Cu")
		(net "PHY_CON_B_TO_IOC_3_DP")
	)
	(arc
		(start 201.635106 -66.976244)
		(mid 201.608794 -66.936305)
		(end 201.599546 -66.889376)
		(width 0.0889)
		(layer "B.Cu")
		(net "PHY_CON_B_TO_IOC_3_DP")
	)
	(arc
		(start 201.708512 -67.013074)
		(mid 201.674243 -67.006203)
		(end 201.645266 -66.986658)
		(width 0.0889)
		(layer "B.Cu")
		(net "PHY_CON_B_TO_IOC_3_DP")
	)
	(segment
		(start 161.413698 -24.142192)
		(end 160.279334 -23.007828)
		(width 0.12446)
		(layer "B.Cu")
		(net "PHY_CON_B_TO_IOC_3_DN_C")
	)
	(segment
		(start 165.959536 -38.137338)
		(end 165.832536 -38.010338)
		(width 0.12446)
		(layer "B.Cu")
		(net "PHY_CON_B_TO_IOC_3_DN_C")
	)
	(segment
		(start 159.8803 -22.10435)
		(end 159.829754 -22.07895)
		(width 0.12446)
		(layer "B.Cu")
		(net "PHY_CON_B_TO_IOC_3_DN_C")
	)
	(segment
		(start 159.779716 -21.910802)
		(end 159.999934 -21.500084)
		(width 0.12446)
		(layer "B.Cu")
		(net "PHY_CON_B_TO_IOC_3_DN_C")
	)
	(segment
		(start 165.832536 -38.010338)
		(end 165.832536 -27.048714)
		(width 0.12446)
		(layer "B.Cu")
		(net "PHY_CON_B_TO_IOC_3_DN_C")
	)
	(segment
		(start 160.279334 -23.007828)
		(end 160.279334 -22.503384)
		(width 0.12446)
		(layer "B.Cu")
		(net "PHY_CON_B_TO_IOC_3_DN_C")
	)
	(segment
		(start 162.926014 -24.142192)
		(end 161.413698 -24.142192)
		(width 0.12446)
		(layer "B.Cu")
		(net "PHY_CON_B_TO_IOC_3_DN_C")
	)
	(segment
		(start 160.279334 -22.503384)
		(end 159.8803 -22.10435)
		(width 0.12446)
		(layer "B.Cu")
		(net "PHY_CON_B_TO_IOC_3_DN_C")
	)
	(segment
		(start 159.829754 -22.07895)
		(end 159.779716 -21.910802)
		(width 0.12446)
		(layer "B.Cu")
		(net "PHY_CON_B_TO_IOC_3_DN_C")
	)
	(segment
		(start 165.832536 -27.048714)
		(end 162.926014 -24.142192)
		(width 0.12446)
		(layer "B.Cu")
		(net "PHY_CON_B_TO_IOC_3_DN_C")
	)
	(segment
		(start 201.593196 -67.502532)
		(end 201.593196 -67.493134)
		(width 0.12446)
		(layer "F.Cu")
		(net "PHY_CON_B_TO_IOC_3_DN")
	)
	(segment
		(start 201.593196 -67.493134)
		(end 201.200004 -67.099942)
		(width 0.12446)
		(layer "F.Cu")
		(net "PHY_CON_B_TO_IOC_3_DN")
	)
	(via
		(at 201.593196 -67.502532)
		(size 0.508)
		(drill 0.254)
		(layers "F.Cu" "B.Cu")
		(net "PHY_CON_B_TO_IOC_3_DN")
	)
	(segment
		(start 189.423548 -40.776906)
		(end 190.291466 -40.607996)
		(width 0.12446)
		(layer "B.Cu")
		(net "PHY_CON_B_TO_IOC_3_DN")
	)
	(segment
		(start 168.557448 -43.434)
		(end 175.749204 -43.434)
		(width 0.12446)
		(layer "B.Cu")
		(net "PHY_CON_B_TO_IOC_3_DN")
	)
	(segment
		(start 190.291466 -40.607996)
		(end 197.448678 -42.051224)
		(width 0.12446)
		(layer "B.Cu")
		(net "PHY_CON_B_TO_IOC_3_DN")
	)
	(segment
		(start 212.311742 -61.30925)
		(end 212.306408 -61.33592)
		(width 0.12446)
		(layer "B.Cu")
		(net "PHY_CON_B_TO_IOC_3_DN")
	)
	(segment
		(start 206.137764 -67.512692)
		(end 202.206098 -67.512692)
		(width 0.0889)
		(layer "B.Cu")
		(net "PHY_CON_B_TO_IOC_3_DN")
	)
	(segment
		(start 207.169766 -67.003422)
		(end 206.647034 -67.003422)
		(width 0.0889)
		(layer "B.Cu")
		(net "PHY_CON_B_TO_IOC_3_DN")
	)
	(segment
		(start 209.702908 -64.19342)
		(end 209.702654 -64.19342)
		(width 0.12446)
		(layer "B.Cu")
		(net "PHY_CON_B_TO_IOC_3_DN")
	)
	(segment
		(start 207.8101 -67.111372)
		(end 207.299814 -67.111372)
		(width 0.12446)
		(layer "B.Cu")
		(net "PHY_CON_B_TO_IOC_3_DN")
	)
	(segment
		(start 165.832536 -38.823138)
		(end 165.832536 -40.709088)
		(width 0.12446)
		(layer "B.Cu")
		(net "PHY_CON_B_TO_IOC_3_DN")
	)
	(segment
		(start 201.593196 -67.309492)
		(end 201.593196 -67.502532)
		(width 0.0889)
		(layer "B.Cu")
		(net "PHY_CON_B_TO_IOC_3_DN")
	)
	(segment
		(start 202.206098 -67.512692)
		(end 201.89698 -67.203574)
		(width 0.0889)
		(layer "B.Cu")
		(net "PHY_CON_B_TO_IOC_3_DN")
	)
	(segment
		(start 165.832536 -40.709088)
		(end 168.557448 -43.434)
		(width 0.12446)
		(layer "B.Cu")
		(net "PHY_CON_B_TO_IOC_3_DN")
	)
	(segment
		(start 209.7024 -65.219072)
		(end 207.8101 -67.111372)
		(width 0.12446)
		(layer "B.Cu")
		(net "PHY_CON_B_TO_IOC_3_DN")
	)
	(segment
		(start 207.299814 -67.111372)
		(end 207.277716 -67.111372)
		(width 0.0889)
		(layer "B.Cu")
		(net "PHY_CON_B_TO_IOC_3_DN")
	)
	(segment
		(start 204.606652 -43.494452)
		(end 209.568288 -46.842934)
		(width 0.12446)
		(layer "B.Cu")
		(net "PHY_CON_B_TO_IOC_3_DN")
	)
	(segment
		(start 201.624946 -67.2338)
		(end 201.624692 -67.234054)
		(width 0.0889)
		(layer "B.Cu")
		(net "PHY_CON_B_TO_IOC_3_DN")
	)
	(segment
		(start 209.568288 -46.842934)
		(end 212.38845 -60.925202)
		(width 0.12446)
		(layer "B.Cu")
		(net "PHY_CON_B_TO_IOC_3_DN")
	)
	(segment
		(start 197.448678 -42.051224)
		(end 204.606652 -43.494452)
		(width 0.12446)
		(layer "B.Cu")
		(net "PHY_CON_B_TO_IOC_3_DN")
	)
	(segment
		(start 188.3537 -40.984932)
		(end 189.423548 -40.776906)
		(width 0.12446)
		(layer "B.Cu")
		(net "PHY_CON_B_TO_IOC_3_DN")
	)
	(segment
		(start 175.749204 -43.434)
		(end 187.17895 -41.213278)
		(width 0.12446)
		(layer "B.Cu")
		(net "PHY_CON_B_TO_IOC_3_DN")
	)
	(segment
		(start 206.647034 -67.003422)
		(end 206.137764 -67.512692)
		(width 0.0889)
		(layer "B.Cu")
		(net "PHY_CON_B_TO_IOC_3_DN")
	)
	(segment
		(start 165.959536 -38.696138)
		(end 165.832536 -38.823138)
		(width 0.12446)
		(layer "B.Cu")
		(net "PHY_CON_B_TO_IOC_3_DN")
	)
	(segment
		(start 201.89698 -67.203574)
		(end 201.698606 -67.203574)
		(width 0.0889)
		(layer "B.Cu")
		(net "PHY_CON_B_TO_IOC_3_DN")
	)
	(segment
		(start 212.243162 -61.653166)
		(end 209.702908 -64.19342)
		(width 0.12446)
		(layer "B.Cu")
		(net "PHY_CON_B_TO_IOC_3_DN")
	)
	(segment
		(start 207.277716 -67.111372)
		(end 207.169766 -67.003422)
		(width 0.0889)
		(layer "B.Cu")
		(net "PHY_CON_B_TO_IOC_3_DN")
	)
	(segment
		(start 212.38845 -60.925202)
		(end 212.311742 -61.30925)
		(width 0.12446)
		(layer "B.Cu")
		(net "PHY_CON_B_TO_IOC_3_DN")
	)
	(segment
		(start 209.702654 -64.19342)
		(end 209.7024 -65.219072)
		(width 0.12446)
		(layer "B.Cu")
		(net "PHY_CON_B_TO_IOC_3_DN")
	)
	(segment
		(start 212.306408 -61.33592)
		(end 212.243162 -61.653166)
		(width 0.12446)
		(layer "B.Cu")
		(net "PHY_CON_B_TO_IOC_3_DN")
	)
	(segment
		(start 187.17895 -41.213278)
		(end 188.3537 -40.984932)
		(width 0.12446)
		(layer "B.Cu")
		(net "PHY_CON_B_TO_IOC_3_DN")
	)
	(arc
		(start 201.698606 -67.203574)
		(mid 201.658794 -67.211422)
		(end 201.624946 -67.2338)
		(width 0.0889)
		(layer "B.Cu")
		(net "PHY_CON_B_TO_IOC_3_DN")
	)
	(arc
		(start 201.624692 -67.234054)
		(mid 201.601403 -67.268622)
		(end 201.593196 -67.309492)
		(width 0.0889)
		(layer "B.Cu")
		(net "PHY_CON_B_TO_IOC_3_DN")
	)
	(segment
		(start 164.955474 -24.413972)
		(end 163.85032 -23.308564)
		(width 0.12446)
		(layer "B.Cu")
		(net "PHY_CON_B_TO_IOC_2_DP_C")
	)
	(segment
		(start 165.864032 -25.70353)
		(end 165.864032 -25.322784)
		(width 0.12446)
		(layer "B.Cu")
		(net "PHY_CON_B_TO_IOC_2_DP_C")
	)
	(segment
		(start 161.720276 -22.488652)
		(end 161.500058 -22.899878)
		(width 0.12446)
		(layer "B.Cu")
		(net "PHY_CON_B_TO_IOC_2_DP_C")
	)
	(segment
		(start 166.772844 -38.009068)
		(end 166.772844 -26.231596)
		(width 0.12446)
		(layer "B.Cu")
		(net "PHY_CON_B_TO_IOC_2_DP_C")
	)
	(segment
		(start 161.894774 -22.441154)
		(end 161.89325 -22.440392)
		(width 0.12446)
		(layer "B.Cu")
		(net "PHY_CON_B_TO_IOC_2_DP_C")
	)
	(segment
		(start 166.64559 -38.137338)
		(end 166.772844 -38.009068)
		(width 0.12446)
		(layer "B.Cu")
		(net "PHY_CON_B_TO_IOC_2_DP_C")
	)
	(segment
		(start 163.85032 -23.308564)
		(end 162.693604 -23.308564)
		(width 0.12446)
		(layer "B.Cu")
		(net "PHY_CON_B_TO_IOC_2_DP_C")
	)
	(segment
		(start 166.772844 -26.231596)
		(end 166.508938 -25.967436)
		(width 0.12446)
		(layer "B.Cu")
		(net "PHY_CON_B_TO_IOC_2_DP_C")
	)
	(segment
		(start 161.901632 -22.44471)
		(end 161.896044 -22.441916)
		(width 0.12446)
		(layer "B.Cu")
		(net "PHY_CON_B_TO_IOC_2_DP_C")
	)
	(segment
		(start 166.508938 -25.967436)
		(end 166.128192 -25.967436)
		(width 0.12446)
		(layer "B.Cu")
		(net "PHY_CON_B_TO_IOC_2_DP_C")
	)
	(segment
		(start 164.955474 -24.794718)
		(end 164.955474 -24.413972)
		(width 0.12446)
		(layer "B.Cu")
		(net "PHY_CON_B_TO_IOC_2_DP_C")
	)
	(segment
		(start 165.21938 -25.058624)
		(end 164.955474 -24.794718)
		(width 0.12446)
		(layer "B.Cu")
		(net "PHY_CON_B_TO_IOC_2_DP_C")
	)
	(segment
		(start 161.90341 -22.445726)
		(end 161.901632 -22.44471)
		(width 0.12446)
		(layer "B.Cu")
		(net "PHY_CON_B_TO_IOC_2_DP_C")
	)
	(segment
		(start 161.935668 -22.462744)
		(end 161.90341 -22.445726)
		(width 0.12446)
		(layer "B.Cu")
		(net "PHY_CON_B_TO_IOC_2_DP_C")
	)
	(segment
		(start 161.89325 -22.440392)
		(end 161.89198 -22.43963)
		(width 0.12446)
		(layer "B.Cu")
		(net "PHY_CON_B_TO_IOC_2_DP_C")
	)
	(segment
		(start 166.128192 -25.967436)
		(end 165.864032 -25.70353)
		(width 0.12446)
		(layer "B.Cu")
		(net "PHY_CON_B_TO_IOC_2_DP_C")
	)
	(segment
		(start 162.693604 -23.308564)
		(end 162.306254 -22.921214)
		(width 0.12446)
		(layer "B.Cu")
		(net "PHY_CON_B_TO_IOC_2_DP_C")
	)
	(segment
		(start 162.065462 -22.532086)
		(end 161.935668 -22.462744)
		(width 0.12446)
		(layer "B.Cu")
		(net "PHY_CON_B_TO_IOC_2_DP_C")
	)
	(segment
		(start 162.306254 -22.921214)
		(end 162.065462 -22.532086)
		(width 0.12446)
		(layer "B.Cu")
		(net "PHY_CON_B_TO_IOC_2_DP_C")
	)
	(segment
		(start 161.890456 -22.438868)
		(end 161.888932 -22.437852)
		(width 0.12446)
		(layer "B.Cu")
		(net "PHY_CON_B_TO_IOC_2_DP_C")
	)
	(segment
		(start 161.89198 -22.43963)
		(end 161.890456 -22.438868)
		(width 0.12446)
		(layer "B.Cu")
		(net "PHY_CON_B_TO_IOC_2_DP_C")
	)
	(segment
		(start 165.600126 -25.058624)
		(end 165.21938 -25.058624)
		(width 0.12446)
		(layer "B.Cu")
		(net "PHY_CON_B_TO_IOC_2_DP_C")
	)
	(segment
		(start 161.896044 -22.441916)
		(end 161.894774 -22.441154)
		(width 0.12446)
		(layer "B.Cu")
		(net "PHY_CON_B_TO_IOC_2_DP_C")
	)
	(segment
		(start 165.864032 -25.322784)
		(end 165.600126 -25.058624)
		(width 0.12446)
		(layer "B.Cu")
		(net "PHY_CON_B_TO_IOC_2_DP_C")
	)
	(arc
		(start 161.888932 -22.437852)
		(mid 161.794083 -22.428322)
		(end 161.720276 -22.488652)
		(width 0.12446)
		(layer "B.Cu")
		(net "PHY_CON_B_TO_IOC_2_DP_C")
	)
	(segment
		(start 202.3999 -68.30314)
		(end 202.3999 -68.300092)
		(width 0.12446)
		(layer "F.Cu")
		(net "PHY_CON_B_TO_IOC_2_DP")
	)
	(segment
		(start 202.3999 -68.300092)
		(end 201.99985 -67.900042)
		(width 0.12446)
		(layer "F.Cu")
		(net "PHY_CON_B_TO_IOC_2_DP")
	)
	(via
		(at 202.3999 -68.30314)
		(size 0.508)
		(drill 0.254)
		(layers "F.Cu" "B.Cu")
		(net "PHY_CON_B_TO_IOC_2_DP")
	)
	(segment
		(start 212.681312 -56.783478)
		(end 212.998304 -56.994552)
		(width 0.12446)
		(layer "B.Cu")
		(net "PHY_CON_B_TO_IOC_2_DP")
	)
	(segment
		(start 205.476856 -42.772584)
		(end 210.229704 -46.305978)
		(width 0.12446)
		(layer "B.Cu")
		(net "PHY_CON_B_TO_IOC_2_DP")
	)
	(segment
		(start 166.64559 -38.696138)
		(end 166.74846 -38.799008)
		(width 0.12446)
		(layer "B.Cu")
		(net "PHY_CON_B_TO_IOC_2_DP")
	)
	(segment
		(start 182.533544 -41.26992)
		(end 182.899558 -41.196768)
		(width 0.12446)
		(layer "B.Cu")
		(net "PHY_CON_B_TO_IOC_2_DP")
	)
	(segment
		(start 213.071456 -57.36082)
		(end 212.860382 -57.677558)
		(width 0.12446)
		(layer "B.Cu")
		(net "PHY_CON_B_TO_IOC_2_DP")
	)
	(segment
		(start 203.425552 -68.029582)
		(end 202.941428 -68.513706)
		(width 0.0889)
		(layer "B.Cu")
		(net "PHY_CON_B_TO_IOC_2_DP")
	)
	(segment
		(start 208.157064 -67.921632)
		(end 207.299814 -67.921632)
		(width 0.12446)
		(layer "B.Cu")
		(net "PHY_CON_B_TO_IOC_2_DP")
	)
	(segment
		(start 213.502494 -59.514994)
		(end 213.592156 -59.96305)
		(width 0.12446)
		(layer "B.Cu")
		(net "PHY_CON_B_TO_IOC_2_DP")
	)
	(segment
		(start 213.185756 -59.30392)
		(end 213.502494 -59.514994)
		(width 0.12446)
		(layer "B.Cu")
		(net "PHY_CON_B_TO_IOC_2_DP")
	)
	(segment
		(start 207.299814 -67.921632)
		(end 207.277716 -67.921632)
		(width 0.0889)
		(layer "B.Cu")
		(net "PHY_CON_B_TO_IOC_2_DP")
	)
	(segment
		(start 182.899558 -41.196768)
		(end 183.110886 -40.88003)
		(width 0.12446)
		(layer "B.Cu")
		(net "PHY_CON_B_TO_IOC_2_DP")
	)
	(segment
		(start 181.273196 -41.521888)
		(end 181.63921 -41.448736)
		(width 0.12446)
		(layer "B.Cu")
		(net "PHY_CON_B_TO_IOC_2_DP")
	)
	(segment
		(start 184.159906 -40.945054)
		(end 184.371234 -40.628316)
		(width 0.12446)
		(layer "B.Cu")
		(net "PHY_CON_B_TO_IOC_2_DP")
	)
	(segment
		(start 184.371234 -40.628316)
		(end 189.56909 -39.589456)
		(width 0.12446)
		(layer "B.Cu")
		(net "PHY_CON_B_TO_IOC_2_DP")
	)
	(segment
		(start 213.323678 -58.620914)
		(end 213.11235 -58.937906)
		(width 0.12446)
		(layer "B.Cu")
		(net "PHY_CON_B_TO_IOC_2_DP")
	)
	(segment
		(start 213.11235 -58.937906)
		(end 213.185756 -59.30392)
		(width 0.12446)
		(layer "B.Cu")
		(net "PHY_CON_B_TO_IOC_2_DP")
	)
	(segment
		(start 166.74846 -40.412416)
		(end 168.815004 -42.47896)
		(width 0.12446)
		(layer "B.Cu")
		(net "PHY_CON_B_TO_IOC_2_DP")
	)
	(segment
		(start 180.956458 -41.31056)
		(end 181.273196 -41.521888)
		(width 0.12446)
		(layer "B.Cu")
		(net "PHY_CON_B_TO_IOC_2_DP")
	)
	(segment
		(start 212.860382 -57.677558)
		(end 212.933534 -58.043572)
		(width 0.12446)
		(layer "B.Cu")
		(net "PHY_CON_B_TO_IOC_2_DP")
	)
	(segment
		(start 212.819234 -56.100472)
		(end 212.60816 -56.41721)
		(width 0.12446)
		(layer "B.Cu")
		(net "PHY_CON_B_TO_IOC_2_DP")
	)
	(segment
		(start 183.110886 -40.88003)
		(end 183.4769 -40.806878)
		(width 0.12446)
		(layer "B.Cu")
		(net "PHY_CON_B_TO_IOC_2_DP")
	)
	(segment
		(start 207.169766 -68.029582)
		(end 203.425552 -68.029582)
		(width 0.0889)
		(layer "B.Cu")
		(net "PHY_CON_B_TO_IOC_2_DP")
	)
	(segment
		(start 210.229704 -46.305978)
		(end 211.125308 -47.632874)
		(width 0.12446)
		(layer "B.Cu")
		(net "PHY_CON_B_TO_IOC_2_DP")
	)
	(segment
		(start 181.850538 -41.131998)
		(end 182.216552 -41.058846)
		(width 0.12446)
		(layer "B.Cu")
		(net "PHY_CON_B_TO_IOC_2_DP")
	)
	(segment
		(start 180.012848 -41.773856)
		(end 180.378862 -41.70045)
		(width 0.12446)
		(layer "B.Cu")
		(net "PHY_CON_B_TO_IOC_2_DP")
	)
	(segment
		(start 202.610466 -68.513706)
		(end 202.3999 -68.30314)
		(width 0.0889)
		(layer "B.Cu")
		(net "PHY_CON_B_TO_IOC_2_DP")
	)
	(segment
		(start 181.63921 -41.448736)
		(end 181.850538 -41.131998)
		(width 0.12446)
		(layer "B.Cu")
		(net "PHY_CON_B_TO_IOC_2_DP")
	)
	(segment
		(start 189.56909 -39.589456)
		(end 205.476856 -42.772584)
		(width 0.12446)
		(layer "B.Cu")
		(net "PHY_CON_B_TO_IOC_2_DP")
	)
	(segment
		(start 212.60816 -56.41721)
		(end 212.681312 -56.783478)
		(width 0.12446)
		(layer "B.Cu")
		(net "PHY_CON_B_TO_IOC_2_DP")
	)
	(segment
		(start 207.277716 -67.921632)
		(end 207.169766 -68.029582)
		(width 0.0889)
		(layer "B.Cu")
		(net "PHY_CON_B_TO_IOC_2_DP")
	)
	(segment
		(start 180.59019 -41.383712)
		(end 180.956458 -41.31056)
		(width 0.12446)
		(layer "B.Cu")
		(net "PHY_CON_B_TO_IOC_2_DP")
	)
	(segment
		(start 212.998304 -56.994552)
		(end 213.071456 -57.36082)
		(width 0.12446)
		(layer "B.Cu")
		(net "PHY_CON_B_TO_IOC_2_DP")
	)
	(segment
		(start 213.592156 -59.96305)
		(end 213.053168 -62.656974)
		(width 0.12446)
		(layer "B.Cu")
		(net "PHY_CON_B_TO_IOC_2_DP")
	)
	(segment
		(start 166.74846 -38.799008)
		(end 166.74846 -40.412416)
		(width 0.12446)
		(layer "B.Cu")
		(net "PHY_CON_B_TO_IOC_2_DP")
	)
	(segment
		(start 183.4769 -40.806878)
		(end 183.793638 -41.018206)
		(width 0.12446)
		(layer "B.Cu")
		(net "PHY_CON_B_TO_IOC_2_DP")
	)
	(segment
		(start 212.173058 -63.905638)
		(end 208.157064 -67.921632)
		(width 0.12446)
		(layer "B.Cu")
		(net "PHY_CON_B_TO_IOC_2_DP")
	)
	(segment
		(start 212.933534 -58.043572)
		(end 213.250272 -58.2549)
		(width 0.12446)
		(layer "B.Cu")
		(net "PHY_CON_B_TO_IOC_2_DP")
	)
	(segment
		(start 179.69611 -41.562528)
		(end 180.012848 -41.773856)
		(width 0.12446)
		(layer "B.Cu")
		(net "PHY_CON_B_TO_IOC_2_DP")
	)
	(segment
		(start 183.793638 -41.018206)
		(end 184.159906 -40.945054)
		(width 0.12446)
		(layer "B.Cu")
		(net "PHY_CON_B_TO_IOC_2_DP")
	)
	(segment
		(start 182.216552 -41.058846)
		(end 182.533544 -41.26992)
		(width 0.12446)
		(layer "B.Cu")
		(net "PHY_CON_B_TO_IOC_2_DP")
	)
	(segment
		(start 202.941428 -68.513706)
		(end 202.610466 -68.513706)
		(width 0.0889)
		(layer "B.Cu")
		(net "PHY_CON_B_TO_IOC_2_DP")
	)
	(segment
		(start 168.815004 -42.47896)
		(end 175.109886 -42.47896)
		(width 0.12446)
		(layer "B.Cu")
		(net "PHY_CON_B_TO_IOC_2_DP")
	)
	(segment
		(start 175.109886 -42.47896)
		(end 179.69611 -41.562528)
		(width 0.12446)
		(layer "B.Cu")
		(net "PHY_CON_B_TO_IOC_2_DP")
	)
	(segment
		(start 211.125308 -47.632874)
		(end 212.819234 -56.100472)
		(width 0.12446)
		(layer "B.Cu")
		(net "PHY_CON_B_TO_IOC_2_DP")
	)
	(segment
		(start 213.053168 -62.656974)
		(end 212.173058 -63.905638)
		(width 0.12446)
		(layer "B.Cu")
		(net "PHY_CON_B_TO_IOC_2_DP")
	)
	(segment
		(start 213.250272 -58.2549)
		(end 213.323678 -58.620914)
		(width 0.12446)
		(layer "B.Cu")
		(net "PHY_CON_B_TO_IOC_2_DP")
	)
	(segment
		(start 180.378862 -41.70045)
		(end 180.59019 -41.383712)
		(width 0.12446)
		(layer "B.Cu")
		(net "PHY_CON_B_TO_IOC_2_DP")
	)
	(segment
		(start 162.200336 -22.142958)
		(end 162.174428 -22.129242)
		(width 0.12446)
		(layer "B.Cu")
		(net "PHY_CON_B_TO_IOC_2_DN_C")
	)
	(segment
		(start 162.029902 -21.910802)
		(end 162.25012 -21.500084)
		(width 0.12446)
		(layer "B.Cu")
		(net "PHY_CON_B_TO_IOC_2_DN_C")
	)
	(segment
		(start 167.179244 -26.063194)
		(end 164.018722 -22.902164)
		(width 0.12446)
		(layer "B.Cu")
		(net "PHY_CON_B_TO_IOC_2_DN_C")
	)
	(segment
		(start 162.080956 -22.079458)
		(end 162.080702 -22.079458)
		(width 0.12446)
		(layer "B.Cu")
		(net "PHY_CON_B_TO_IOC_2_DN_C")
	)
	(segment
		(start 162.353752 -22.225)
		(end 162.200336 -22.142958)
		(width 0.12446)
		(layer "B.Cu")
		(net "PHY_CON_B_TO_IOC_2_DN_C")
	)
	(segment
		(start 164.018722 -22.902164)
		(end 162.862006 -22.902164)
		(width 0.12446)
		(layer "B.Cu")
		(net "PHY_CON_B_TO_IOC_2_DN_C")
	)
	(segment
		(start 162.174428 -22.129242)
		(end 162.13074 -22.105874)
		(width 0.12446)
		(layer "B.Cu")
		(net "PHY_CON_B_TO_IOC_2_DN_C")
	)
	(segment
		(start 162.086036 -22.081998)
		(end 162.080956 -22.079458)
		(width 0.12446)
		(layer "B.Cu")
		(net "PHY_CON_B_TO_IOC_2_DN_C")
	)
	(segment
		(start 162.09391 -22.086062)
		(end 162.087814 -22.083014)
		(width 0.12446)
		(layer "B.Cu")
		(net "PHY_CON_B_TO_IOC_2_DN_C")
	)
	(segment
		(start 162.087814 -22.083014)
		(end 162.086036 -22.081998)
		(width 0.12446)
		(layer "B.Cu")
		(net "PHY_CON_B_TO_IOC_2_DN_C")
	)
	(segment
		(start 162.862006 -22.902164)
		(end 162.627056 -22.667214)
		(width 0.12446)
		(layer "B.Cu")
		(net "PHY_CON_B_TO_IOC_2_DN_C")
	)
	(segment
		(start 167.179244 -38.035992)
		(end 167.179244 -26.063194)
		(width 0.12446)
		(layer "B.Cu")
		(net "PHY_CON_B_TO_IOC_2_DN_C")
	)
	(segment
		(start 162.627056 -22.667214)
		(end 162.353752 -22.225)
		(width 0.12446)
		(layer "B.Cu")
		(net "PHY_CON_B_TO_IOC_2_DN_C")
	)
	(segment
		(start 167.28059 -38.137338)
		(end 167.179244 -38.035992)
		(width 0.12446)
		(layer "B.Cu")
		(net "PHY_CON_B_TO_IOC_2_DN_C")
	)
	(segment
		(start 162.13074 -22.105874)
		(end 162.09391 -22.086062)
		(width 0.12446)
		(layer "B.Cu")
		(net "PHY_CON_B_TO_IOC_2_DN_C")
	)
	(arc
		(start 162.080702 -22.079458)
		(mid 162.020372 -22.005651)
		(end 162.029902 -21.910802)
		(width 0.12446)
		(layer "B.Cu")
		(net "PHY_CON_B_TO_IOC_2_DN_C")
	)
	(segment
		(start 201.595228 -68.295266)
		(end 201.200004 -67.900042)
		(width 0.12446)
		(layer "F.Cu")
		(net "PHY_CON_B_TO_IOC_2_DN")
	)
	(segment
		(start 201.595482 -68.295266)
		(end 201.595228 -68.295266)
		(width 0.12446)
		(layer "F.Cu")
		(net "PHY_CON_B_TO_IOC_2_DN")
	)
	(via
		(at 201.595482 -68.295266)
		(size 0.508)
		(drill 0.254)
		(layers "F.Cu" "B.Cu")
		(net "PHY_CON_B_TO_IOC_2_DN")
	)
	(segment
		(start 205.646274 -42.391838)
		(end 210.5279 -46.021244)
		(width 0.12446)
		(layer "B.Cu")
		(net "PHY_CON_B_TO_IOC_2_DN")
	)
	(segment
		(start 212.50529 -64.139826)
		(end 212.485224 -64.168274)
		(width 0.12446)
		(layer "B.Cu")
		(net "PHY_CON_B_TO_IOC_2_DN")
	)
	(segment
		(start 167.15486 -40.244014)
		(end 168.983406 -42.07256)
		(width 0.12446)
		(layer "B.Cu")
		(net "PHY_CON_B_TO_IOC_2_DN")
	)
	(segment
		(start 201.901806 -68.704206)
		(end 201.595482 -68.397882)
		(width 0.0889)
		(layer "B.Cu")
		(net "PHY_CON_B_TO_IOC_2_DN")
	)
	(segment
		(start 213.451694 -62.73673)
		(end 213.451948 -62.73673)
		(width 0.12446)
		(layer "B.Cu")
		(net "PHY_CON_B_TO_IOC_2_DN")
	)
	(segment
		(start 214.006684 -59.96305)
		(end 213.451694 -62.73673)
		(width 0.12446)
		(layer "B.Cu")
		(net "PHY_CON_B_TO_IOC_2_DN")
	)
	(segment
		(start 167.15486 -38.821868)
		(end 167.15486 -40.244014)
		(width 0.12446)
		(layer "B.Cu")
		(net "PHY_CON_B_TO_IOC_2_DN")
	)
	(segment
		(start 203.504546 -68.220082)
		(end 203.020422 -68.704206)
		(width 0.0889)
		(layer "B.Cu")
		(net "PHY_CON_B_TO_IOC_2_DN")
	)
	(segment
		(start 211.507832 -47.473108)
		(end 214.006684 -59.96305)
		(width 0.12446)
		(layer "B.Cu")
		(net "PHY_CON_B_TO_IOC_2_DN")
	)
	(segment
		(start 207.169766 -68.220082)
		(end 203.504546 -68.220082)
		(width 0.0889)
		(layer "B.Cu")
		(net "PHY_CON_B_TO_IOC_2_DN")
	)
	(segment
		(start 208.325466 -68.328032)
		(end 207.299814 -68.328032)
		(width 0.12446)
		(layer "B.Cu")
		(net "PHY_CON_B_TO_IOC_2_DN")
	)
	(segment
		(start 168.983406 -42.07256)
		(end 175.0695 -42.07256)
		(width 0.12446)
		(layer "B.Cu")
		(net "PHY_CON_B_TO_IOC_2_DN")
	)
	(segment
		(start 212.485224 -64.168274)
		(end 208.325466 -68.328032)
		(width 0.12446)
		(layer "B.Cu")
		(net "PHY_CON_B_TO_IOC_2_DN")
	)
	(segment
		(start 213.43493 -62.820804)
		(end 212.945472 -63.515494)
		(width 0.12446)
		(layer "B.Cu")
		(net "PHY_CON_B_TO_IOC_2_DN")
	)
	(segment
		(start 167.28059 -38.696138)
		(end 167.15486 -38.821868)
		(width 0.12446)
		(layer "B.Cu")
		(net "PHY_CON_B_TO_IOC_2_DN")
	)
	(segment
		(start 175.0695 -42.07256)
		(end 189.56909 -39.174928)
		(width 0.12446)
		(layer "B.Cu")
		(net "PHY_CON_B_TO_IOC_2_DN")
	)
	(segment
		(start 201.595482 -68.397882)
		(end 201.595482 -68.295266)
		(width 0.0889)
		(layer "B.Cu")
		(net "PHY_CON_B_TO_IOC_2_DN")
	)
	(segment
		(start 203.020422 -68.704206)
		(end 201.901806 -68.704206)
		(width 0.0889)
		(layer "B.Cu")
		(net "PHY_CON_B_TO_IOC_2_DN")
	)
	(segment
		(start 213.451948 -62.73673)
		(end 213.43493 -62.820804)
		(width 0.12446)
		(layer "B.Cu")
		(net "PHY_CON_B_TO_IOC_2_DN")
	)
	(segment
		(start 189.56909 -39.174928)
		(end 205.646274 -42.391838)
		(width 0.12446)
		(layer "B.Cu")
		(net "PHY_CON_B_TO_IOC_2_DN")
	)
	(segment
		(start 212.945472 -63.515494)
		(end 212.50529 -64.139826)
		(width 0.12446)
		(layer "B.Cu")
		(net "PHY_CON_B_TO_IOC_2_DN")
	)
	(segment
		(start 207.299814 -68.328032)
		(end 207.277716 -68.328032)
		(width 0.0889)
		(layer "B.Cu")
		(net "PHY_CON_B_TO_IOC_2_DN")
	)
	(segment
		(start 210.5279 -46.021244)
		(end 211.507832 -47.473108)
		(width 0.12446)
		(layer "B.Cu")
		(net "PHY_CON_B_TO_IOC_2_DN")
	)
	(segment
		(start 207.277716 -68.328032)
		(end 207.169766 -68.220082)
		(width 0.0889)
		(layer "B.Cu")
		(net "PHY_CON_B_TO_IOC_2_DN")
	)
	(segment
		(start 167.14724 -24.673052)
		(end 167.14724 -24.292306)
		(width 0.12446)
		(layer "B.Cu")
		(net "PHY_CON_B_TO_IOC_1_DP_C")
	)
	(segment
		(start 159.998664 -19.53895)
		(end 159.998664 -19.041872)
		(width 0.12446)
		(layer "B.Cu")
		(net "PHY_CON_B_TO_IOC_1_DP_C")
	)
	(segment
		(start 168.074848 -25.219914)
		(end 167.791892 -24.936958)
		(width 0.12446)
		(layer "B.Cu")
		(net "PHY_CON_B_TO_IOC_1_DP_C")
	)
	(segment
		(start 159.748728 -18.696686)
		(end 159.743394 -18.693892)
		(width 0.12446)
		(layer "B.Cu")
		(net "PHY_CON_B_TO_IOC_1_DP_C")
	)
	(segment
		(start 168.074848 -38.054026)
		(end 168.074848 -25.219914)
		(width 0.12446)
		(layer "B.Cu")
		(net "PHY_CON_B_TO_IOC_1_DP_C")
	)
	(segment
		(start 167.791892 -24.936958)
		(end 167.411146 -24.936958)
		(width 0.12446)
		(layer "B.Cu")
		(net "PHY_CON_B_TO_IOC_1_DP_C")
	)
	(segment
		(start 161.139124 -20.67941)
		(end 159.998664 -19.53895)
		(width 0.12446)
		(layer "B.Cu")
		(net "PHY_CON_B_TO_IOC_1_DP_C")
	)
	(segment
		(start 166.238428 -23.383494)
		(end 163.534344 -20.67941)
		(width 0.12446)
		(layer "B.Cu")
		(net "PHY_CON_B_TO_IOC_1_DP_C")
	)
	(segment
		(start 159.470344 -18.688812)
		(end 159.250126 -19.100038)
		(width 0.12446)
		(layer "B.Cu")
		(net "PHY_CON_B_TO_IOC_1_DP_C")
	)
	(segment
		(start 167.14724 -24.292306)
		(end 166.88308 -24.028146)
		(width 0.12446)
		(layer "B.Cu")
		(net "PHY_CON_B_TO_IOC_1_DP_C")
	)
	(segment
		(start 166.88308 -24.028146)
		(end 166.502334 -24.028146)
		(width 0.12446)
		(layer "B.Cu")
		(net "PHY_CON_B_TO_IOC_1_DP_C")
	)
	(segment
		(start 159.749236 -18.69694)
		(end 159.748728 -18.696686)
		(width 0.12446)
		(layer "B.Cu")
		(net "PHY_CON_B_TO_IOC_1_DP_C")
	)
	(segment
		(start 167.411146 -24.936958)
		(end 167.14724 -24.673052)
		(width 0.12446)
		(layer "B.Cu")
		(net "PHY_CON_B_TO_IOC_1_DP_C")
	)
	(segment
		(start 159.743394 -18.693892)
		(end 159.742632 -18.693384)
		(width 0.12446)
		(layer "B.Cu")
		(net "PHY_CON_B_TO_IOC_1_DP_C")
	)
	(segment
		(start 166.238428 -23.76424)
		(end 166.238428 -23.383494)
		(width 0.12446)
		(layer "B.Cu")
		(net "PHY_CON_B_TO_IOC_1_DP_C")
	)
	(segment
		(start 163.534344 -20.67941)
		(end 161.139124 -20.67941)
		(width 0.12446)
		(layer "B.Cu")
		(net "PHY_CON_B_TO_IOC_1_DP_C")
	)
	(segment
		(start 159.742632 -18.693384)
		(end 159.639 -18.638012)
		(width 0.12446)
		(layer "B.Cu")
		(net "PHY_CON_B_TO_IOC_1_DP_C")
	)
	(segment
		(start 159.998664 -19.041872)
		(end 159.749236 -18.69694)
		(width 0.12446)
		(layer "B.Cu")
		(net "PHY_CON_B_TO_IOC_1_DP_C")
	)
	(segment
		(start 166.502334 -24.028146)
		(end 166.238428 -23.76424)
		(width 0.12446)
		(layer "B.Cu")
		(net "PHY_CON_B_TO_IOC_1_DP_C")
	)
	(segment
		(start 167.966136 -38.162738)
		(end 168.074848 -38.054026)
		(width 0.12446)
		(layer "B.Cu")
		(net "PHY_CON_B_TO_IOC_1_DP_C")
	)
	(arc
		(start 159.639 -18.638012)
		(mid 159.544151 -18.628482)
		(end 159.470344 -18.688812)
		(width 0.12446)
		(layer "B.Cu")
		(net "PHY_CON_B_TO_IOC_1_DP_C")
	)
	(segment
		(start 201.595228 -69.104256)
		(end 201.604118 -69.104256)
		(width 0.12446)
		(layer "F.Cu")
		(net "PHY_CON_B_TO_IOC_1_DP")
	)
	(segment
		(start 201.604118 -69.104256)
		(end 201.99985 -69.499988)
		(width 0.12446)
		(layer "F.Cu")
		(net "PHY_CON_B_TO_IOC_1_DP")
	)
	(via
		(at 201.595228 -69.104256)
		(size 0.508)
		(drill 0.254)
		(layers "F.Cu" "B.Cu")
		(net "PHY_CON_B_TO_IOC_1_DP")
	)
	(segment
		(start 214.376 -63.4492)
		(end 213.245446 -65.14719)
		(width 0.12446)
		(layer "B.Cu")
		(net "PHY_CON_B_TO_IOC_1_DP")
	)
	(segment
		(start 177.032412 -40.720518)
		(end 177.39868 -40.647366)
		(width 0.12446)
		(layer "B.Cu")
		(net "PHY_CON_B_TO_IOC_1_DP")
	)
	(segment
		(start 202.670918 -69.998082)
		(end 202.079606 -69.40677)
		(width 0.0889)
		(layer "B.Cu")
		(net "PHY_CON_B_TO_IOC_1_DP")
	)
	(segment
		(start 175.089312 -40.834564)
		(end 175.455326 -40.761158)
		(width 0.12446)
		(layer "B.Cu")
		(net "PHY_CON_B_TO_IOC_1_DP")
	)
	(segment
		(start 205.990444 -69.998082)
		(end 202.670918 -69.998082)
		(width 0.0889)
		(layer "B.Cu")
		(net "PHY_CON_B_TO_IOC_1_DP")
	)
	(segment
		(start 208.502504 -69.890132)
		(end 206.120492 -69.890132)
		(width 0.12446)
		(layer "B.Cu")
		(net "PHY_CON_B_TO_IOC_1_DP")
	)
	(segment
		(start 174.51197 -41.224454)
		(end 174.877984 -41.151302)
		(width 0.12446)
		(layer "B.Cu")
		(net "PHY_CON_B_TO_IOC_1_DP")
	)
	(segment
		(start 168.042336 -39.609268)
		(end 169.606468 -41.1734)
		(width 0.12446)
		(layer "B.Cu")
		(net "PHY_CON_B_TO_IOC_1_DP")
	)
	(segment
		(start 168.042336 -38.797738)
		(end 168.042336 -39.609268)
		(width 0.12446)
		(layer "B.Cu")
		(net "PHY_CON_B_TO_IOC_1_DP")
	)
	(segment
		(start 211.256372 -45.49902)
		(end 212.345778 -47.114206)
		(width 0.12446)
		(layer "B.Cu")
		(net "PHY_CON_B_TO_IOC_1_DP")
	)
	(segment
		(start 213.245446 -65.14719)
		(end 208.502504 -69.890132)
		(width 0.12446)
		(layer "B.Cu")
		(net "PHY_CON_B_TO_IOC_1_DP")
	)
	(segment
		(start 176.138332 -40.899334)
		(end 176.349406 -40.582596)
		(width 0.12446)
		(layer "B.Cu")
		(net "PHY_CON_B_TO_IOC_1_DP")
	)
	(segment
		(start 177.609754 -40.330374)
		(end 177.609754 -40.330628)
		(width 0.12446)
		(layer "B.Cu")
		(net "PHY_CON_B_TO_IOC_1_DP")
	)
	(segment
		(start 202.07605 -69.410326)
		(end 201.724514 -69.410326)
		(width 0.0889)
		(layer "B.Cu")
		(net "PHY_CON_B_TO_IOC_1_DP")
	)
	(segment
		(start 175.455326 -40.761158)
		(end 175.772064 -40.972486)
		(width 0.12446)
		(layer "B.Cu")
		(net "PHY_CON_B_TO_IOC_1_DP")
	)
	(segment
		(start 174.877984 -41.151302)
		(end 175.089312 -40.834564)
		(width 0.12446)
		(layer "B.Cu")
		(net "PHY_CON_B_TO_IOC_1_DP")
	)
	(segment
		(start 173.39437 -41.1734)
		(end 174.194978 -41.01338)
		(width 0.12446)
		(layer "B.Cu")
		(net "PHY_CON_B_TO_IOC_1_DP")
	)
	(segment
		(start 212.345778 -47.114206)
		(end 214.994236 -60.35802)
		(width 0.12446)
		(layer "B.Cu")
		(net "PHY_CON_B_TO_IOC_1_DP")
	)
	(segment
		(start 169.606468 -41.1734)
		(end 173.39437 -41.1734)
		(width 0.12446)
		(layer "B.Cu")
		(net "PHY_CON_B_TO_IOC_1_DP")
	)
	(segment
		(start 175.772064 -40.972486)
		(end 176.138332 -40.899334)
		(width 0.12446)
		(layer "B.Cu")
		(net "PHY_CON_B_TO_IOC_1_DP")
	)
	(segment
		(start 177.609754 -40.330628)
		(end 188.668406 -38.11905)
		(width 0.12446)
		(layer "B.Cu")
		(net "PHY_CON_B_TO_IOC_1_DP")
	)
	(segment
		(start 176.715674 -40.50919)
		(end 177.032412 -40.720518)
		(width 0.12446)
		(layer "B.Cu")
		(net "PHY_CON_B_TO_IOC_1_DP")
	)
	(segment
		(start 188.668406 -38.11905)
		(end 206.056738 -41.59758)
		(width 0.12446)
		(layer "B.Cu")
		(net "PHY_CON_B_TO_IOC_1_DP")
	)
	(segment
		(start 201.595228 -69.28104)
		(end 201.595228 -69.104256)
		(width 0.0889)
		(layer "B.Cu")
		(net "PHY_CON_B_TO_IOC_1_DP")
	)
	(segment
		(start 202.079606 -69.40677)
		(end 202.07605 -69.410326)
		(width 0.0889)
		(layer "B.Cu")
		(net "PHY_CON_B_TO_IOC_1_DP")
	)
	(segment
		(start 176.349406 -40.582596)
		(end 176.715674 -40.50919)
		(width 0.12446)
		(layer "B.Cu")
		(net "PHY_CON_B_TO_IOC_1_DP")
	)
	(segment
		(start 206.056738 -41.59758)
		(end 211.256372 -45.49902)
		(width 0.12446)
		(layer "B.Cu")
		(net "PHY_CON_B_TO_IOC_1_DP")
	)
	(segment
		(start 177.39868 -40.647366)
		(end 177.609754 -40.330374)
		(width 0.12446)
		(layer "B.Cu")
		(net "PHY_CON_B_TO_IOC_1_DP")
	)
	(segment
		(start 214.994236 -60.35802)
		(end 214.376 -63.4492)
		(width 0.12446)
		(layer "B.Cu")
		(net "PHY_CON_B_TO_IOC_1_DP")
	)
	(segment
		(start 206.120492 -69.890132)
		(end 206.098394 -69.890132)
		(width 0.0889)
		(layer "B.Cu")
		(net "PHY_CON_B_TO_IOC_1_DP")
	)
	(segment
		(start 167.966136 -38.721538)
		(end 168.042336 -38.797738)
		(width 0.12446)
		(layer "B.Cu")
		(net "PHY_CON_B_TO_IOC_1_DP")
	)
	(segment
		(start 206.098394 -69.890132)
		(end 205.990444 -69.998082)
		(width 0.0889)
		(layer "B.Cu")
		(net "PHY_CON_B_TO_IOC_1_DP")
	)
	(segment
		(start 174.194978 -41.01338)
		(end 174.51197 -41.224454)
		(width 0.12446)
		(layer "B.Cu")
		(net "PHY_CON_B_TO_IOC_1_DP")
	)
	(arc
		(start 201.724514 -69.410326)
		(mid 201.633095 -69.372459)
		(end 201.595228 -69.28104)
		(width 0.0889)
		(layer "B.Cu")
		(net "PHY_CON_B_TO_IOC_1_DP")
	)
	(segment
		(start 159.830516 -18.279364)
		(end 159.83077 -18.279364)
		(width 0.12446)
		(layer "B.Cu")
		(net "PHY_CON_B_TO_IOC_1_DN_C")
	)
	(segment
		(start 168.481248 -38.04285)
		(end 168.601136 -38.162738)
		(width 0.12446)
		(layer "B.Cu")
		(net "PHY_CON_B_TO_IOC_1_DN_C")
	)
	(segment
		(start 163.702746 -20.27301)
		(end 168.481248 -25.051512)
		(width 0.12446)
		(layer "B.Cu")
		(net "PHY_CON_B_TO_IOC_1_DN_C")
	)
	(segment
		(start 159.83077 -18.279364)
		(end 159.912558 -18.323052)
		(width 0.12446)
		(layer "B.Cu")
		(net "PHY_CON_B_TO_IOC_1_DN_C")
	)
	(segment
		(start 159.999934 -17.69999)
		(end 159.779716 -18.110708)
		(width 0.12446)
		(layer "B.Cu")
		(net "PHY_CON_B_TO_IOC_1_DN_C")
	)
	(segment
		(start 160.405064 -19.370548)
		(end 161.307526 -20.27301)
		(width 0.12446)
		(layer "B.Cu")
		(net "PHY_CON_B_TO_IOC_1_DN_C")
	)
	(segment
		(start 168.481248 -25.051512)
		(end 168.481248 -38.04285)
		(width 0.12446)
		(layer "B.Cu")
		(net "PHY_CON_B_TO_IOC_1_DN_C")
	)
	(segment
		(start 159.935672 -18.335498)
		(end 160.020254 -18.377916)
		(width 0.12446)
		(layer "B.Cu")
		(net "PHY_CON_B_TO_IOC_1_DN_C")
	)
	(segment
		(start 159.912558 -18.323052)
		(end 159.935672 -18.335498)
		(width 0.12446)
		(layer "B.Cu")
		(net "PHY_CON_B_TO_IOC_1_DN_C")
	)
	(segment
		(start 160.020254 -18.377916)
		(end 160.405064 -18.910046)
		(width 0.12446)
		(layer "B.Cu")
		(net "PHY_CON_B_TO_IOC_1_DN_C")
	)
	(segment
		(start 161.307526 -20.27301)
		(end 163.702746 -20.27301)
		(width 0.12446)
		(layer "B.Cu")
		(net "PHY_CON_B_TO_IOC_1_DN_C")
	)
	(segment
		(start 160.405064 -18.910046)
		(end 160.405064 -19.370548)
		(width 0.12446)
		(layer "B.Cu")
		(net "PHY_CON_B_TO_IOC_1_DN_C")
	)
	(arc
		(start 159.779716 -18.110708)
		(mid 159.770186 -18.205557)
		(end 159.830516 -18.279364)
		(width 0.12446)
		(layer "B.Cu")
		(net "PHY_CON_B_TO_IOC_1_DN_C")
	)
	(segment
		(start 201.5998 -69.899784)
		(end 201.200004 -69.499988)
		(width 0.12446)
		(layer "F.Cu")
		(net "PHY_CON_B_TO_IOC_1_DN")
	)
	(segment
		(start 201.609198 -69.899784)
		(end 201.5998 -69.899784)
		(width 0.12446)
		(layer "F.Cu")
		(net "PHY_CON_B_TO_IOC_1_DN")
	)
	(via
		(at 201.609198 -69.899784)
		(size 0.508)
		(drill 0.254)
		(layers "F.Cu" "B.Cu")
		(net "PHY_CON_B_TO_IOC_1_DN")
	)
	(segment
		(start 205.990444 -70.188582)
		(end 202.591924 -70.188582)
		(width 0.0889)
		(layer "B.Cu")
		(net "PHY_CON_B_TO_IOC_1_DN")
	)
	(segment
		(start 206.226918 -41.217088)
		(end 211.555076 -45.215048)
		(width 0.12446)
		(layer "B.Cu")
		(net "PHY_CON_B_TO_IOC_1_DN")
	)
	(segment
		(start 211.555076 -45.215048)
		(end 212.728302 -46.95444)
		(width 0.12446)
		(layer "B.Cu")
		(net "PHY_CON_B_TO_IOC_1_DN")
	)
	(segment
		(start 214.149178 -64.523366)
		(end 213.561422 -65.406016)
		(width 0.12446)
		(layer "B.Cu")
		(net "PHY_CON_B_TO_IOC_1_DN")
	)
	(segment
		(start 214.06866 -53.656484)
		(end 215.408764 -60.35802)
		(width 0.12446)
		(layer "B.Cu")
		(net "PHY_CON_B_TO_IOC_1_DN")
	)
	(segment
		(start 212.728302 -46.95444)
		(end 214.06866 -53.656484)
		(width 0.12446)
		(layer "B.Cu")
		(net "PHY_CON_B_TO_IOC_1_DN")
	)
	(segment
		(start 173.353984 -40.767)
		(end 188.668406 -37.704522)
		(width 0.12446)
		(layer "B.Cu")
		(net "PHY_CON_B_TO_IOC_1_DN")
	)
	(segment
		(start 201.609198 -69.706744)
		(end 201.609198 -69.899784)
		(width 0.0889)
		(layer "B.Cu")
		(net "PHY_CON_B_TO_IOC_1_DN")
	)
	(segment
		(start 206.120492 -70.296532)
		(end 206.098394 -70.296532)
		(width 0.0889)
		(layer "B.Cu")
		(net "PHY_CON_B_TO_IOC_1_DN")
	)
	(segment
		(start 213.561422 -65.406016)
		(end 208.670906 -70.296532)
		(width 0.12446)
		(layer "B.Cu")
		(net "PHY_CON_B_TO_IOC_1_DN")
	)
	(segment
		(start 215.083898 -61.983366)
		(end 214.758778 -63.607696)
		(width 0.12446)
		(layer "B.Cu")
		(net "PHY_CON_B_TO_IOC_1_DN")
	)
	(segment
		(start 202.004168 -69.600826)
		(end 201.714608 -69.600826)
		(width 0.0889)
		(layer "B.Cu")
		(net "PHY_CON_B_TO_IOC_1_DN")
	)
	(segment
		(start 169.77487 -40.767)
		(end 173.353984 -40.767)
		(width 0.12446)
		(layer "B.Cu")
		(net "PHY_CON_B_TO_IOC_1_DN")
	)
	(segment
		(start 168.601136 -38.721538)
		(end 168.448736 -38.873938)
		(width 0.12446)
		(layer "B.Cu")
		(net "PHY_CON_B_TO_IOC_1_DN")
	)
	(segment
		(start 215.408764 -60.35802)
		(end 215.315546 -60.823856)
		(width 0.12446)
		(layer "B.Cu")
		(net "PHY_CON_B_TO_IOC_1_DN")
	)
	(segment
		(start 168.448736 -39.440866)
		(end 169.77487 -40.767)
		(width 0.12446)
		(layer "B.Cu")
		(net "PHY_CON_B_TO_IOC_1_DN")
	)
	(segment
		(start 215.315546 -60.823856)
		(end 215.238584 -61.21019)
		(width 0.12446)
		(layer "B.Cu")
		(net "PHY_CON_B_TO_IOC_1_DN")
	)
	(segment
		(start 168.448736 -38.873938)
		(end 168.448736 -39.440866)
		(width 0.12446)
		(layer "B.Cu")
		(net "PHY_CON_B_TO_IOC_1_DN")
	)
	(segment
		(start 201.640948 -69.631052)
		(end 201.640694 -69.631306)
		(width 0.0889)
		(layer "B.Cu")
		(net "PHY_CON_B_TO_IOC_1_DN")
	)
	(segment
		(start 215.238584 -61.21019)
		(end 215.083644 -61.983366)
		(width 0.12446)
		(layer "B.Cu")
		(net "PHY_CON_B_TO_IOC_1_DN")
	)
	(segment
		(start 188.668406 -37.704522)
		(end 206.226918 -41.217088)
		(width 0.12446)
		(layer "B.Cu")
		(net "PHY_CON_B_TO_IOC_1_DN")
	)
	(segment
		(start 202.591924 -70.188582)
		(end 202.004168 -69.600826)
		(width 0.0889)
		(layer "B.Cu")
		(net "PHY_CON_B_TO_IOC_1_DN")
	)
	(segment
		(start 215.083644 -61.983366)
		(end 215.083898 -61.983366)
		(width 0.12446)
		(layer "B.Cu")
		(net "PHY_CON_B_TO_IOC_1_DN")
	)
	(segment
		(start 206.098394 -70.296532)
		(end 205.990444 -70.188582)
		(width 0.0889)
		(layer "B.Cu")
		(net "PHY_CON_B_TO_IOC_1_DN")
	)
	(segment
		(start 214.758778 -63.607696)
		(end 214.149178 -64.523366)
		(width 0.12446)
		(layer "B.Cu")
		(net "PHY_CON_B_TO_IOC_1_DN")
	)
	(segment
		(start 208.670906 -70.296532)
		(end 206.120492 -70.296532)
		(width 0.12446)
		(layer "B.Cu")
		(net "PHY_CON_B_TO_IOC_1_DN")
	)
	(arc
		(start 201.640694 -69.631306)
		(mid 201.617405 -69.665874)
		(end 201.609198 -69.706744)
		(width 0.0889)
		(layer "B.Cu")
		(net "PHY_CON_B_TO_IOC_1_DN")
	)
	(arc
		(start 201.714608 -69.600826)
		(mid 201.674796 -69.608674)
		(end 201.640948 -69.631052)
		(width 0.0889)
		(layer "B.Cu")
		(net "PHY_CON_B_TO_IOC_1_DN")
	)
	(segment
		(start 168.474136 -23.87219)
		(end 168.209976 -23.60803)
		(width 0.12446)
		(layer "B.Cu")
		(net "PHY_CON_B_TO_IOC_0_DP_C")
	)
	(segment
		(start 168.854882 -23.87219)
		(end 168.474136 -23.87219)
		(width 0.12446)
		(layer "B.Cu")
		(net "PHY_CON_B_TO_IOC_0_DP_C")
	)
	(segment
		(start 162.59429 -19.3802)
		(end 162.387534 -19.173444)
		(width 0.12446)
		(layer "B.Cu")
		(net "PHY_CON_B_TO_IOC_0_DP_C")
	)
	(segment
		(start 167.301164 -22.318472)
		(end 164.362892 -19.3802)
		(width 0.12446)
		(layer "B.Cu")
		(net "PHY_CON_B_TO_IOC_0_DP_C")
	)
	(segment
		(start 169.451274 -24.468582)
		(end 168.854882 -23.87219)
		(width 0.12446)
		(layer "B.Cu")
		(net "PHY_CON_B_TO_IOC_0_DP_C")
	)
	(segment
		(start 167.94607 -22.963378)
		(end 167.565324 -22.963378)
		(width 0.12446)
		(layer "B.Cu")
		(net "PHY_CON_B_TO_IOC_0_DP_C")
	)
	(segment
		(start 167.565324 -22.963378)
		(end 167.301164 -22.699218)
		(width 0.12446)
		(layer "B.Cu")
		(net "PHY_CON_B_TO_IOC_0_DP_C")
	)
	(segment
		(start 168.209976 -23.60803)
		(end 168.209976 -23.227284)
		(width 0.12446)
		(layer "B.Cu")
		(net "PHY_CON_B_TO_IOC_0_DP_C")
	)
	(segment
		(start 162.387534 -19.173444)
		(end 162.382708 -19.168364)
		(width 0.12446)
		(layer "B.Cu")
		(net "PHY_CON_B_TO_IOC_0_DP_C")
	)
	(segment
		(start 162.382708 -19.168364)
		(end 161.888932 -18.638012)
		(width 0.12446)
		(layer "B.Cu")
		(net "PHY_CON_B_TO_IOC_0_DP_C")
	)
	(segment
		(start 168.209976 -23.227284)
		(end 167.94607 -22.963378)
		(width 0.12446)
		(layer "B.Cu")
		(net "PHY_CON_B_TO_IOC_0_DP_C")
	)
	(segment
		(start 167.301164 -22.699218)
		(end 167.301164 -22.318472)
		(width 0.12446)
		(layer "B.Cu")
		(net "PHY_CON_B_TO_IOC_0_DP_C")
	)
	(segment
		(start 169.33799 -38.162738)
		(end 169.451274 -38.049454)
		(width 0.12446)
		(layer "B.Cu")
		(net "PHY_CON_B_TO_IOC_0_DP_C")
	)
	(segment
		(start 169.451274 -38.049454)
		(end 169.451274 -24.468582)
		(width 0.12446)
		(layer "B.Cu")
		(net "PHY_CON_B_TO_IOC_0_DP_C")
	)
	(segment
		(start 164.362892 -19.3802)
		(end 162.59429 -19.3802)
		(width 0.12446)
		(layer "B.Cu")
		(net "PHY_CON_B_TO_IOC_0_DP_C")
	)
	(segment
		(start 161.720276 -18.688812)
		(end 161.500058 -19.100038)
		(width 0.12446)
		(layer "B.Cu")
		(net "PHY_CON_B_TO_IOC_0_DP_C")
	)
	(arc
		(start 161.888932 -18.638012)
		(mid 161.794083 -18.628482)
		(end 161.720276 -18.688812)
		(width 0.12446)
		(layer "B.Cu")
		(net "PHY_CON_B_TO_IOC_0_DP_C")
	)
	(segment
		(start 202.404472 -70.704456)
		(end 201.99985 -70.299834)
		(width 0.12446)
		(layer "F.Cu")
		(net "PHY_CON_B_TO_IOC_0_DP")
	)
	(via
		(at 202.404472 -70.704456)
		(size 0.508)
		(drill 0.254)
		(layers "F.Cu" "B.Cu")
		(net "PHY_CON_B_TO_IOC_0_DP")
	)
	(segment
		(start 171.037758 -39.936166)
		(end 169.887138 -39.712392)
		(width 0.12446)
		(layer "B.Cu")
		(net "PHY_CON_B_TO_IOC_0_DP")
	)
	(segment
		(start 169.558208 -39.383208)
		(end 169.439336 -39.264336)
		(width 0.12446)
		(layer "B.Cu")
		(net "PHY_CON_B_TO_IOC_0_DP")
	)
	(segment
		(start 174.080678 -39.345108)
		(end 173.867826 -39.66083)
		(width 0.12446)
		(layer "B.Cu")
		(net "PHY_CON_B_TO_IOC_0_DP")
	)
	(segment
		(start 175.708818 -39.028878)
		(end 175.342296 -39.099998)
		(width 0.12446)
		(layer "B.Cu")
		(net "PHY_CON_B_TO_IOC_0_DP")
	)
	(segment
		(start 206.209392 -71.63435)
		(end 206.317342 -71.5264)
		(width 0.0889)
		(layer "B.Cu")
		(net "PHY_CON_B_TO_IOC_0_DP")
	)
	(segment
		(start 187.952126 -36.650676)
		(end 187.615068 -36.716208)
		(width 0.12446)
		(layer "B.Cu")
		(net "PHY_CON_B_TO_IOC_0_DP")
	)
	(segment
		(start 176.02454 -39.24173)
		(end 175.708818 -39.028878)
		(width 0.12446)
		(layer "B.Cu")
		(net "PHY_CON_B_TO_IOC_0_DP")
	)
	(segment
		(start 187.615068 -36.716208)
		(end 186.809126 -36.872926)
		(width 0.12446)
		(layer "B.Cu")
		(net "PHY_CON_B_TO_IOC_0_DP")
	)
	(segment
		(start 206.576676 -40.37711)
		(end 187.952126 -36.650676)
		(width 0.12446)
		(layer "B.Cu")
		(net "PHY_CON_B_TO_IOC_0_DP")
	)
	(segment
		(start 214.968582 -66.777616)
		(end 215.625934 -63.490602)
		(width 0.12446)
		(layer "B.Cu")
		(net "PHY_CON_B_TO_IOC_0_DP")
	)
	(segment
		(start 215.625934 -63.490602)
		(end 216.283032 -60.20435)
		(width 0.12446)
		(layer "B.Cu")
		(net "PHY_CON_B_TO_IOC_0_DP")
	)
	(segment
		(start 202.616054 -70.916038)
		(end 202.647804 -70.916038)
		(width 0.0889)
		(layer "B.Cu")
		(net "PHY_CON_B_TO_IOC_0_DP")
	)
	(segment
		(start 173.185582 -39.519098)
		(end 171.037758 -39.936166)
		(width 0.12446)
		(layer "B.Cu")
		(net "PHY_CON_B_TO_IOC_0_DP")
	)
	(segment
		(start 169.439336 -39.264336)
		(end 169.439336 -38.822884)
		(width 0.12446)
		(layer "B.Cu")
		(net "PHY_CON_B_TO_IOC_0_DP")
	)
	(segment
		(start 213.543642 -46.504606)
		(end 212.258148 -44.598844)
		(width 0.12446)
		(layer "B.Cu")
		(net "PHY_CON_B_TO_IOC_0_DP")
	)
	(segment
		(start 185.382154 -37.149786)
		(end 185.015632 -37.22116)
		(width 0.12446)
		(layer "B.Cu")
		(net "PHY_CON_B_TO_IOC_0_DP")
	)
	(segment
		(start 177.65268 -38.9255)
		(end 177.286158 -38.996874)
		(width 0.12446)
		(layer "B.Cu")
		(net "PHY_CON_B_TO_IOC_0_DP")
	)
	(segment
		(start 177.286158 -38.996874)
		(end 176.970436 -38.783768)
		(width 0.12446)
		(layer "B.Cu")
		(net "PHY_CON_B_TO_IOC_0_DP")
	)
	(segment
		(start 202.921362 -71.189596)
		(end 205.246732 -71.189596)
		(width 0.0889)
		(layer "B.Cu")
		(net "PHY_CON_B_TO_IOC_0_DP")
	)
	(segment
		(start 210.219798 -71.5264)
		(end 214.968582 -66.777616)
		(width 0.12446)
		(layer "B.Cu")
		(net "PHY_CON_B_TO_IOC_0_DP")
	)
	(segment
		(start 169.887138 -39.712392)
		(end 169.558208 -39.383462)
		(width 0.12446)
		(layer "B.Cu")
		(net "PHY_CON_B_TO_IOC_0_DP")
	)
	(segment
		(start 216.283032 -60.20435)
		(end 214.91321 -53.354478)
		(width 0.12446)
		(layer "B.Cu")
		(net "PHY_CON_B_TO_IOC_0_DP")
	)
	(segment
		(start 176.603914 -38.854888)
		(end 176.391062 -39.17061)
		(width 0.12446)
		(layer "B.Cu")
		(net "PHY_CON_B_TO_IOC_0_DP")
	)
	(segment
		(start 184.120536 -37.394896)
		(end 183.754014 -37.46627)
		(width 0.12446)
		(layer "B.Cu")
		(net "PHY_CON_B_TO_IOC_0_DP")
	)
	(segment
		(start 177.865532 -38.610032)
		(end 177.65268 -38.9255)
		(width 0.12446)
		(layer "B.Cu")
		(net "PHY_CON_B_TO_IOC_0_DP")
	)
	(segment
		(start 206.33944 -71.5264)
		(end 210.219798 -71.5264)
		(width 0.12446)
		(layer "B.Cu")
		(net "PHY_CON_B_TO_IOC_0_DP")
	)
	(segment
		(start 182.858918 -37.640006)
		(end 177.865532 -38.610032)
		(width 0.12446)
		(layer "B.Cu")
		(net "PHY_CON_B_TO_IOC_0_DP")
	)
	(segment
		(start 176.391062 -39.17061)
		(end 176.02454 -39.24173)
		(width 0.12446)
		(layer "B.Cu")
		(net "PHY_CON_B_TO_IOC_0_DP")
	)
	(segment
		(start 169.558208 -39.383462)
		(end 169.558208 -39.383208)
		(width 0.12446)
		(layer "B.Cu")
		(net "PHY_CON_B_TO_IOC_0_DP")
	)
	(segment
		(start 205.246732 -71.189596)
		(end 205.691486 -71.63435)
		(width 0.0889)
		(layer "B.Cu")
		(net "PHY_CON_B_TO_IOC_0_DP")
	)
	(segment
		(start 183.17464 -37.853112)
		(end 182.858918 -37.640006)
		(width 0.12446)
		(layer "B.Cu")
		(net "PHY_CON_B_TO_IOC_0_DP")
	)
	(segment
		(start 205.691486 -71.63435)
		(end 206.209392 -71.63435)
		(width 0.0889)
		(layer "B.Cu")
		(net "PHY_CON_B_TO_IOC_0_DP")
	)
	(segment
		(start 183.541162 -37.781738)
		(end 183.17464 -37.853112)
		(width 0.12446)
		(layer "B.Cu")
		(net "PHY_CON_B_TO_IOC_0_DP")
	)
	(segment
		(start 202.647804 -70.916038)
		(end 202.921362 -71.189596)
		(width 0.0889)
		(layer "B.Cu")
		(net "PHY_CON_B_TO_IOC_0_DP")
	)
	(segment
		(start 184.80278 -37.536628)
		(end 184.436258 -37.608002)
		(width 0.12446)
		(layer "B.Cu")
		(net "PHY_CON_B_TO_IOC_0_DP")
	)
	(segment
		(start 174.4472 -39.273988)
		(end 174.080678 -39.345108)
		(width 0.12446)
		(layer "B.Cu")
		(net "PHY_CON_B_TO_IOC_0_DP")
	)
	(segment
		(start 184.436258 -37.608002)
		(end 184.120536 -37.394896)
		(width 0.12446)
		(layer "B.Cu")
		(net "PHY_CON_B_TO_IOC_0_DP")
	)
	(segment
		(start 214.91321 -53.354478)
		(end 213.543642 -46.504606)
		(width 0.12446)
		(layer "B.Cu")
		(net "PHY_CON_B_TO_IOC_0_DP")
	)
	(segment
		(start 176.970436 -38.783768)
		(end 176.603914 -38.854888)
		(width 0.12446)
		(layer "B.Cu")
		(net "PHY_CON_B_TO_IOC_0_DP")
	)
	(segment
		(start 186.27725 -36.97605)
		(end 186.064398 -37.291518)
		(width 0.12446)
		(layer "B.Cu")
		(net "PHY_CON_B_TO_IOC_0_DP")
	)
	(segment
		(start 183.754014 -37.46627)
		(end 183.541162 -37.781738)
		(width 0.12446)
		(layer "B.Cu")
		(net "PHY_CON_B_TO_IOC_0_DP")
	)
	(segment
		(start 186.809126 -36.872926)
		(end 186.27725 -36.97605)
		(width 0.12446)
		(layer "B.Cu")
		(net "PHY_CON_B_TO_IOC_0_DP")
	)
	(segment
		(start 173.867826 -39.66083)
		(end 173.501304 -39.73195)
		(width 0.12446)
		(layer "B.Cu")
		(net "PHY_CON_B_TO_IOC_0_DP")
	)
	(segment
		(start 185.697876 -37.362892)
		(end 185.382154 -37.149786)
		(width 0.12446)
		(layer "B.Cu")
		(net "PHY_CON_B_TO_IOC_0_DP")
	)
	(segment
		(start 173.501304 -39.73195)
		(end 173.185582 -39.519098)
		(width 0.12446)
		(layer "B.Cu")
		(net "PHY_CON_B_TO_IOC_0_DP")
	)
	(segment
		(start 202.404472 -70.704456)
		(end 202.616054 -70.916038)
		(width 0.0889)
		(layer "B.Cu")
		(net "PHY_CON_B_TO_IOC_0_DP")
	)
	(segment
		(start 212.258148 -44.598844)
		(end 206.576676 -40.37711)
		(width 0.12446)
		(layer "B.Cu")
		(net "PHY_CON_B_TO_IOC_0_DP")
	)
	(segment
		(start 169.439336 -38.822884)
		(end 169.33799 -38.721538)
		(width 0.12446)
		(layer "B.Cu")
		(net "PHY_CON_B_TO_IOC_0_DP")
	)
	(segment
		(start 175.342296 -39.099998)
		(end 175.129444 -39.41572)
		(width 0.12446)
		(layer "B.Cu")
		(net "PHY_CON_B_TO_IOC_0_DP")
	)
	(segment
		(start 175.129444 -39.41572)
		(end 174.762922 -39.48684)
		(width 0.12446)
		(layer "B.Cu")
		(net "PHY_CON_B_TO_IOC_0_DP")
	)
	(segment
		(start 206.317342 -71.5264)
		(end 206.33944 -71.5264)
		(width 0.0889)
		(layer "B.Cu")
		(net "PHY_CON_B_TO_IOC_0_DP")
	)
	(segment
		(start 185.015632 -37.22116)
		(end 184.80278 -37.536628)
		(width 0.12446)
		(layer "B.Cu")
		(net "PHY_CON_B_TO_IOC_0_DP")
	)
	(segment
		(start 174.762922 -39.48684)
		(end 174.4472 -39.273988)
		(width 0.12446)
		(layer "B.Cu")
		(net "PHY_CON_B_TO_IOC_0_DP")
	)
	(segment
		(start 186.064398 -37.291518)
		(end 185.697876 -37.362892)
		(width 0.12446)
		(layer "B.Cu")
		(net "PHY_CON_B_TO_IOC_0_DP")
	)
	(segment
		(start 169.857674 -24.30018)
		(end 164.531294 -18.9738)
		(width 0.12446)
		(layer "B.Cu")
		(net "PHY_CON_B_TO_IOC_0_DN_C")
	)
	(segment
		(start 162.029902 -18.111216)
		(end 162.25012 -17.69999)
		(width 0.12446)
		(layer "B.Cu")
		(net "PHY_CON_B_TO_IOC_0_DN_C")
	)
	(segment
		(start 162.680142 -18.89125)
		(end 162.186366 -18.360898)
		(width 0.12446)
		(layer "B.Cu")
		(net "PHY_CON_B_TO_IOC_0_DN_C")
	)
	(segment
		(start 169.857674 -38.047422)
		(end 169.857674 -24.30018)
		(width 0.12446)
		(layer "B.Cu")
		(net "PHY_CON_B_TO_IOC_0_DN_C")
	)
	(segment
		(start 164.531294 -18.9738)
		(end 162.762692 -18.9738)
		(width 0.12446)
		(layer "B.Cu")
		(net "PHY_CON_B_TO_IOC_0_DN_C")
	)
	(segment
		(start 162.762692 -18.9738)
		(end 162.680142 -18.89125)
		(width 0.12446)
		(layer "B.Cu")
		(net "PHY_CON_B_TO_IOC_0_DN_C")
	)
	(segment
		(start 162.186366 -18.360898)
		(end 162.080702 -18.279618)
		(width 0.12446)
		(layer "B.Cu")
		(net "PHY_CON_B_TO_IOC_0_DN_C")
	)
	(segment
		(start 169.97299 -38.162738)
		(end 169.857674 -38.047422)
		(width 0.12446)
		(layer "B.Cu")
		(net "PHY_CON_B_TO_IOC_0_DN_C")
	)
	(arc
		(start 162.080702 -18.279618)
		(mid 162.020405 -18.205918)
		(end 162.029902 -18.111216)
		(width 0.12446)
		(layer "B.Cu")
		(net "PHY_CON_B_TO_IOC_0_DN_C")
	)
	(segment
		(start 201.59345 -70.702678)
		(end 201.59345 -70.69328)
		(width 0.12446)
		(layer "F.Cu")
		(net "PHY_CON_B_TO_IOC_0_DN")
	)
	(segment
		(start 201.59345 -70.69328)
		(end 201.200004 -70.299834)
		(width 0.12446)
		(layer "F.Cu")
		(net "PHY_CON_B_TO_IOC_0_DN")
	)
	(via
		(at 201.59345 -70.702678)
		(size 0.508)
		(drill 0.254)
		(layers "F.Cu" "B.Cu")
		(net "PHY_CON_B_TO_IOC_0_DN")
	)
	(segment
		(start 205.167738 -71.380096)
		(end 205.612492 -71.82485)
		(width 0.0889)
		(layer "B.Cu")
		(net "PHY_CON_B_TO_IOC_0_DN")
	)
	(segment
		(start 205.612492 -71.82485)
		(end 206.209392 -71.82485)
		(width 0.0889)
		(layer "B.Cu")
		(net "PHY_CON_B_TO_IOC_0_DN")
	)
	(segment
		(start 213.926166 -46.34484)
		(end 212.556344 -44.313856)
		(width 0.12446)
		(layer "B.Cu")
		(net "PHY_CON_B_TO_IOC_0_DN")
	)
	(segment
		(start 214.626952 -49.849786)
		(end 213.926166 -46.34484)
		(width 0.12446)
		(layer "B.Cu")
		(net "PHY_CON_B_TO_IOC_0_DN")
	)
	(segment
		(start 206.33944 -71.9328)
		(end 210.3882 -71.9328)
		(width 0.12446)
		(layer "B.Cu")
		(net "PHY_CON_B_TO_IOC_0_DN")
	)
	(segment
		(start 187.537598 -36.317174)
		(end 186.731656 -36.473892)
		(width 0.12446)
		(layer "B.Cu")
		(net "PHY_CON_B_TO_IOC_0_DN")
	)
	(segment
		(start 212.556344 -44.313856)
		(end 206.74584 -39.996364)
		(width 0.12446)
		(layer "B.Cu")
		(net "PHY_CON_B_TO_IOC_0_DN")
	)
	(segment
		(start 169.845736 -38.848792)
		(end 169.97299 -38.721538)
		(width 0.12446)
		(layer "B.Cu")
		(net "PHY_CON_B_TO_IOC_0_DN")
	)
	(segment
		(start 201.995532 -71.106538)
		(end 202.56881 -71.106538)
		(width 0.0889)
		(layer "B.Cu")
		(net "PHY_CON_B_TO_IOC_0_DN")
	)
	(segment
		(start 216.69756 -60.20435)
		(end 214.626952 -49.849786)
		(width 0.12446)
		(layer "B.Cu")
		(net "PHY_CON_B_TO_IOC_0_DN")
	)
	(segment
		(start 202.56881 -71.106538)
		(end 202.842368 -71.380096)
		(width 0.0889)
		(layer "B.Cu")
		(net "PHY_CON_B_TO_IOC_0_DN")
	)
	(segment
		(start 186.19978 -36.576762)
		(end 171.037758 -39.522146)
		(width 0.12446)
		(layer "B.Cu")
		(net "PHY_CON_B_TO_IOC_0_DN")
	)
	(segment
		(start 210.3882 -71.9328)
		(end 215.342978 -66.978022)
		(width 0.12446)
		(layer "B.Cu")
		(net "PHY_CON_B_TO_IOC_0_DN")
	)
	(segment
		(start 206.209392 -71.82485)
		(end 206.317342 -71.9328)
		(width 0.0889)
		(layer "B.Cu")
		(net "PHY_CON_B_TO_IOC_0_DN")
	)
	(segment
		(start 170.086782 -39.33698)
		(end 169.845736 -39.095934)
		(width 0.12446)
		(layer "B.Cu")
		(net "PHY_CON_B_TO_IOC_0_DN")
	)
	(segment
		(start 171.037758 -39.522146)
		(end 170.086782 -39.33698)
		(width 0.12446)
		(layer "B.Cu")
		(net "PHY_CON_B_TO_IOC_0_DN")
	)
	(segment
		(start 206.317342 -71.9328)
		(end 206.33944 -71.9328)
		(width 0.0889)
		(layer "B.Cu")
		(net "PHY_CON_B_TO_IOC_0_DN")
	)
	(segment
		(start 202.842368 -71.380096)
		(end 205.167738 -71.380096)
		(width 0.0889)
		(layer "B.Cu")
		(net "PHY_CON_B_TO_IOC_0_DN")
	)
	(segment
		(start 215.342978 -66.978022)
		(end 216.69756 -60.20435)
		(width 0.12446)
		(layer "B.Cu")
		(net "PHY_CON_B_TO_IOC_0_DN")
	)
	(segment
		(start 206.74584 -39.996364)
		(end 187.953142 -36.236402)
		(width 0.12446)
		(layer "B.Cu")
		(net "PHY_CON_B_TO_IOC_0_DN")
	)
	(segment
		(start 169.845736 -39.095934)
		(end 169.845736 -38.848792)
		(width 0.12446)
		(layer "B.Cu")
		(net "PHY_CON_B_TO_IOC_0_DN")
	)
	(segment
		(start 187.953142 -36.236402)
		(end 187.537598 -36.317174)
		(width 0.12446)
		(layer "B.Cu")
		(net "PHY_CON_B_TO_IOC_0_DN")
	)
	(segment
		(start 201.59345 -70.702678)
		(end 201.995532 -71.106538)
		(width 0.0889)
		(layer "B.Cu")
		(net "PHY_CON_B_TO_IOC_0_DN")
	)
	(segment
		(start 186.731656 -36.473892)
		(end 186.465972 -36.525454)
		(width 0.12446)
		(layer "B.Cu")
		(net "PHY_CON_B_TO_IOC_0_DN")
	)
	(segment
		(start 186.19978 -36.577016)
		(end 186.19978 -36.576762)
		(width 0.12446)
		(layer "B.Cu")
		(net "PHY_CON_B_TO_IOC_0_DN")
	)
	(segment
		(start 186.465972 -36.525454)
		(end 186.19978 -36.577016)
		(width 0.12446)
		(layer "B.Cu")
		(net "PHY_CON_B_TO_IOC_0_DN")
	)
	(segment
		(start 179.872894 -23.342854)
		(end 179.872894 -22.671786)
		(width 0.12446)
		(layer "B.Cu")
		(net "PHY_CON_A_TO_IOC_3_DP_C")
	)
	(segment
		(start 179.639468 -22.43836)
		(end 179.63896 -22.438106)
		(width 0.12446)
		(layer "B.Cu")
		(net "PHY_CON_A_TO_IOC_3_DP_C")
	)
	(segment
		(start 182.914544 -24.678386)
		(end 181.208426 -24.678386)
		(width 0.12446)
		(layer "B.Cu")
		(net "PHY_CON_A_TO_IOC_3_DP_C")
	)
	(segment
		(start 181.208426 -24.678386)
		(end 179.872894 -23.342854)
		(width 0.12446)
		(layer "B.Cu")
		(net "PHY_CON_A_TO_IOC_3_DP_C")
	)
	(segment
		(start 179.872894 -22.671786)
		(end 179.639468 -22.43836)
		(width 0.12446)
		(layer "B.Cu")
		(net "PHY_CON_A_TO_IOC_3_DP_C")
	)
	(segment
		(start 184.03316 -25.797002)
		(end 182.914544 -24.678386)
		(width 0.12446)
		(layer "B.Cu")
		(net "PHY_CON_A_TO_IOC_3_DP_C")
	)
	(segment
		(start 179.470304 -22.488906)
		(end 179.250086 -22.899878)
		(width 0.12446)
		(layer "B.Cu")
		(net "PHY_CON_A_TO_IOC_3_DP_C")
	)
	(segment
		(start 191.299338 -25.797002)
		(end 184.03316 -25.797002)
		(width 0.12446)
		(layer "B.Cu")
		(net "PHY_CON_A_TO_IOC_3_DP_C")
	)
	(segment
		(start 191.410336 -25.908)
		(end 191.299338 -25.797002)
		(width 0.12446)
		(layer "B.Cu")
		(net "PHY_CON_A_TO_IOC_3_DP_C")
	)
	(arc
		(start 179.63896 -22.438106)
		(mid 179.544111 -22.428576)
		(end 179.470304 -22.488906)
		(width 0.12446)
		(layer "B.Cu")
		(net "PHY_CON_A_TO_IOC_3_DP_C")
	)
	(segment
		(start 201.602848 -71.503032)
		(end 201.99985 -71.900034)
		(width 0.12446)
		(layer "F.Cu")
		(net "PHY_CON_A_TO_IOC_3_DP")
	)
	(segment
		(start 201.594466 -71.503032)
		(end 201.602848 -71.503032)
		(width 0.12446)
		(layer "F.Cu")
		(net "PHY_CON_A_TO_IOC_3_DP")
	)
	(via
		(at 201.594466 -71.503032)
		(size 0.508)
		(drill 0.254)
		(layers "F.Cu" "B.Cu")
		(net "PHY_CON_A_TO_IOC_3_DP")
	)
	(segment
		(start 198.395082 -27.831288)
		(end 198.704708 -28.040076)
		(width 0.12446)
		(layer "B.Cu")
		(net "PHY_CON_A_TO_IOC_3_DP")
	)
	(segment
		(start 201.594466 -71.695056)
		(end 201.594466 -71.503032)
		(width 0.0889)
		(layer "B.Cu")
		(net "PHY_CON_A_TO_IOC_3_DP")
	)
	(segment
		(start 200.152508 -29.341318)
		(end 200.525888 -29.268674)
		(width 0.12446)
		(layer "B.Cu")
		(net "PHY_CON_A_TO_IOC_3_DP")
	)
	(segment
		(start 204.65796 -72.02678)
		(end 204.635862 -72.02678)
		(width 0.0889)
		(layer "B.Cu")
		(net "PHY_CON_A_TO_IOC_3_DP")
	)
	(segment
		(start 206.839312 -33.851596)
		(end 207.148684 -34.060384)
		(width 0.12446)
		(layer "B.Cu")
		(net "PHY_CON_A_TO_IOC_3_DP")
	)
	(segment
		(start 204.527912 -72.13473)
		(end 204.13726 -72.13473)
		(width 0.0889)
		(layer "B.Cu")
		(net "PHY_CON_A_TO_IOC_3_DP")
	)
	(segment
		(start 198.777352 -28.413964)
		(end 199.086978 -28.622752)
		(width 0.12446)
		(layer "B.Cu")
		(net "PHY_CON_A_TO_IOC_3_DP")
	)
	(segment
		(start 204.635862 -72.02678)
		(end 204.527912 -72.13473)
		(width 0.0889)
		(layer "B.Cu")
		(net "PHY_CON_A_TO_IOC_3_DP")
	)
	(segment
		(start 197.711822 -27.695144)
		(end 198.021448 -27.903932)
		(width 0.12446)
		(layer "B.Cu")
		(net "PHY_CON_A_TO_IOC_3_DP")
	)
	(segment
		(start 213.974172 -41.475406)
		(end 217.72245 -60.761118)
		(width 0.12446)
		(layer "B.Cu")
		(net "PHY_CON_A_TO_IOC_3_DP")
	)
	(segment
		(start 205.735682 -72.74306)
		(end 205.019402 -72.02678)
		(width 0.12446)
		(layer "B.Cu")
		(net "PHY_CON_A_TO_IOC_3_DP")
	)
	(segment
		(start 191.969136 -25.908)
		(end 192.051686 -25.82545)
		(width 0.12446)
		(layer "B.Cu")
		(net "PHY_CON_A_TO_IOC_3_DP")
	)
	(segment
		(start 207.522572 -33.98774)
		(end 207.832198 -34.196528)
		(width 0.12446)
		(layer "B.Cu")
		(net "PHY_CON_A_TO_IOC_3_DP")
	)
	(segment
		(start 199.842882 -29.13253)
		(end 200.152508 -29.341318)
		(width 0.12446)
		(layer "B.Cu")
		(net "PHY_CON_A_TO_IOC_3_DP")
	)
	(segment
		(start 202.145138 -71.906638)
		(end 202.044046 -71.805546)
		(width 0.0889)
		(layer "B.Cu")
		(net "PHY_CON_A_TO_IOC_3_DP")
	)
	(segment
		(start 192.051686 -25.82545)
		(end 194.098926 -25.82545)
		(width 0.12446)
		(layer "B.Cu")
		(net "PHY_CON_A_TO_IOC_3_DP")
	)
	(segment
		(start 206.083154 -33.341564)
		(end 206.457042 -33.26892)
		(width 0.12446)
		(layer "B.Cu")
		(net "PHY_CON_A_TO_IOC_3_DP")
	)
	(segment
		(start 202.757532 -71.906638)
		(end 202.145138 -71.906638)
		(width 0.0889)
		(layer "B.Cu")
		(net "PHY_CON_A_TO_IOC_3_DP")
	)
	(segment
		(start 199.460612 -28.550108)
		(end 199.770238 -28.758896)
		(width 0.12446)
		(layer "B.Cu")
		(net "PHY_CON_A_TO_IOC_3_DP")
	)
	(segment
		(start 207.904842 -34.570162)
		(end 208.214214 -34.77895)
		(width 0.12446)
		(layer "B.Cu")
		(net "PHY_CON_A_TO_IOC_3_DP")
	)
	(segment
		(start 195.956682 -26.186638)
		(end 195.956428 -26.186892)
		(width 0.12446)
		(layer "B.Cu")
		(net "PHY_CON_A_TO_IOC_3_DP")
	)
	(segment
		(start 205.701138 -32.759142)
		(end 205.773782 -33.132776)
		(width 0.12446)
		(layer "B.Cu")
		(net "PHY_CON_A_TO_IOC_3_DP")
	)
	(segment
		(start 216.293192 -68.119498)
		(end 211.669884 -72.74306)
		(width 0.12446)
		(layer "B.Cu")
		(net "PHY_CON_A_TO_IOC_3_DP")
	)
	(segment
		(start 206.457042 -33.26892)
		(end 206.766668 -33.477708)
		(width 0.12446)
		(layer "B.Cu")
		(net "PHY_CON_A_TO_IOC_3_DP")
	)
	(segment
		(start 197.639178 -27.32151)
		(end 197.711822 -27.695144)
		(width 0.12446)
		(layer "B.Cu")
		(net "PHY_CON_A_TO_IOC_3_DP")
	)
	(segment
		(start 207.148684 -34.060384)
		(end 207.522572 -33.98774)
		(width 0.12446)
		(layer "B.Cu")
		(net "PHY_CON_A_TO_IOC_3_DP")
	)
	(segment
		(start 207.832198 -34.196528)
		(end 207.904842 -34.570162)
		(width 0.12446)
		(layer "B.Cu")
		(net "PHY_CON_A_TO_IOC_3_DP")
	)
	(segment
		(start 208.214214 -34.77895)
		(end 208.588102 -34.706306)
		(width 0.12446)
		(layer "B.Cu")
		(net "PHY_CON_A_TO_IOC_3_DP")
	)
	(segment
		(start 205.773782 -33.132776)
		(end 206.083154 -33.341564)
		(width 0.12446)
		(layer "B.Cu")
		(net "PHY_CON_A_TO_IOC_3_DP")
	)
	(segment
		(start 195.956428 -26.186892)
		(end 197.639178 -27.32151)
		(width 0.12446)
		(layer "B.Cu")
		(net "PHY_CON_A_TO_IOC_3_DP")
	)
	(segment
		(start 210.094322 -35.722306)
		(end 213.974172 -41.475406)
		(width 0.12446)
		(layer "B.Cu")
		(net "PHY_CON_A_TO_IOC_3_DP")
	)
	(segment
		(start 217.72245 -60.761118)
		(end 216.293192 -68.119498)
		(width 0.12446)
		(layer "B.Cu")
		(net "PHY_CON_A_TO_IOC_3_DP")
	)
	(segment
		(start 200.526142 -29.268674)
		(end 205.701138 -32.759142)
		(width 0.12446)
		(layer "B.Cu")
		(net "PHY_CON_A_TO_IOC_3_DP")
	)
	(segment
		(start 203.71181 -71.70928)
		(end 202.95489 -71.70928)
		(width 0.0889)
		(layer "B.Cu")
		(net "PHY_CON_A_TO_IOC_3_DP")
	)
	(segment
		(start 205.019402 -72.02678)
		(end 204.65796 -72.02678)
		(width 0.12446)
		(layer "B.Cu")
		(net "PHY_CON_A_TO_IOC_3_DP")
	)
	(segment
		(start 206.766668 -33.477708)
		(end 206.839312 -33.851596)
		(width 0.12446)
		(layer "B.Cu")
		(net "PHY_CON_A_TO_IOC_3_DP")
	)
	(segment
		(start 194.098926 -25.82545)
		(end 195.956682 -26.186638)
		(width 0.12446)
		(layer "B.Cu")
		(net "PHY_CON_A_TO_IOC_3_DP")
	)
	(segment
		(start 202.044046 -71.805546)
		(end 201.708512 -71.805546)
		(width 0.0889)
		(layer "B.Cu")
		(net "PHY_CON_A_TO_IOC_3_DP")
	)
	(segment
		(start 208.588102 -34.706306)
		(end 210.094322 -35.722306)
		(width 0.12446)
		(layer "B.Cu")
		(net "PHY_CON_A_TO_IOC_3_DP")
	)
	(segment
		(start 199.086978 -28.622752)
		(end 199.460612 -28.550108)
		(width 0.12446)
		(layer "B.Cu")
		(net "PHY_CON_A_TO_IOC_3_DP")
	)
	(segment
		(start 198.704708 -28.040076)
		(end 198.777352 -28.413964)
		(width 0.12446)
		(layer "B.Cu")
		(net "PHY_CON_A_TO_IOC_3_DP")
	)
	(segment
		(start 199.770238 -28.758896)
		(end 199.842882 -29.13253)
		(width 0.12446)
		(layer "B.Cu")
		(net "PHY_CON_A_TO_IOC_3_DP")
	)
	(segment
		(start 200.525888 -29.268674)
		(end 200.526142 -29.268674)
		(width 0.12446)
		(layer "B.Cu")
		(net "PHY_CON_A_TO_IOC_3_DP")
	)
	(segment
		(start 198.021448 -27.903932)
		(end 198.395082 -27.831288)
		(width 0.12446)
		(layer "B.Cu")
		(net "PHY_CON_A_TO_IOC_3_DP")
	)
	(segment
		(start 211.669884 -72.74306)
		(end 205.735682 -72.74306)
		(width 0.12446)
		(layer "B.Cu")
		(net "PHY_CON_A_TO_IOC_3_DP")
	)
	(segment
		(start 202.95489 -71.70928)
		(end 202.757532 -71.906638)
		(width 0.0889)
		(layer "B.Cu")
		(net "PHY_CON_A_TO_IOC_3_DP")
	)
	(segment
		(start 204.13726 -72.13473)
		(end 203.71181 -71.70928)
		(width 0.0889)
		(layer "B.Cu")
		(net "PHY_CON_A_TO_IOC_3_DP")
	)
	(arc
		(start 201.708512 -71.805546)
		(mid 201.706606 -71.805436)
		(end 201.704702 -71.805292)
		(width 0.0889)
		(layer "B.Cu")
		(net "PHY_CON_A_TO_IOC_3_DP")
	)
	(arc
		(start 201.704702 -71.805292)
		(mid 201.626753 -71.773005)
		(end 201.594466 -71.695056)
		(width 0.0889)
		(layer "B.Cu")
		(net "PHY_CON_A_TO_IOC_3_DP")
	)
	(segment
		(start 184.201562 -25.390602)
		(end 183.082946 -24.271986)
		(width 0.12446)
		(layer "B.Cu")
		(net "PHY_CON_A_TO_IOC_3_DN_C")
	)
	(segment
		(start 179.779676 -21.910802)
		(end 179.999894 -21.500084)
		(width 0.12446)
		(layer "B.Cu")
		(net "PHY_CON_A_TO_IOC_3_DN_C")
	)
	(segment
		(start 191.410336 -25.273)
		(end 191.292734 -25.390602)
		(width 0.12446)
		(layer "B.Cu")
		(net "PHY_CON_A_TO_IOC_3_DN_C")
	)
	(segment
		(start 187.437014 -25.390602)
		(end 184.201562 -25.390602)
		(width 0.12446)
		(layer "B.Cu")
		(net "PHY_CON_A_TO_IOC_3_DN_C")
	)
	(segment
		(start 188.079634 -25.121362)
		(end 187.706254 -25.121362)
		(width 0.12446)
		(layer "B.Cu")
		(net "PHY_CON_A_TO_IOC_3_DN_C")
	)
	(segment
		(start 180.279294 -23.174452)
		(end 180.279294 -22.503384)
		(width 0.12446)
		(layer "B.Cu")
		(net "PHY_CON_A_TO_IOC_3_DN_C")
	)
	(segment
		(start 179.829714 -22.07895)
		(end 179.779676 -21.910802)
		(width 0.12446)
		(layer "B.Cu")
		(net "PHY_CON_A_TO_IOC_3_DN_C")
	)
	(segment
		(start 180.279294 -22.503384)
		(end 179.88026 -22.10435)
		(width 0.12446)
		(layer "B.Cu")
		(net "PHY_CON_A_TO_IOC_3_DN_C")
	)
	(segment
		(start 183.082946 -24.271986)
		(end 181.376828 -24.271986)
		(width 0.12446)
		(layer "B.Cu")
		(net "PHY_CON_A_TO_IOC_3_DN_C")
	)
	(segment
		(start 187.706254 -25.121362)
		(end 187.437014 -25.390602)
		(width 0.12446)
		(layer "B.Cu")
		(net "PHY_CON_A_TO_IOC_3_DN_C")
	)
	(segment
		(start 191.292734 -25.390602)
		(end 188.348874 -25.390602)
		(width 0.12446)
		(layer "B.Cu")
		(net "PHY_CON_A_TO_IOC_3_DN_C")
	)
	(segment
		(start 179.88026 -22.10435)
		(end 179.829714 -22.07895)
		(width 0.12446)
		(layer "B.Cu")
		(net "PHY_CON_A_TO_IOC_3_DN_C")
	)
	(segment
		(start 181.376828 -24.271986)
		(end 180.279294 -23.174452)
		(width 0.12446)
		(layer "B.Cu")
		(net "PHY_CON_A_TO_IOC_3_DN_C")
	)
	(segment
		(start 188.348874 -25.390602)
		(end 188.079634 -25.121362)
		(width 0.12446)
		(layer "B.Cu")
		(net "PHY_CON_A_TO_IOC_3_DN_C")
	)
	(segment
		(start 201.59345 -72.29348)
		(end 201.200004 -71.900034)
		(width 0.12446)
		(layer "F.Cu")
		(net "PHY_CON_A_TO_IOC_3_DN")
	)
	(segment
		(start 201.59345 -72.297798)
		(end 201.59345 -72.29348)
		(width 0.12446)
		(layer "F.Cu")
		(net "PHY_CON_A_TO_IOC_3_DN")
	)
	(via
		(at 201.59345 -72.297798)
		(size 0.508)
		(drill 0.254)
		(layers "F.Cu" "B.Cu")
		(net "PHY_CON_A_TO_IOC_3_DN")
	)
	(segment
		(start 214.357458 -41.316656)
		(end 218.13647 -60.761118)
		(width 0.12446)
		(layer "B.Cu")
		(net "PHY_CON_A_TO_IOC_3_DN")
	)
	(segment
		(start 196.115432 -25.803352)
		(end 208.675986 -34.275014)
		(width 0.12446)
		(layer "B.Cu")
		(net "PHY_CON_A_TO_IOC_3_DN")
	)
	(segment
		(start 203.632816 -71.89978)
		(end 203.033884 -71.89978)
		(width 0.0889)
		(layer "B.Cu")
		(net "PHY_CON_A_TO_IOC_3_DN")
	)
	(segment
		(start 202.066144 -72.097138)
		(end 201.965052 -71.996046)
		(width 0.0889)
		(layer "B.Cu")
		(net "PHY_CON_A_TO_IOC_3_DN")
	)
	(segment
		(start 210.387184 -35.429444)
		(end 214.357458 -41.316656)
		(width 0.12446)
		(layer "B.Cu")
		(net "PHY_CON_A_TO_IOC_3_DN")
	)
	(segment
		(start 194.138296 -25.41905)
		(end 196.115432 -25.803352)
		(width 0.12446)
		(layer "B.Cu")
		(net "PHY_CON_A_TO_IOC_3_DN")
	)
	(segment
		(start 205.56728 -73.14946)
		(end 204.851 -72.43318)
		(width 0.12446)
		(layer "B.Cu")
		(net "PHY_CON_A_TO_IOC_3_DN")
	)
	(segment
		(start 204.65796 -72.43318)
		(end 204.635862 -72.43318)
		(width 0.0889)
		(layer "B.Cu")
		(net "PHY_CON_A_TO_IOC_3_DN")
	)
	(segment
		(start 204.635862 -72.43318)
		(end 204.527912 -72.32523)
		(width 0.0889)
		(layer "B.Cu")
		(net "PHY_CON_A_TO_IOC_3_DN")
	)
	(segment
		(start 204.527912 -72.32523)
		(end 204.058266 -72.32523)
		(width 0.0889)
		(layer "B.Cu")
		(net "PHY_CON_A_TO_IOC_3_DN")
	)
	(segment
		(start 203.033884 -71.89978)
		(end 202.836526 -72.097138)
		(width 0.0889)
		(layer "B.Cu")
		(net "PHY_CON_A_TO_IOC_3_DN")
	)
	(segment
		(start 191.969136 -25.273)
		(end 192.115186 -25.41905)
		(width 0.12446)
		(layer "B.Cu")
		(net "PHY_CON_A_TO_IOC_3_DN")
	)
	(segment
		(start 208.675986 -34.275014)
		(end 210.387184 -35.429444)
		(width 0.12446)
		(layer "B.Cu")
		(net "PHY_CON_A_TO_IOC_3_DN")
	)
	(segment
		(start 201.59345 -72.10425)
		(end 201.59345 -72.297798)
		(width 0.0889)
		(layer "B.Cu")
		(net "PHY_CON_A_TO_IOC_3_DN")
	)
	(segment
		(start 192.115186 -25.41905)
		(end 194.138296 -25.41905)
		(width 0.12446)
		(layer "B.Cu")
		(net "PHY_CON_A_TO_IOC_3_DN")
	)
	(segment
		(start 218.13647 -60.761118)
		(end 216.668604 -68.319142)
		(width 0.12446)
		(layer "B.Cu")
		(net "PHY_CON_A_TO_IOC_3_DN")
	)
	(segment
		(start 204.851 -72.43318)
		(end 204.65796 -72.43318)
		(width 0.12446)
		(layer "B.Cu")
		(net "PHY_CON_A_TO_IOC_3_DN")
	)
	(segment
		(start 211.838286 -73.14946)
		(end 205.56728 -73.14946)
		(width 0.12446)
		(layer "B.Cu")
		(net "PHY_CON_A_TO_IOC_3_DN")
	)
	(segment
		(start 201.965052 -71.996046)
		(end 201.701654 -71.996046)
		(width 0.0889)
		(layer "B.Cu")
		(net "PHY_CON_A_TO_IOC_3_DN")
	)
	(segment
		(start 216.668604 -68.319142)
		(end 211.838286 -73.14946)
		(width 0.12446)
		(layer "B.Cu")
		(net "PHY_CON_A_TO_IOC_3_DN")
	)
	(segment
		(start 204.058266 -72.32523)
		(end 203.632816 -71.89978)
		(width 0.0889)
		(layer "B.Cu")
		(net "PHY_CON_A_TO_IOC_3_DN")
	)
	(segment
		(start 202.836526 -72.097138)
		(end 202.066144 -72.097138)
		(width 0.0889)
		(layer "B.Cu")
		(net "PHY_CON_A_TO_IOC_3_DN")
	)
	(arc
		(start 201.701654 -71.996046)
		(mid 201.687835 -71.996834)
		(end 201.674222 -71.999348)
		(width 0.0889)
		(layer "B.Cu")
		(net "PHY_CON_A_TO_IOC_3_DN")
	)
	(arc
		(start 201.674222 -71.999348)
		(mid 201.615958 -72.038041)
		(end 201.59345 -72.10425)
		(width 0.0889)
		(layer "B.Cu")
		(net "PHY_CON_A_TO_IOC_3_DN")
	)
	(segment
		(start 181.902608 -22.445218)
		(end 182.065422 -22.531832)
		(width 0.12446)
		(layer "B.Cu")
		(net "PHY_CON_A_TO_IOC_2_DP_C")
	)
	(segment
		(start 183.538114 -23.284688)
		(end 184.027826 -23.7744)
		(width 0.12446)
		(layer "B.Cu")
		(net "PHY_CON_A_TO_IOC_2_DP_C")
	)
	(segment
		(start 191.2366 -23.876)
		(end 191.41059 -23.876)
		(width 0.12446)
		(layer "B.Cu")
		(net "PHY_CON_A_TO_IOC_2_DP_C")
	)
	(segment
		(start 182.065422 -22.531832)
		(end 182.531004 -23.284688)
		(width 0.12446)
		(layer "B.Cu")
		(net "PHY_CON_A_TO_IOC_2_DP_C")
	)
	(segment
		(start 191.135 -23.7744)
		(end 191.2366 -23.876)
		(width 0.12446)
		(layer "B.Cu")
		(net "PHY_CON_A_TO_IOC_2_DP_C")
	)
	(segment
		(start 181.888892 -22.437852)
		(end 181.890416 -22.438868)
		(width 0.12446)
		(layer "B.Cu")
		(net "PHY_CON_A_TO_IOC_2_DP_C")
	)
	(segment
		(start 181.89321 -22.440392)
		(end 181.894734 -22.441154)
		(width 0.12446)
		(layer "B.Cu")
		(net "PHY_CON_A_TO_IOC_2_DP_C")
	)
	(segment
		(start 181.89194 -22.43963)
		(end 181.89321 -22.440392)
		(width 0.12446)
		(layer "B.Cu")
		(net "PHY_CON_A_TO_IOC_2_DP_C")
	)
	(segment
		(start 181.890416 -22.438868)
		(end 181.89194 -22.43963)
		(width 0.12446)
		(layer "B.Cu")
		(net "PHY_CON_A_TO_IOC_2_DP_C")
	)
	(segment
		(start 184.027826 -23.7744)
		(end 191.135 -23.7744)
		(width 0.12446)
		(layer "B.Cu")
		(net "PHY_CON_A_TO_IOC_2_DP_C")
	)
	(segment
		(start 181.894734 -22.441154)
		(end 181.896004 -22.441916)
		(width 0.12446)
		(layer "B.Cu")
		(net "PHY_CON_A_TO_IOC_2_DP_C")
	)
	(segment
		(start 182.531004 -23.284688)
		(end 183.538114 -23.284688)
		(width 0.12446)
		(layer "B.Cu")
		(net "PHY_CON_A_TO_IOC_2_DP_C")
	)
	(segment
		(start 181.896004 -22.441916)
		(end 181.902608 -22.445218)
		(width 0.12446)
		(layer "B.Cu")
		(net "PHY_CON_A_TO_IOC_2_DP_C")
	)
	(segment
		(start 181.500018 -22.899878)
		(end 181.720236 -22.488652)
		(width 0.12446)
		(layer "B.Cu")
		(net "PHY_CON_A_TO_IOC_2_DP_C")
	)
	(arc
		(start 181.720236 -22.488652)
		(mid 181.794043 -22.428322)
		(end 181.888892 -22.437852)
		(width 0.12446)
		(layer "B.Cu")
		(net "PHY_CON_A_TO_IOC_2_DP_C")
	)
	(segment
		(start 201.99985 -72.69988)
		(end 202.397106 -73.097136)
		(width 0.12446)
		(layer "F.Cu")
		(net "PHY_CON_A_TO_IOC_2_DP")
	)
	(via
		(at 202.397106 -73.097136)
		(size 0.508)
		(drill 0.254)
		(layers "F.Cu" "B.Cu")
		(net "PHY_CON_A_TO_IOC_2_DP")
	)
	(segment
		(start 213.523322 -38.178994)
		(end 213.595966 -37.805106)
		(width 0.12446)
		(layer "B.Cu")
		(net "PHY_CON_A_TO_IOC_2_DP")
	)
	(segment
		(start 206.151226 -30.212284)
		(end 202.897232 -28.017216)
		(width 0.12446)
		(layer "B.Cu")
		(net "PHY_CON_A_TO_IOC_2_DP")
	)
	(segment
		(start 202.213972 -27.881072)
		(end 202.141328 -27.507184)
		(width 0.12446)
		(layer "B.Cu")
		(net "PHY_CON_A_TO_IOC_2_DP")
	)
	(segment
		(start 198.944738 -25.350978)
		(end 197.71487 -24.521414)
		(width 0.12446)
		(layer "B.Cu")
		(net "PHY_CON_A_TO_IOC_2_DP")
	)
	(segment
		(start 199.327008 -25.933654)
		(end 199.017382 -25.724866)
		(width 0.12446)
		(layer "B.Cu")
		(net "PHY_CON_A_TO_IOC_2_DP")
	)
	(segment
		(start 201.148442 -27.162252)
		(end 201.075798 -26.788618)
		(width 0.12446)
		(layer "B.Cu")
		(net "PHY_CON_A_TO_IOC_2_DP")
	)
	(segment
		(start 214.105998 -38.561264)
		(end 213.73211 -38.48862)
		(width 0.12446)
		(layer "B.Cu")
		(net "PHY_CON_A_TO_IOC_2_DP")
	)
	(segment
		(start 197.71487 -24.521414)
		(end 194.053206 -23.790402)
		(width 0.12446)
		(layer "B.Cu")
		(net "PHY_CON_A_TO_IOC_2_DP")
	)
	(segment
		(start 207.2894 -31.304738)
		(end 207.216756 -30.93085)
		(width 0.12446)
		(layer "B.Cu")
		(net "PHY_CON_A_TO_IOC_2_DP")
	)
	(segment
		(start 204.280008 -73.008744)
		(end 205.674214 -74.40295)
		(width 0.0889)
		(layer "B.Cu")
		(net "PHY_CON_A_TO_IOC_2_DP")
	)
	(segment
		(start 202.606656 -73.306686)
		(end 203.090272 -73.306686)
		(width 0.0889)
		(layer "B.Cu")
		(net "PHY_CON_A_TO_IOC_2_DP")
	)
	(segment
		(start 205.674214 -74.40295)
		(end 207.111346 -74.40295)
		(width 0.0889)
		(layer "B.Cu")
		(net "PHY_CON_A_TO_IOC_2_DP")
	)
	(segment
		(start 214.105998 -38.561518)
		(end 214.105998 -38.561264)
		(width 0.12446)
		(layer "B.Cu")
		(net "PHY_CON_A_TO_IOC_2_DP")
	)
	(segment
		(start 207.219296 -74.295)
		(end 207.241394 -74.295)
		(width 0.0889)
		(layer "B.Cu")
		(net "PHY_CON_A_TO_IOC_2_DP")
	)
	(segment
		(start 207.241394 -74.295)
		(end 213.038944 -74.295)
		(width 0.12446)
		(layer "B.Cu")
		(net "PHY_CON_A_TO_IOC_2_DP")
	)
	(segment
		(start 201.075798 -26.788618)
		(end 200.766172 -26.57983)
		(width 0.12446)
		(layer "B.Cu")
		(net "PHY_CON_A_TO_IOC_2_DP")
	)
	(segment
		(start 201.831702 -27.298396)
		(end 201.458068 -27.37104)
		(width 0.12446)
		(layer "B.Cu")
		(net "PHY_CON_A_TO_IOC_2_DP")
	)
	(segment
		(start 212.085936 -36.047934)
		(end 212.15858 -35.6743)
		(width 0.12446)
		(layer "B.Cu")
		(net "PHY_CON_A_TO_IOC_2_DP")
	)
	(segment
		(start 207.111346 -74.40295)
		(end 207.219296 -74.295)
		(width 0.0889)
		(layer "B.Cu")
		(net "PHY_CON_A_TO_IOC_2_DP")
	)
	(segment
		(start 210.413346 -33.087056)
		(end 209.03819 -32.159448)
		(width 0.12446)
		(layer "B.Cu")
		(net "PHY_CON_A_TO_IOC_2_DP")
	)
	(segment
		(start 213.73211 -38.48862)
		(end 213.523322 -38.178994)
		(width 0.12446)
		(layer "B.Cu")
		(net "PHY_CON_A_TO_IOC_2_DP")
	)
	(segment
		(start 212.8774 -36.73983)
		(end 212.668358 -36.430204)
		(width 0.12446)
		(layer "B.Cu")
		(net "PHY_CON_A_TO_IOC_2_DP")
	)
	(segment
		(start 192.054988 -23.790402)
		(end 191.96939 -23.876)
		(width 0.12446)
		(layer "B.Cu")
		(net "PHY_CON_A_TO_IOC_2_DP")
	)
	(segment
		(start 207.216756 -30.93085)
		(end 206.907384 -30.722062)
		(width 0.12446)
		(layer "B.Cu")
		(net "PHY_CON_A_TO_IOC_2_DP")
	)
	(segment
		(start 203.090272 -73.306686)
		(end 203.388214 -73.008744)
		(width 0.0889)
		(layer "B.Cu")
		(net "PHY_CON_A_TO_IOC_2_DP")
	)
	(segment
		(start 200.766172 -26.57983)
		(end 200.392538 -26.652474)
		(width 0.12446)
		(layer "B.Cu")
		(net "PHY_CON_A_TO_IOC_2_DP")
	)
	(segment
		(start 194.053206 -23.790402)
		(end 192.054988 -23.790402)
		(width 0.12446)
		(layer "B.Cu")
		(net "PHY_CON_A_TO_IOC_2_DP")
	)
	(segment
		(start 200.010268 -26.069798)
		(end 199.700896 -25.86101)
		(width 0.12446)
		(layer "B.Cu")
		(net "PHY_CON_A_TO_IOC_2_DP")
	)
	(segment
		(start 213.595966 -37.805106)
		(end 213.387178 -37.495734)
		(width 0.12446)
		(layer "B.Cu")
		(net "PHY_CON_A_TO_IOC_2_DP")
	)
	(segment
		(start 203.388214 -73.008744)
		(end 204.280008 -73.008744)
		(width 0.0889)
		(layer "B.Cu")
		(net "PHY_CON_A_TO_IOC_2_DP")
	)
	(segment
		(start 206.907384 -30.722062)
		(end 206.533496 -30.794706)
		(width 0.12446)
		(layer "B.Cu")
		(net "PHY_CON_A_TO_IOC_2_DP")
	)
	(segment
		(start 208.664556 -32.232092)
		(end 208.35493 -32.023304)
		(width 0.12446)
		(layer "B.Cu")
		(net "PHY_CON_A_TO_IOC_2_DP")
	)
	(segment
		(start 215.133174 -40.083994)
		(end 214.105998 -38.561518)
		(width 0.12446)
		(layer "B.Cu")
		(net "PHY_CON_A_TO_IOC_2_DP")
	)
	(segment
		(start 213.038944 -74.295)
		(end 217.260932 -70.073012)
		(width 0.12446)
		(layer "B.Cu")
		(net "PHY_CON_A_TO_IOC_2_DP")
	)
	(segment
		(start 212.804756 -37.113464)
		(end 212.8774 -36.73983)
		(width 0.12446)
		(layer "B.Cu")
		(net "PHY_CON_A_TO_IOC_2_DP")
	)
	(segment
		(start 201.458068 -27.37104)
		(end 201.148442 -27.162252)
		(width 0.12446)
		(layer "B.Cu")
		(net "PHY_CON_A_TO_IOC_2_DP")
	)
	(segment
		(start 202.523598 -28.08986)
		(end 202.213972 -27.881072)
		(width 0.12446)
		(layer "B.Cu")
		(net "PHY_CON_A_TO_IOC_2_DP")
	)
	(segment
		(start 213.387178 -37.495734)
		(end 213.013544 -37.42309)
		(width 0.12446)
		(layer "B.Cu")
		(net "PHY_CON_A_TO_IOC_2_DP")
	)
	(segment
		(start 208.282286 -31.64967)
		(end 207.972914 -31.440882)
		(width 0.12446)
		(layer "B.Cu")
		(net "PHY_CON_A_TO_IOC_2_DP")
	)
	(segment
		(start 212.294724 -36.35756)
		(end 212.085936 -36.047934)
		(width 0.12446)
		(layer "B.Cu")
		(net "PHY_CON_A_TO_IOC_2_DP")
	)
	(segment
		(start 202.397106 -73.097136)
		(end 202.606656 -73.306686)
		(width 0.0889)
		(layer "B.Cu")
		(net "PHY_CON_A_TO_IOC_2_DP")
	)
	(segment
		(start 212.668358 -36.430204)
		(end 212.294724 -36.35756)
		(width 0.12446)
		(layer "B.Cu")
		(net "PHY_CON_A_TO_IOC_2_DP")
	)
	(segment
		(start 199.700896 -25.86101)
		(end 199.327008 -25.933654)
		(width 0.12446)
		(layer "B.Cu")
		(net "PHY_CON_A_TO_IOC_2_DP")
	)
	(segment
		(start 202.897232 -28.017216)
		(end 202.523598 -28.08986)
		(width 0.12446)
		(layer "B.Cu")
		(net "PHY_CON_A_TO_IOC_2_DP")
	)
	(segment
		(start 206.533496 -30.794706)
		(end 206.22387 -30.585918)
		(width 0.12446)
		(layer "B.Cu")
		(net "PHY_CON_A_TO_IOC_2_DP")
	)
	(segment
		(start 212.15858 -35.6743)
		(end 210.413346 -33.087056)
		(width 0.12446)
		(layer "B.Cu")
		(net "PHY_CON_A_TO_IOC_2_DP")
	)
	(segment
		(start 202.141328 -27.507184)
		(end 201.831702 -27.298396)
		(width 0.12446)
		(layer "B.Cu")
		(net "PHY_CON_A_TO_IOC_2_DP")
	)
	(segment
		(start 213.013544 -37.42309)
		(end 212.804756 -37.113464)
		(width 0.12446)
		(layer "B.Cu")
		(net "PHY_CON_A_TO_IOC_2_DP")
	)
	(segment
		(start 209.03819 -32.159448)
		(end 208.664556 -32.232092)
		(width 0.12446)
		(layer "B.Cu")
		(net "PHY_CON_A_TO_IOC_2_DP")
	)
	(segment
		(start 200.082912 -26.443686)
		(end 200.010268 -26.069798)
		(width 0.12446)
		(layer "B.Cu")
		(net "PHY_CON_A_TO_IOC_2_DP")
	)
	(segment
		(start 217.260932 -70.073012)
		(end 219.137992 -60.684918)
		(width 0.12446)
		(layer "B.Cu")
		(net "PHY_CON_A_TO_IOC_2_DP")
	)
	(segment
		(start 206.22387 -30.585918)
		(end 206.151226 -30.212284)
		(width 0.12446)
		(layer "B.Cu")
		(net "PHY_CON_A_TO_IOC_2_DP")
	)
	(segment
		(start 208.35493 -32.023304)
		(end 208.282286 -31.64967)
		(width 0.12446)
		(layer "B.Cu")
		(net "PHY_CON_A_TO_IOC_2_DP")
	)
	(segment
		(start 199.017382 -25.724866)
		(end 198.944738 -25.350978)
		(width 0.12446)
		(layer "B.Cu")
		(net "PHY_CON_A_TO_IOC_2_DP")
	)
	(segment
		(start 200.392538 -26.652474)
		(end 200.082912 -26.443686)
		(width 0.12446)
		(layer "B.Cu")
		(net "PHY_CON_A_TO_IOC_2_DP")
	)
	(segment
		(start 219.137992 -60.684918)
		(end 215.133174 -40.083994)
		(width 0.12446)
		(layer "B.Cu")
		(net "PHY_CON_A_TO_IOC_2_DP")
	)
	(segment
		(start 207.972914 -31.440882)
		(end 207.599026 -31.513526)
		(width 0.12446)
		(layer "B.Cu")
		(net "PHY_CON_A_TO_IOC_2_DP")
	)
	(segment
		(start 207.599026 -31.513526)
		(end 207.2894 -31.304738)
		(width 0.12446)
		(layer "B.Cu")
		(net "PHY_CON_A_TO_IOC_2_DP")
	)
	(segment
		(start 191.1096 -23.368)
		(end 191.2366 -23.241)
		(width 0.12446)
		(layer "B.Cu")
		(net "PHY_CON_A_TO_IOC_2_DN_C")
	)
	(segment
		(start 182.080662 -22.079458)
		(end 182.080916 -22.079458)
		(width 0.12446)
		(layer "B.Cu")
		(net "PHY_CON_A_TO_IOC_2_DN_C")
	)
	(segment
		(start 182.353712 -22.225)
		(end 182.757572 -22.878288)
		(width 0.12446)
		(layer "B.Cu")
		(net "PHY_CON_A_TO_IOC_2_DN_C")
	)
	(segment
		(start 188.726318 -23.09876)
		(end 188.995558 -23.368)
		(width 0.12446)
		(layer "B.Cu")
		(net "PHY_CON_A_TO_IOC_2_DN_C")
	)
	(segment
		(start 188.995558 -23.368)
		(end 191.1096 -23.368)
		(width 0.12446)
		(layer "B.Cu")
		(net "PHY_CON_A_TO_IOC_2_DN_C")
	)
	(segment
		(start 182.085996 -22.081998)
		(end 182.087774 -22.083014)
		(width 0.12446)
		(layer "B.Cu")
		(net "PHY_CON_A_TO_IOC_2_DN_C")
	)
	(segment
		(start 182.087774 -22.083014)
		(end 182.091838 -22.085046)
		(width 0.12446)
		(layer "B.Cu")
		(net "PHY_CON_A_TO_IOC_2_DN_C")
	)
	(segment
		(start 183.706516 -22.878288)
		(end 184.196228 -23.368)
		(width 0.12446)
		(layer "B.Cu")
		(net "PHY_CON_A_TO_IOC_2_DN_C")
	)
	(segment
		(start 184.196228 -23.368)
		(end 188.083698 -23.368)
		(width 0.12446)
		(layer "B.Cu")
		(net "PHY_CON_A_TO_IOC_2_DN_C")
	)
	(segment
		(start 191.2366 -23.241)
		(end 191.41059 -23.241)
		(width 0.12446)
		(layer "B.Cu")
		(net "PHY_CON_A_TO_IOC_2_DN_C")
	)
	(segment
		(start 182.25008 -21.500084)
		(end 182.029862 -21.910802)
		(width 0.12446)
		(layer "B.Cu")
		(net "PHY_CON_A_TO_IOC_2_DN_C")
	)
	(segment
		(start 182.093616 -22.086062)
		(end 182.094378 -22.08657)
		(width 0.12446)
		(layer "B.Cu")
		(net "PHY_CON_A_TO_IOC_2_DN_C")
	)
	(segment
		(start 182.757572 -22.878288)
		(end 183.706516 -22.878288)
		(width 0.12446)
		(layer "B.Cu")
		(net "PHY_CON_A_TO_IOC_2_DN_C")
	)
	(segment
		(start 188.083698 -23.368)
		(end 188.352938 -23.09876)
		(width 0.12446)
		(layer "B.Cu")
		(net "PHY_CON_A_TO_IOC_2_DN_C")
	)
	(segment
		(start 182.080916 -22.079458)
		(end 182.085996 -22.081998)
		(width 0.12446)
		(layer "B.Cu")
		(net "PHY_CON_A_TO_IOC_2_DN_C")
	)
	(segment
		(start 188.352938 -23.09876)
		(end 188.726318 -23.09876)
		(width 0.12446)
		(layer "B.Cu")
		(net "PHY_CON_A_TO_IOC_2_DN_C")
	)
	(segment
		(start 182.094378 -22.08657)
		(end 182.353712 -22.225)
		(width 0.12446)
		(layer "B.Cu")
		(net "PHY_CON_A_TO_IOC_2_DN_C")
	)
	(segment
		(start 182.091838 -22.085046)
		(end 182.093616 -22.086062)
		(width 0.12446)
		(layer "B.Cu")
		(net "PHY_CON_A_TO_IOC_2_DN_C")
	)
	(arc
		(start 182.029862 -21.910802)
		(mid 182.020332 -22.005651)
		(end 182.080662 -22.079458)
		(width 0.12446)
		(layer "B.Cu")
		(net "PHY_CON_A_TO_IOC_2_DN_C")
	)
	(segment
		(start 201.600562 -73.100438)
		(end 201.200004 -72.69988)
		(width 0.12446)
		(layer "F.Cu")
		(net "PHY_CON_A_TO_IOC_2_DN")
	)
	(via
		(at 201.600562 -73.100438)
		(size 0.508)
		(drill 0.254)
		(layers "F.Cu" "B.Cu")
		(net "PHY_CON_A_TO_IOC_2_DN")
	)
	(segment
		(start 207.219296 -74.7014)
		(end 207.241394 -74.7014)
		(width 0.0889)
		(layer "B.Cu")
		(net "PHY_CON_A_TO_IOC_2_DN")
	)
	(segment
		(start 210.706208 -32.794194)
		(end 209.265266 -31.82239)
		(width 0.12446)
		(layer "B.Cu")
		(net "PHY_CON_A_TO_IOC_2_DN")
	)
	(segment
		(start 203.169266 -73.497186)
		(end 203.467208 -73.199244)
		(width 0.0889)
		(layer "B.Cu")
		(net "PHY_CON_A_TO_IOC_2_DN")
	)
	(segment
		(start 204.201014 -73.199244)
		(end 205.59522 -74.59345)
		(width 0.0889)
		(layer "B.Cu")
		(net "PHY_CON_A_TO_IOC_2_DN")
	)
	(segment
		(start 197.874636 -24.138636)
		(end 194.093592 -23.384002)
		(width 0.12446)
		(layer "B.Cu")
		(net "PHY_CON_A_TO_IOC_2_DN")
	)
	(segment
		(start 201.99477 -73.494646)
		(end 202.228704 -73.494646)
		(width 0.0889)
		(layer "B.Cu")
		(net "PHY_CON_A_TO_IOC_2_DN")
	)
	(segment
		(start 213.207346 -74.7014)
		(end 217.635328 -70.273418)
		(width 0.12446)
		(layer "B.Cu")
		(net "PHY_CON_A_TO_IOC_2_DN")
	)
	(segment
		(start 194.093592 -23.384002)
		(end 192.112392 -23.384002)
		(width 0.12446)
		(layer "B.Cu")
		(net "PHY_CON_A_TO_IOC_2_DN")
	)
	(segment
		(start 207.111346 -74.59345)
		(end 207.219296 -74.7014)
		(width 0.0889)
		(layer "B.Cu")
		(net "PHY_CON_A_TO_IOC_2_DN")
	)
	(segment
		(start 202.231244 -73.497186)
		(end 203.169266 -73.497186)
		(width 0.0889)
		(layer "B.Cu")
		(net "PHY_CON_A_TO_IOC_2_DN")
	)
	(segment
		(start 205.59522 -74.59345)
		(end 207.111346 -74.59345)
		(width 0.0889)
		(layer "B.Cu")
		(net "PHY_CON_A_TO_IOC_2_DN")
	)
	(segment
		(start 209.265266 -31.822136)
		(end 203.124308 -27.679904)
		(width 0.12446)
		(layer "B.Cu")
		(net "PHY_CON_A_TO_IOC_2_DN")
	)
	(segment
		(start 201.600562 -73.100438)
		(end 201.99477 -73.494646)
		(width 0.0889)
		(layer "B.Cu")
		(net "PHY_CON_A_TO_IOC_2_DN")
	)
	(segment
		(start 202.228704 -73.494646)
		(end 202.231244 -73.497186)
		(width 0.0889)
		(layer "B.Cu")
		(net "PHY_CON_A_TO_IOC_2_DN")
	)
	(segment
		(start 209.265266 -31.82239)
		(end 209.265266 -31.822136)
		(width 0.12446)
		(layer "B.Cu")
		(net "PHY_CON_A_TO_IOC_2_DN")
	)
	(segment
		(start 215.51646 -39.925244)
		(end 210.706208 -32.794194)
		(width 0.12446)
		(layer "B.Cu")
		(net "PHY_CON_A_TO_IOC_2_DN")
	)
	(segment
		(start 219.552266 -60.685934)
		(end 215.51646 -39.925244)
		(width 0.12446)
		(layer "B.Cu")
		(net "PHY_CON_A_TO_IOC_2_DN")
	)
	(segment
		(start 197.874636 -24.13889)
		(end 197.874636 -24.138636)
		(width 0.12446)
		(layer "B.Cu")
		(net "PHY_CON_A_TO_IOC_2_DN")
	)
	(segment
		(start 203.467208 -73.199244)
		(end 204.201014 -73.199244)
		(width 0.0889)
		(layer "B.Cu")
		(net "PHY_CON_A_TO_IOC_2_DN")
	)
	(segment
		(start 217.635328 -70.273418)
		(end 219.552266 -60.685934)
		(width 0.12446)
		(layer "B.Cu")
		(net "PHY_CON_A_TO_IOC_2_DN")
	)
	(segment
		(start 203.124308 -27.679904)
		(end 197.874636 -24.13889)
		(width 0.12446)
		(layer "B.Cu")
		(net "PHY_CON_A_TO_IOC_2_DN")
	)
	(segment
		(start 207.241394 -74.7014)
		(end 213.207346 -74.7014)
		(width 0.12446)
		(layer "B.Cu")
		(net "PHY_CON_A_TO_IOC_2_DN")
	)
	(segment
		(start 192.112392 -23.384002)
		(end 191.96939 -23.241)
		(width 0.12446)
		(layer "B.Cu")
		(net "PHY_CON_A_TO_IOC_2_DN")
	)
	(segment
		(start 191.287146 -21.720556)
		(end 184.217056 -21.720556)
		(width 0.12446)
		(layer "B.Cu")
		(net "PHY_CON_A_TO_IOC_1_DP_C")
	)
	(segment
		(start 191.41059 -21.844)
		(end 191.287146 -21.720556)
		(width 0.12446)
		(layer "B.Cu")
		(net "PHY_CON_A_TO_IOC_1_DP_C")
	)
	(segment
		(start 179.998624 -19.543776)
		(end 179.998624 -19.041872)
		(width 0.12446)
		(layer "B.Cu")
		(net "PHY_CON_A_TO_IOC_1_DP_C")
	)
	(segment
		(start 179.742592 -18.693384)
		(end 179.63896 -18.638012)
		(width 0.12446)
		(layer "B.Cu")
		(net "PHY_CON_A_TO_IOC_1_DP_C")
	)
	(segment
		(start 179.749196 -18.69694)
		(end 179.748688 -18.696686)
		(width 0.12446)
		(layer "B.Cu")
		(net "PHY_CON_A_TO_IOC_1_DP_C")
	)
	(segment
		(start 179.470304 -18.688812)
		(end 179.250086 -19.100038)
		(width 0.12446)
		(layer "B.Cu")
		(net "PHY_CON_A_TO_IOC_1_DP_C")
	)
	(segment
		(start 183.2737 -20.7772)
		(end 181.232048 -20.7772)
		(width 0.12446)
		(layer "B.Cu")
		(net "PHY_CON_A_TO_IOC_1_DP_C")
	)
	(segment
		(start 179.743354 -18.693892)
		(end 179.742592 -18.693384)
		(width 0.12446)
		(layer "B.Cu")
		(net "PHY_CON_A_TO_IOC_1_DP_C")
	)
	(segment
		(start 184.217056 -21.720556)
		(end 183.2737 -20.7772)
		(width 0.12446)
		(layer "B.Cu")
		(net "PHY_CON_A_TO_IOC_1_DP_C")
	)
	(segment
		(start 179.748688 -18.696686)
		(end 179.743354 -18.693892)
		(width 0.12446)
		(layer "B.Cu")
		(net "PHY_CON_A_TO_IOC_1_DP_C")
	)
	(segment
		(start 181.232048 -20.7772)
		(end 179.998624 -19.543776)
		(width 0.12446)
		(layer "B.Cu")
		(net "PHY_CON_A_TO_IOC_1_DP_C")
	)
	(segment
		(start 179.998624 -19.041872)
		(end 179.749196 -18.69694)
		(width 0.12446)
		(layer "B.Cu")
		(net "PHY_CON_A_TO_IOC_1_DP_C")
	)
	(arc
		(start 179.63896 -18.638012)
		(mid 179.544111 -18.628482)
		(end 179.470304 -18.688812)
		(width 0.12446)
		(layer "B.Cu")
		(net "PHY_CON_A_TO_IOC_1_DP_C")
	)
	(segment
		(start 201.994516 -74.299826)
		(end 201.99985 -74.299826)
		(width 0.12446)
		(layer "F.Cu")
		(net "PHY_CON_A_TO_IOC_1_DP")
	)
	(segment
		(start 201.598276 -73.903586)
		(end 201.994516 -74.299826)
		(width 0.12446)
		(layer "F.Cu")
		(net "PHY_CON_A_TO_IOC_1_DP")
	)
	(via
		(at 201.598276 -73.903586)
		(size 0.508)
		(drill 0.254)
		(layers "F.Cu" "B.Cu")
		(net "PHY_CON_A_TO_IOC_1_DP")
	)
	(segment
		(start 207.484472 -28.967176)
		(end 207.559148 -29.340556)
		(width 0.12446)
		(layer "B.Cu")
		(net "PHY_CON_A_TO_IOC_1_DP")
	)
	(segment
		(start 209.312764 -30.185868)
		(end 211.509356 -31.649924)
		(width 0.12446)
		(layer "B.Cu")
		(net "PHY_CON_A_TO_IOC_1_DP")
	)
	(segment
		(start 201.304144 -73.94321)
		(end 201.317352 -73.929748)
		(width 0.0889)
		(layer "B.Cu")
		(net "PHY_CON_A_TO_IOC_1_DP")
	)
	(segment
		(start 207.17383 -28.760166)
		(end 207.484472 -28.967176)
		(width 0.12446)
		(layer "B.Cu")
		(net "PHY_CON_A_TO_IOC_1_DP")
	)
	(segment
		(start 201.573892 -25.027636)
		(end 201.884534 -25.234646)
		(width 0.12446)
		(layer "B.Cu")
		(net "PHY_CON_A_TO_IOC_1_DP")
	)
	(segment
		(start 197.125336 -22.062186)
		(end 197.125336 -22.06244)
		(width 0.12446)
		(layer "B.Cu")
		(net "PHY_CON_A_TO_IOC_1_DP")
	)
	(segment
		(start 205.736952 -75.16749)
		(end 204.357478 -75.16749)
		(width 0.12446)
		(layer "B.Cu")
		(net "PHY_CON_A_TO_IOC_1_DP")
	)
	(segment
		(start 200.131172 -24.389588)
		(end 200.504552 -24.314658)
		(width 0.12446)
		(layer "B.Cu")
		(net "PHY_CON_A_TO_IOC_1_DP")
	)
	(segment
		(start 201.200512 -25.102312)
		(end 201.573892 -25.027636)
		(width 0.12446)
		(layer "B.Cu")
		(net "PHY_CON_A_TO_IOC_1_DP")
	)
	(segment
		(start 204.357478 -75.16749)
		(end 204.33538 -75.16749)
		(width 0.0889)
		(layer "B.Cu")
		(net "PHY_CON_A_TO_IOC_1_DP")
	)
	(segment
		(start 202.643486 -25.74036)
		(end 206.415132 -28.254452)
		(width 0.12446)
		(layer "B.Cu")
		(net "PHY_CON_A_TO_IOC_1_DP")
	)
	(segment
		(start 198.67626 -23.09622)
		(end 198.750936 -23.4696)
		(width 0.12446)
		(layer "B.Cu")
		(net "PHY_CON_A_TO_IOC_1_DP")
	)
	(segment
		(start 199.434958 -23.601934)
		(end 199.745854 -23.808944)
		(width 0.12446)
		(layer "B.Cu")
		(net "PHY_CON_A_TO_IOC_1_DP")
	)
	(segment
		(start 206.415132 -28.254452)
		(end 206.489808 -28.627832)
		(width 0.12446)
		(layer "B.Cu")
		(net "PHY_CON_A_TO_IOC_1_DP")
	)
	(segment
		(start 220.551756 -60.017406)
		(end 218.046554 -72.529446)
		(width 0.12446)
		(layer "B.Cu")
		(net "PHY_CON_A_TO_IOC_1_DP")
	)
	(segment
		(start 203.220066 -75.27544)
		(end 202.651106 -74.70648)
		(width 0.0889)
		(layer "B.Cu")
		(net "PHY_CON_A_TO_IOC_1_DP")
	)
	(segment
		(start 206.489808 -28.627832)
		(end 206.80045 -28.834842)
		(width 0.12446)
		(layer "B.Cu")
		(net "PHY_CON_A_TO_IOC_1_DP")
	)
	(segment
		(start 191.96939 -21.844)
		(end 191.96939 -21.843746)
		(width 0.12446)
		(layer "B.Cu")
		(net "PHY_CON_A_TO_IOC_1_DP")
	)
	(segment
		(start 195.349876 -21.717)
		(end 197.125336 -22.062186)
		(width 0.12446)
		(layer "B.Cu")
		(net "PHY_CON_A_TO_IOC_1_DP")
	)
	(segment
		(start 204.22743 -75.27544)
		(end 203.220066 -75.27544)
		(width 0.0889)
		(layer "B.Cu")
		(net "PHY_CON_A_TO_IOC_1_DP")
	)
	(segment
		(start 207.559148 -29.340556)
		(end 207.86979 -29.547566)
		(width 0.12446)
		(layer "B.Cu")
		(net "PHY_CON_A_TO_IOC_1_DP")
	)
	(segment
		(start 207.86979 -29.547566)
		(end 208.24317 -29.47289)
		(width 0.12446)
		(layer "B.Cu")
		(net "PHY_CON_A_TO_IOC_1_DP")
	)
	(segment
		(start 208.24317 -29.47289)
		(end 208.553812 -29.6799)
		(width 0.12446)
		(layer "B.Cu")
		(net "PHY_CON_A_TO_IOC_1_DP")
	)
	(segment
		(start 199.061578 -23.67661)
		(end 199.434958 -23.601934)
		(width 0.12446)
		(layer "B.Cu")
		(net "PHY_CON_A_TO_IOC_1_DP")
	)
	(segment
		(start 218.046554 -72.529446)
		(end 214.81923 -75.75677)
		(width 0.12446)
		(layer "B.Cu")
		(net "PHY_CON_A_TO_IOC_1_DP")
	)
	(segment
		(start 197.125336 -22.06244)
		(end 198.67626 -23.09622)
		(width 0.12446)
		(layer "B.Cu")
		(net "PHY_CON_A_TO_IOC_1_DP")
	)
	(segment
		(start 204.33538 -75.16749)
		(end 204.22743 -75.27544)
		(width 0.0889)
		(layer "B.Cu")
		(net "PHY_CON_A_TO_IOC_1_DP")
	)
	(segment
		(start 216.323164 -38.87089)
		(end 220.551756 -60.017406)
		(width 0.12446)
		(layer "B.Cu")
		(net "PHY_CON_A_TO_IOC_1_DP")
	)
	(segment
		(start 206.80045 -28.834842)
		(end 207.17383 -28.760166)
		(width 0.12446)
		(layer "B.Cu")
		(net "PHY_CON_A_TO_IOC_1_DP")
	)
	(segment
		(start 192.096136 -21.717)
		(end 195.349876 -21.717)
		(width 0.12446)
		(layer "B.Cu")
		(net "PHY_CON_A_TO_IOC_1_DP")
	)
	(segment
		(start 199.745854 -23.808944)
		(end 199.82053 -24.182324)
		(width 0.12446)
		(layer "B.Cu")
		(net "PHY_CON_A_TO_IOC_1_DP")
	)
	(segment
		(start 206.326232 -75.75677)
		(end 205.736952 -75.16749)
		(width 0.12446)
		(layer "B.Cu")
		(net "PHY_CON_A_TO_IOC_1_DP")
	)
	(segment
		(start 208.628488 -30.05328)
		(end 208.939384 -30.260544)
		(width 0.12446)
		(layer "B.Cu")
		(net "PHY_CON_A_TO_IOC_1_DP")
	)
	(segment
		(start 199.82053 -24.182324)
		(end 200.131172 -24.389588)
		(width 0.12446)
		(layer "B.Cu")
		(net "PHY_CON_A_TO_IOC_1_DP")
	)
	(segment
		(start 201.590402 -74.70648)
		(end 201.26452 -74.380598)
		(width 0.0889)
		(layer "B.Cu")
		(net "PHY_CON_A_TO_IOC_1_DP")
	)
	(segment
		(start 202.270106 -25.815036)
		(end 202.643486 -25.74036)
		(width 0.12446)
		(layer "B.Cu")
		(net "PHY_CON_A_TO_IOC_1_DP")
	)
	(segment
		(start 200.815194 -24.521922)
		(end 200.88987 -24.895302)
		(width 0.12446)
		(layer "B.Cu")
		(net "PHY_CON_A_TO_IOC_1_DP")
	)
	(segment
		(start 201.380598 -73.903586)
		(end 201.598276 -73.903586)
		(width 0.0889)
		(layer "B.Cu")
		(net "PHY_CON_A_TO_IOC_1_DP")
	)
	(segment
		(start 200.88987 -24.895302)
		(end 201.200512 -25.102312)
		(width 0.12446)
		(layer "B.Cu")
		(net "PHY_CON_A_TO_IOC_1_DP")
	)
	(segment
		(start 208.553812 -29.6799)
		(end 208.628488 -30.05328)
		(width 0.12446)
		(layer "B.Cu")
		(net "PHY_CON_A_TO_IOC_1_DP")
	)
	(segment
		(start 214.81923 -75.75677)
		(end 206.326232 -75.75677)
		(width 0.12446)
		(layer "B.Cu")
		(net "PHY_CON_A_TO_IOC_1_DP")
	)
	(segment
		(start 201.26452 -74.380598)
		(end 201.26452 -74.03846)
		(width 0.0889)
		(layer "B.Cu")
		(net "PHY_CON_A_TO_IOC_1_DP")
	)
	(segment
		(start 201.959464 -25.608026)
		(end 202.270106 -25.815036)
		(width 0.12446)
		(layer "B.Cu")
		(net "PHY_CON_A_TO_IOC_1_DP")
	)
	(segment
		(start 208.939384 -30.260544)
		(end 209.312764 -30.185868)
		(width 0.12446)
		(layer "B.Cu")
		(net "PHY_CON_A_TO_IOC_1_DP")
	)
	(segment
		(start 200.504552 -24.314658)
		(end 200.815194 -24.521922)
		(width 0.12446)
		(layer "B.Cu")
		(net "PHY_CON_A_TO_IOC_1_DP")
	)
	(segment
		(start 211.509356 -31.649924)
		(end 216.323164 -38.87089)
		(width 0.12446)
		(layer "B.Cu")
		(net "PHY_CON_A_TO_IOC_1_DP")
	)
	(segment
		(start 201.884534 -25.234646)
		(end 201.959464 -25.608026)
		(width 0.12446)
		(layer "B.Cu")
		(net "PHY_CON_A_TO_IOC_1_DP")
	)
	(segment
		(start 202.651106 -74.70648)
		(end 201.590402 -74.70648)
		(width 0.0889)
		(layer "B.Cu")
		(net "PHY_CON_A_TO_IOC_1_DP")
	)
	(segment
		(start 198.750936 -23.4696)
		(end 199.061578 -23.67661)
		(width 0.12446)
		(layer "B.Cu")
		(net "PHY_CON_A_TO_IOC_1_DP")
	)
	(segment
		(start 191.96939 -21.843746)
		(end 192.096136 -21.717)
		(width 0.12446)
		(layer "B.Cu")
		(net "PHY_CON_A_TO_IOC_1_DP")
	)
	(arc
		(start 201.26452 -74.03846)
		(mid 201.27487 -73.9869)
		(end 201.304144 -73.94321)
		(width 0.0889)
		(layer "B.Cu")
		(net "PHY_CON_A_TO_IOC_1_DP")
	)
	(arc
		(start 201.317352 -73.929748)
		(mid 201.346356 -73.910335)
		(end 201.380598 -73.903586)
		(width 0.0889)
		(layer "B.Cu")
		(net "PHY_CON_A_TO_IOC_1_DP")
	)
	(segment
		(start 180.405024 -18.9103)
		(end 180.020214 -18.377916)
		(width 0.12446)
		(layer "B.Cu")
		(net "PHY_CON_A_TO_IOC_1_DN_C")
	)
	(segment
		(start 191.41059 -21.209)
		(end 191.305434 -21.314156)
		(width 0.12446)
		(layer "B.Cu")
		(net "PHY_CON_A_TO_IOC_1_DN_C")
	)
	(segment
		(start 189.54623 -21.044916)
		(end 189.17285 -21.044916)
		(width 0.12446)
		(layer "B.Cu")
		(net "PHY_CON_A_TO_IOC_1_DN_C")
	)
	(segment
		(start 180.405024 -19.375374)
		(end 180.405024 -18.9103)
		(width 0.12446)
		(layer "B.Cu")
		(net "PHY_CON_A_TO_IOC_1_DN_C")
	)
	(segment
		(start 189.81547 -21.314156)
		(end 189.54623 -21.044916)
		(width 0.12446)
		(layer "B.Cu")
		(net "PHY_CON_A_TO_IOC_1_DN_C")
	)
	(segment
		(start 179.83073 -18.279364)
		(end 179.830476 -18.279364)
		(width 0.12446)
		(layer "B.Cu")
		(net "PHY_CON_A_TO_IOC_1_DN_C")
	)
	(segment
		(start 184.385458 -21.314156)
		(end 183.442102 -20.3708)
		(width 0.12446)
		(layer "B.Cu")
		(net "PHY_CON_A_TO_IOC_1_DN_C")
	)
	(segment
		(start 181.40045 -20.3708)
		(end 180.405024 -19.375374)
		(width 0.12446)
		(layer "B.Cu")
		(net "PHY_CON_A_TO_IOC_1_DN_C")
	)
	(segment
		(start 183.442102 -20.3708)
		(end 181.40045 -20.3708)
		(width 0.12446)
		(layer "B.Cu")
		(net "PHY_CON_A_TO_IOC_1_DN_C")
	)
	(segment
		(start 179.912518 -18.323052)
		(end 179.83073 -18.279364)
		(width 0.12446)
		(layer "B.Cu")
		(net "PHY_CON_A_TO_IOC_1_DN_C")
	)
	(segment
		(start 189.17285 -21.044916)
		(end 188.90361 -21.314156)
		(width 0.12446)
		(layer "B.Cu")
		(net "PHY_CON_A_TO_IOC_1_DN_C")
	)
	(segment
		(start 191.305434 -21.314156)
		(end 189.81547 -21.314156)
		(width 0.12446)
		(layer "B.Cu")
		(net "PHY_CON_A_TO_IOC_1_DN_C")
	)
	(segment
		(start 188.90361 -21.314156)
		(end 184.385458 -21.314156)
		(width 0.12446)
		(layer "B.Cu")
		(net "PHY_CON_A_TO_IOC_1_DN_C")
	)
	(segment
		(start 179.935632 -18.335498)
		(end 179.912518 -18.323052)
		(width 0.12446)
		(layer "B.Cu")
		(net "PHY_CON_A_TO_IOC_1_DN_C")
	)
	(segment
		(start 179.779676 -18.110708)
		(end 179.999894 -17.69999)
		(width 0.12446)
		(layer "B.Cu")
		(net "PHY_CON_A_TO_IOC_1_DN_C")
	)
	(segment
		(start 180.020214 -18.377916)
		(end 179.935632 -18.335498)
		(width 0.12446)
		(layer "B.Cu")
		(net "PHY_CON_A_TO_IOC_1_DN_C")
	)
	(arc
		(start 179.830476 -18.279364)
		(mid 179.770146 -18.205557)
		(end 179.779676 -18.110708)
		(width 0.12446)
		(layer "B.Cu")
		(net "PHY_CON_A_TO_IOC_1_DN_C")
	)
	(segment
		(start 201.19467 -74.299826)
		(end 201.200004 -74.299826)
		(width 0.12446)
		(layer "F.Cu")
		(net "PHY_CON_A_TO_IOC_1_DN")
	)
	(segment
		(start 200.79843 -73.903586)
		(end 201.19467 -74.299826)
		(width 0.12446)
		(layer "F.Cu")
		(net "PHY_CON_A_TO_IOC_1_DN")
	)
	(via
		(at 200.79843 -73.903586)
		(size 0.508)
		(drill 0.254)
		(layers "F.Cu" "B.Cu")
		(net "PHY_CON_A_TO_IOC_1_DN")
	)
	(segment
		(start 191.96939 -21.209)
		(end 192.07099 -21.3106)
		(width 0.12446)
		(layer "B.Cu")
		(net "PHY_CON_A_TO_IOC_1_DN")
	)
	(segment
		(start 216.705942 -38.712394)
		(end 220.966284 -60.017406)
		(width 0.12446)
		(layer "B.Cu")
		(net "PHY_CON_A_TO_IOC_1_DN")
	)
	(segment
		(start 197.28307 -21.678646)
		(end 211.802472 -31.356808)
		(width 0.12446)
		(layer "B.Cu")
		(net "PHY_CON_A_TO_IOC_1_DN")
	)
	(segment
		(start 204.33538 -75.57389)
		(end 204.22743 -75.46594)
		(width 0.0889)
		(layer "B.Cu")
		(net "PHY_CON_A_TO_IOC_1_DN")
	)
	(segment
		(start 203.141072 -75.46594)
		(end 202.572112 -74.89698)
		(width 0.0889)
		(layer "B.Cu")
		(net "PHY_CON_A_TO_IOC_1_DN")
	)
	(segment
		(start 204.357478 -75.57389)
		(end 204.33538 -75.57389)
		(width 0.0889)
		(layer "B.Cu")
		(net "PHY_CON_A_TO_IOC_1_DN")
	)
	(segment
		(start 200.963022 -73.903586)
		(end 200.79843 -73.903586)
		(width 0.0889)
		(layer "B.Cu")
		(net "PHY_CON_A_TO_IOC_1_DN")
	)
	(segment
		(start 201.511408 -74.89698)
		(end 201.07402 -74.459592)
		(width 0.0889)
		(layer "B.Cu")
		(net "PHY_CON_A_TO_IOC_1_DN")
	)
	(segment
		(start 220.966284 -60.017406)
		(end 218.42095 -72.729852)
		(width 0.12446)
		(layer "B.Cu")
		(net "PHY_CON_A_TO_IOC_1_DN")
	)
	(segment
		(start 205.56855 -75.57389)
		(end 204.357478 -75.57389)
		(width 0.12446)
		(layer "B.Cu")
		(net "PHY_CON_A_TO_IOC_1_DN")
	)
	(segment
		(start 201.07402 -74.459592)
		(end 201.07402 -74.029824)
		(width 0.0889)
		(layer "B.Cu")
		(net "PHY_CON_A_TO_IOC_1_DN")
	)
	(segment
		(start 192.07099 -21.3106)
		(end 195.389246 -21.3106)
		(width 0.12446)
		(layer "B.Cu")
		(net "PHY_CON_A_TO_IOC_1_DN")
	)
	(segment
		(start 206.15783 -76.16317)
		(end 205.56855 -75.57389)
		(width 0.12446)
		(layer "B.Cu")
		(net "PHY_CON_A_TO_IOC_1_DN")
	)
	(segment
		(start 202.572112 -74.89698)
		(end 201.511408 -74.89698)
		(width 0.0889)
		(layer "B.Cu")
		(net "PHY_CON_A_TO_IOC_1_DN")
	)
	(segment
		(start 214.987632 -76.16317)
		(end 206.15783 -76.16317)
		(width 0.12446)
		(layer "B.Cu")
		(net "PHY_CON_A_TO_IOC_1_DN")
	)
	(segment
		(start 218.42095 -72.729852)
		(end 214.987632 -76.16317)
		(width 0.12446)
		(layer "B.Cu")
		(net "PHY_CON_A_TO_IOC_1_DN")
	)
	(segment
		(start 204.22743 -75.46594)
		(end 203.141072 -75.46594)
		(width 0.0889)
		(layer "B.Cu")
		(net "PHY_CON_A_TO_IOC_1_DN")
	)
	(segment
		(start 201.036936 -73.94067)
		(end 201.026268 -73.929748)
		(width 0.0889)
		(layer "B.Cu")
		(net "PHY_CON_A_TO_IOC_1_DN")
	)
	(segment
		(start 195.389246 -21.3106)
		(end 197.28307 -21.678646)
		(width 0.12446)
		(layer "B.Cu")
		(net "PHY_CON_A_TO_IOC_1_DN")
	)
	(segment
		(start 211.802472 -31.356808)
		(end 216.705942 -38.712394)
		(width 0.12446)
		(layer "B.Cu")
		(net "PHY_CON_A_TO_IOC_1_DN")
	)
	(arc
		(start 201.026268 -73.929748)
		(mid 200.997264 -73.910335)
		(end 200.963022 -73.903586)
		(width 0.0889)
		(layer "B.Cu")
		(net "PHY_CON_A_TO_IOC_1_DN")
	)
	(arc
		(start 201.07402 -74.029824)
		(mid 201.064328 -73.981568)
		(end 201.036936 -73.94067)
		(width 0.0889)
		(layer "B.Cu")
		(net "PHY_CON_A_TO_IOC_1_DN")
	)
	(segment
		(start 183.778398 -19.3802)
		(end 182.59425 -19.3802)
		(width 0.12446)
		(layer "B.Cu")
		(net "PHY_CON_A_TO_IOC_0_DP_C")
	)
	(segment
		(start 191.41059 -19.812)
		(end 191.303402 -19.704812)
		(width 0.12446)
		(layer "B.Cu")
		(net "PHY_CON_A_TO_IOC_0_DP_C")
	)
	(segment
		(start 182.387494 -19.173444)
		(end 182.382668 -19.168364)
		(width 0.12446)
		(layer "B.Cu")
		(net "PHY_CON_A_TO_IOC_0_DP_C")
	)
	(segment
		(start 182.382668 -19.168364)
		(end 181.888892 -18.638012)
		(width 0.12446)
		(layer "B.Cu")
		(net "PHY_CON_A_TO_IOC_0_DP_C")
	)
	(segment
		(start 182.59425 -19.3802)
		(end 182.387494 -19.173444)
		(width 0.12446)
		(layer "B.Cu")
		(net "PHY_CON_A_TO_IOC_0_DP_C")
	)
	(segment
		(start 184.10301 -19.704812)
		(end 183.778398 -19.3802)
		(width 0.12446)
		(layer "B.Cu")
		(net "PHY_CON_A_TO_IOC_0_DP_C")
	)
	(segment
		(start 191.303402 -19.704812)
		(end 184.10301 -19.704812)
		(width 0.12446)
		(layer "B.Cu")
		(net "PHY_CON_A_TO_IOC_0_DP_C")
	)
	(segment
		(start 181.720236 -18.688812)
		(end 181.500018 -19.100038)
		(width 0.12446)
		(layer "B.Cu")
		(net "PHY_CON_A_TO_IOC_0_DP_C")
	)
	(arc
		(start 181.888892 -18.638012)
		(mid 181.794043 -18.628482)
		(end 181.720236 -18.688812)
		(width 0.12446)
		(layer "B.Cu")
		(net "PHY_CON_A_TO_IOC_0_DP_C")
	)
	(segment
		(start 202.399646 -75.499722)
		(end 201.99985 -75.099926)
		(width 0.12446)
		(layer "F.Cu")
		(net "PHY_CON_A_TO_IOC_0_DP")
	)
	(via
		(at 202.399646 -75.499722)
		(size 0.508)
		(drill 0.254)
		(layers "F.Cu" "B.Cu")
		(net "PHY_CON_A_TO_IOC_0_DP")
	)
	(segment
		(start 208.896458 -28.39466)
		(end 208.585816 -28.18765)
		(width 0.12446)
		(layer "B.Cu")
		(net "PHY_CON_A_TO_IOC_0_DP")
	)
	(segment
		(start 209.65541 -28.900374)
		(end 209.58048 -28.526994)
		(width 0.12446)
		(layer "B.Cu")
		(net "PHY_CON_A_TO_IOC_0_DP")
	)
	(segment
		(start 209.966052 -29.107384)
		(end 209.65541 -28.900374)
		(width 0.12446)
		(layer "B.Cu")
		(net "PHY_CON_A_TO_IOC_0_DP")
	)
	(segment
		(start 203.840334 -76.357226)
		(end 203.9493 -76.24826)
		(width 0.0889)
		(layer "B.Cu")
		(net "PHY_CON_A_TO_IOC_0_DP")
	)
	(segment
		(start 221.833694 -59.987434)
		(end 217.449654 -38.064948)
		(width 0.12446)
		(layer "B.Cu")
		(net "PHY_CON_A_TO_IOC_0_DP")
	)
	(segment
		(start 211.035646 -29.820108)
		(end 210.72475 -29.613098)
		(width 0.12446)
		(layer "B.Cu")
		(net "PHY_CON_A_TO_IOC_0_DP")
	)
	(segment
		(start 204.430122 -76.24826)
		(end 205.180692 -76.99883)
		(width 0.12446)
		(layer "B.Cu")
		(net "PHY_CON_A_TO_IOC_0_DP")
	)
	(segment
		(start 216.447116 -76.99883)
		(end 218.929966 -74.51598)
		(width 0.12446)
		(layer "B.Cu")
		(net "PHY_CON_A_TO_IOC_0_DP")
	)
	(segment
		(start 201.251058 -23.299674)
		(end 200.940416 -23.092664)
		(width 0.12446)
		(layer "B.Cu")
		(net "PHY_CON_A_TO_IOC_0_DP")
	)
	(segment
		(start 202.08113 -75.654408)
		(end 202.08113 -75.935078)
		(width 0.0889)
		(layer "B.Cu")
		(net "PHY_CON_A_TO_IOC_0_DP")
	)
	(segment
		(start 202.320652 -24.012398)
		(end 202.01001 -23.805388)
		(width 0.12446)
		(layer "B.Cu")
		(net "PHY_CON_A_TO_IOC_0_DP")
	)
	(segment
		(start 202.01001 -23.805388)
		(end 201.935334 -23.432008)
		(width 0.12446)
		(layer "B.Cu")
		(net "PHY_CON_A_TO_IOC_0_DP")
	)
	(segment
		(start 209.269838 -28.319984)
		(end 208.896458 -28.39466)
		(width 0.12446)
		(layer "B.Cu")
		(net "PHY_CON_A_TO_IOC_0_DP")
	)
	(segment
		(start 203.079604 -24.518112)
		(end 203.004674 -24.144732)
		(width 0.12446)
		(layer "B.Cu")
		(net "PHY_CON_A_TO_IOC_0_DP")
	)
	(segment
		(start 208.51114 -27.81427)
		(end 203.763372 -24.650446)
		(width 0.12446)
		(layer "B.Cu")
		(net "PHY_CON_A_TO_IOC_0_DP")
	)
	(segment
		(start 201.624438 -23.224998)
		(end 201.251058 -23.299674)
		(width 0.12446)
		(layer "B.Cu")
		(net "PHY_CON_A_TO_IOC_0_DP")
	)
	(segment
		(start 200.940416 -23.092664)
		(end 200.86574 -22.719284)
		(width 0.12446)
		(layer "B.Cu")
		(net "PHY_CON_A_TO_IOC_0_DP")
	)
	(segment
		(start 212.300312 -30.339284)
		(end 211.409026 -29.745432)
		(width 0.12446)
		(layer "B.Cu")
		(net "PHY_CON_A_TO_IOC_0_DP")
	)
	(segment
		(start 202.399646 -75.499722)
		(end 202.23607 -75.499722)
		(width 0.0889)
		(layer "B.Cu")
		(net "PHY_CON_A_TO_IOC_0_DP")
	)
	(segment
		(start 208.585816 -28.18765)
		(end 208.51114 -27.81427)
		(width 0.12446)
		(layer "B.Cu")
		(net "PHY_CON_A_TO_IOC_0_DP")
	)
	(segment
		(start 200.181718 -22.58695)
		(end 199.870822 -22.37994)
		(width 0.12446)
		(layer "B.Cu")
		(net "PHY_CON_A_TO_IOC_0_DP")
	)
	(segment
		(start 209.58048 -28.526994)
		(end 209.269838 -28.319984)
		(width 0.12446)
		(layer "B.Cu")
		(net "PHY_CON_A_TO_IOC_0_DP")
	)
	(segment
		(start 203.763372 -24.650446)
		(end 203.390246 -24.725122)
		(width 0.12446)
		(layer "B.Cu")
		(net "PHY_CON_A_TO_IOC_0_DP")
	)
	(segment
		(start 210.339432 -29.032708)
		(end 209.966052 -29.107384)
		(width 0.12446)
		(layer "B.Cu")
		(net "PHY_CON_A_TO_IOC_0_DP")
	)
	(segment
		(start 202.503278 -76.357226)
		(end 203.840334 -76.357226)
		(width 0.0889)
		(layer "B.Cu")
		(net "PHY_CON_A_TO_IOC_0_DP")
	)
	(segment
		(start 200.555098 -22.512274)
		(end 200.181718 -22.58695)
		(width 0.12446)
		(layer "B.Cu")
		(net "PHY_CON_A_TO_IOC_0_DP")
	)
	(segment
		(start 210.72475 -29.613098)
		(end 210.650074 -29.239718)
		(width 0.12446)
		(layer "B.Cu")
		(net "PHY_CON_A_TO_IOC_0_DP")
	)
	(segment
		(start 203.9493 -76.24826)
		(end 204.430122 -76.24826)
		(width 0.12446)
		(layer "B.Cu")
		(net "PHY_CON_A_TO_IOC_0_DP")
	)
	(segment
		(start 211.409026 -29.745432)
		(end 211.035646 -29.820108)
		(width 0.12446)
		(layer "B.Cu")
		(net "PHY_CON_A_TO_IOC_0_DP")
	)
	(segment
		(start 199.870822 -22.37994)
		(end 199.796146 -22.00656)
		(width 0.12446)
		(layer "B.Cu")
		(net "PHY_CON_A_TO_IOC_0_DP")
	)
	(segment
		(start 205.180692 -76.99883)
		(end 216.447116 -76.99883)
		(width 0.12446)
		(layer "B.Cu")
		(net "PHY_CON_A_TO_IOC_0_DP")
	)
	(segment
		(start 202.694032 -23.937722)
		(end 202.320652 -24.012398)
		(width 0.12446)
		(layer "B.Cu")
		(net "PHY_CON_A_TO_IOC_0_DP")
	)
	(segment
		(start 202.08113 -75.935078)
		(end 202.503278 -76.357226)
		(width 0.0889)
		(layer "B.Cu")
		(net "PHY_CON_A_TO_IOC_0_DP")
	)
	(segment
		(start 200.86574 -22.719284)
		(end 200.555098 -22.512274)
		(width 0.12446)
		(layer "B.Cu")
		(net "PHY_CON_A_TO_IOC_0_DP")
	)
	(segment
		(start 218.929966 -74.51598)
		(end 221.833694 -59.987434)
		(width 0.12446)
		(layer "B.Cu")
		(net "PHY_CON_A_TO_IOC_0_DP")
	)
	(segment
		(start 210.650074 -29.239718)
		(end 210.339432 -29.032708)
		(width 0.12446)
		(layer "B.Cu")
		(net "PHY_CON_A_TO_IOC_0_DP")
	)
	(segment
		(start 196.267324 -19.655028)
		(end 192.126362 -19.655028)
		(width 0.12446)
		(layer "B.Cu")
		(net "PHY_CON_A_TO_IOC_0_DP")
	)
	(segment
		(start 192.126362 -19.655028)
		(end 191.96939 -19.812)
		(width 0.12446)
		(layer "B.Cu")
		(net "PHY_CON_A_TO_IOC_0_DP")
	)
	(segment
		(start 217.449654 -38.064948)
		(end 212.300312 -30.339284)
		(width 0.12446)
		(layer "B.Cu")
		(net "PHY_CON_A_TO_IOC_0_DP")
	)
	(segment
		(start 203.390246 -24.725122)
		(end 203.079604 -24.518112)
		(width 0.12446)
		(layer "B.Cu")
		(net "PHY_CON_A_TO_IOC_0_DP")
	)
	(segment
		(start 203.004674 -24.144732)
		(end 202.694032 -23.937722)
		(width 0.12446)
		(layer "B.Cu")
		(net "PHY_CON_A_TO_IOC_0_DP")
	)
	(segment
		(start 201.935334 -23.432008)
		(end 201.624438 -23.224998)
		(width 0.12446)
		(layer "B.Cu")
		(net "PHY_CON_A_TO_IOC_0_DP")
	)
	(segment
		(start 199.796146 -22.00656)
		(end 196.267324 -19.655028)
		(width 0.12446)
		(layer "B.Cu")
		(net "PHY_CON_A_TO_IOC_0_DP")
	)
	(arc
		(start 202.126342 -75.545188)
		(mid 202.092859 -75.595299)
		(end 202.08113 -75.654408)
		(width 0.0889)
		(layer "B.Cu")
		(net "PHY_CON_A_TO_IOC_0_DP")
	)
	(arc
		(start 202.23607 -75.499722)
		(mid 202.17668 -75.511535)
		(end 202.126342 -75.545188)
		(width 0.0889)
		(layer "B.Cu")
		(net "PHY_CON_A_TO_IOC_0_DP")
	)
	(segment
		(start 182.680102 -18.89125)
		(end 182.186326 -18.360898)
		(width 0.12446)
		(layer "B.Cu")
		(net "PHY_CON_A_TO_IOC_0_DN_C")
	)
	(segment
		(start 182.186326 -18.360898)
		(end 182.080662 -18.279618)
		(width 0.12446)
		(layer "B.Cu")
		(net "PHY_CON_A_TO_IOC_0_DN_C")
	)
	(segment
		(start 190.382906 -19.298412)
		(end 190.113666 -19.029172)
		(width 0.12446)
		(layer "B.Cu")
		(net "PHY_CON_A_TO_IOC_0_DN_C")
	)
	(segment
		(start 191.41059 -19.177)
		(end 191.380364 -19.206972)
		(width 0.12446)
		(layer "B.Cu")
		(net "PHY_CON_A_TO_IOC_0_DN_C")
	)
	(segment
		(start 189.740286 -19.029172)
		(end 189.471046 -19.298412)
		(width 0.12446)
		(layer "B.Cu")
		(net "PHY_CON_A_TO_IOC_0_DN_C")
	)
	(segment
		(start 183.9468 -18.9738)
		(end 182.762652 -18.9738)
		(width 0.12446)
		(layer "B.Cu")
		(net "PHY_CON_A_TO_IOC_0_DN_C")
	)
	(segment
		(start 182.762652 -18.9738)
		(end 182.680102 -18.89125)
		(width 0.12446)
		(layer "B.Cu")
		(net "PHY_CON_A_TO_IOC_0_DN_C")
	)
	(segment
		(start 190.113666 -19.029172)
		(end 189.740286 -19.029172)
		(width 0.12446)
		(layer "B.Cu")
		(net "PHY_CON_A_TO_IOC_0_DN_C")
	)
	(segment
		(start 184.271412 -19.298412)
		(end 183.9468 -18.9738)
		(width 0.12446)
		(layer "B.Cu")
		(net "PHY_CON_A_TO_IOC_0_DN_C")
	)
	(segment
		(start 189.471046 -19.298412)
		(end 184.271412 -19.298412)
		(width 0.12446)
		(layer "B.Cu")
		(net "PHY_CON_A_TO_IOC_0_DN_C")
	)
	(segment
		(start 182.029862 -18.111216)
		(end 182.25008 -17.69999)
		(width 0.12446)
		(layer "B.Cu")
		(net "PHY_CON_A_TO_IOC_0_DN_C")
	)
	(segment
		(start 191.380364 -19.206972)
		(end 191.288924 -19.298412)
		(width 0.12446)
		(layer "B.Cu")
		(net "PHY_CON_A_TO_IOC_0_DN_C")
	)
	(segment
		(start 191.288924 -19.298412)
		(end 190.382906 -19.298412)
		(width 0.12446)
		(layer "B.Cu")
		(net "PHY_CON_A_TO_IOC_0_DN_C")
	)
	(arc
		(start 182.080662 -18.279618)
		(mid 182.020365 -18.205918)
		(end 182.029862 -18.111216)
		(width 0.12446)
		(layer "B.Cu")
		(net "PHY_CON_A_TO_IOC_0_DN_C")
	)
	(segment
		(start 201.200004 -75.099926)
		(end 201.5998 -75.499722)
		(width 0.12446)
		(layer "F.Cu")
		(net "PHY_CON_A_TO_IOC_0_DN")
	)
	(via
		(at 201.5998 -75.499722)
		(size 0.508)
		(drill 0.254)
		(layers "F.Cu" "B.Cu")
		(net "PHY_CON_A_TO_IOC_0_DN")
	)
	(segment
		(start 212.593428 -30.046168)
		(end 211.49437 -29.313886)
		(width 0.12446)
		(layer "B.Cu")
		(net "PHY_CON_A_TO_IOC_0_DN")
	)
	(segment
		(start 201.89063 -75.652376)
		(end 201.89063 -76.014072)
		(width 0.0889)
		(layer "B.Cu")
		(net "PHY_CON_A_TO_IOC_0_DN")
	)
	(segment
		(start 217.832432 -37.906452)
		(end 212.593428 -30.046168)
		(width 0.12446)
		(layer "B.Cu")
		(net "PHY_CON_A_TO_IOC_0_DN")
	)
	(segment
		(start 222.248222 -59.987434)
		(end 217.832432 -37.906452)
		(width 0.12446)
		(layer "B.Cu")
		(net "PHY_CON_A_TO_IOC_0_DN")
	)
	(segment
		(start 203.842366 -76.547726)
		(end 203.9493 -76.65466)
		(width 0.0889)
		(layer "B.Cu")
		(net "PHY_CON_A_TO_IOC_0_DN")
	)
	(segment
		(start 201.5998 -75.499722)
		(end 201.737976 -75.499722)
		(width 0.0889)
		(layer "B.Cu")
		(net "PHY_CON_A_TO_IOC_0_DN")
	)
	(segment
		(start 219.304362 -74.716386)
		(end 222.248222 -59.987434)
		(width 0.12446)
		(layer "B.Cu")
		(net "PHY_CON_A_TO_IOC_0_DN")
	)
	(segment
		(start 203.9493 -76.65466)
		(end 204.26172 -76.65466)
		(width 0.12446)
		(layer "B.Cu")
		(net "PHY_CON_A_TO_IOC_0_DN")
	)
	(segment
		(start 203.848716 -24.218646)
		(end 196.390514 -19.248628)
		(width 0.12446)
		(layer "B.Cu")
		(net "PHY_CON_A_TO_IOC_0_DN")
	)
	(segment
		(start 204.26172 -76.65466)
		(end 205.01229 -77.40523)
		(width 0.12446)
		(layer "B.Cu")
		(net "PHY_CON_A_TO_IOC_0_DN")
	)
	(segment
		(start 216.615518 -77.40523)
		(end 219.304362 -74.716386)
		(width 0.12446)
		(layer "B.Cu")
		(net "PHY_CON_A_TO_IOC_0_DN")
	)
	(segment
		(start 211.49437 -29.313886)
		(end 211.49437 -29.313632)
		(width 0.12446)
		(layer "B.Cu")
		(net "PHY_CON_A_TO_IOC_0_DN")
	)
	(segment
		(start 192.041018 -19.248628)
		(end 191.96939 -19.177)
		(width 0.12446)
		(layer "B.Cu")
		(net "PHY_CON_A_TO_IOC_0_DN")
	)
	(segment
		(start 211.49437 -29.313632)
		(end 203.848716 -24.218646)
		(width 0.12446)
		(layer "B.Cu")
		(net "PHY_CON_A_TO_IOC_0_DN")
	)
	(segment
		(start 201.89063 -76.014072)
		(end 202.424284 -76.547726)
		(width 0.0889)
		(layer "B.Cu")
		(net "PHY_CON_A_TO_IOC_0_DN")
	)
	(segment
		(start 202.424284 -76.547726)
		(end 203.842366 -76.547726)
		(width 0.0889)
		(layer "B.Cu")
		(net "PHY_CON_A_TO_IOC_0_DN")
	)
	(segment
		(start 205.01229 -77.40523)
		(end 216.615518 -77.40523)
		(width 0.12446)
		(layer "B.Cu")
		(net "PHY_CON_A_TO_IOC_0_DN")
	)
	(segment
		(start 196.390514 -19.248628)
		(end 192.041018 -19.248628)
		(width 0.12446)
		(layer "B.Cu")
		(net "PHY_CON_A_TO_IOC_0_DN")
	)
	(arc
		(start 201.737976 -75.499722)
		(mid 201.796394 -75.511342)
		(end 201.845926 -75.544426)
		(width 0.0889)
		(layer "B.Cu")
		(net "PHY_CON_A_TO_IOC_0_DN")
	)
	(arc
		(start 201.845926 -75.544426)
		(mid 201.879019 -75.593954)
		(end 201.89063 -75.652376)
		(width 0.0889)
		(layer "B.Cu")
		(net "PHY_CON_A_TO_IOC_0_DN")
	)
	(segment
		(start 35.680396 -138.499596)
		(end 36.8554 -139.6746)
		(width 0.127)
		(layer "F.Cu")
		(net "PECI")
	)
	(segment
		(start 39.17442 -139.6746)
		(end 36.8554 -139.6746)
		(width 0.127)
		(layer "F.Cu")
		(net "PECI")
	)
	(segment
		(start 35.680396 -136.73709)
		(end 35.680396 -138.499596)
		(width 0.127)
		(layer "F.Cu")
		(net "PECI")
	)
	(segment
		(start 39.299896 -139.800076)
		(end 39.17442 -139.6746)
		(width 0.127)
		(layer "F.Cu")
		(net "PECI")
	)
	(via
		(at 36.8554 -139.6746)
		(size 0.6604)
		(drill 0.3302)
		(layers "F.Cu" "B.Cu")
		(net "PECI")
	)
	(segment
		(start 55.645558 -148.9456)
		(end 55.299864 -148.599906)
		(width 0.127)
		(layer "F.Cu")
		(net "PD_USB2BVRES")
	)
	(segment
		(start 60.198 -151.7396)
		(end 60.198 -151.6634)
		(width 0.127)
		(layer "F.Cu")
		(net "PD_USB2BVRES")
	)
	(segment
		(start 60.198 -151.6634)
		(end 58.47334 -149.93874)
		(width 0.127)
		(layer "F.Cu")
		(net "PD_USB2BVRES")
	)
	(segment
		(start 60.4266 -152.654)
		(end 60.198 -152.4254)
		(width 0.127)
		(layer "F.Cu")
		(net "PD_USB2BVRES")
	)
	(segment
		(start 57.55894 -149.93874)
		(end 56.5658 -148.9456)
		(width 0.127)
		(layer "F.Cu")
		(net "PD_USB2BVRES")
	)
	(segment
		(start 56.5658 -148.9456)
		(end 55.645558 -148.9456)
		(width 0.127)
		(layer "F.Cu")
		(net "PD_USB2BVRES")
	)
	(segment
		(start 60.9219 -152.654)
		(end 60.4266 -152.654)
		(width 0.127)
		(layer "F.Cu")
		(net "PD_USB2BVRES")
	)
	(segment
		(start 60.198 -152.4254)
		(end 60.198 -151.7396)
		(width 0.127)
		(layer "F.Cu")
		(net "PD_USB2BVRES")
	)
	(segment
		(start 58.47334 -149.93874)
		(end 57.55894 -149.93874)
		(width 0.127)
		(layer "F.Cu")
		(net "PD_USB2BVRES")
	)
	(via
		(at 60.198 -151.7396)
		(size 0.6604)
		(drill 0.3302)
		(layers "F.Cu" "B.Cu")
		(net "PD_USB2BVRES")
	)
	(segment
		(start 55.76824 -147.45716)
		(end 55.42534 -147.80006)
		(width 0.127)
		(layer "F.Cu")
		(net "PD_USB2AVRES")
	)
	(segment
		(start 60.608718 -149.5806)
		(end 60.418218 -149.3901)
		(width 0.127)
		(layer "F.Cu")
		(net "PD_USB2AVRES")
	)
	(segment
		(start 56.9214 -147.45716)
		(end 55.76824 -147.45716)
		(width 0.127)
		(layer "F.Cu")
		(net "PD_USB2AVRES")
	)
	(segment
		(start 60.418218 -149.3901)
		(end 59.693048 -149.3901)
		(width 0.127)
		(layer "F.Cu")
		(net "PD_USB2AVRES")
	)
	(segment
		(start 61.914278 -148.59)
		(end 61.2902 -148.59)
		(width 0.127)
		(layer "F.Cu")
		(net "PD_USB2AVRES")
	)
	(segment
		(start 61.2902 -148.59)
		(end 61.0235 -148.8567)
		(width 0.127)
		(layer "F.Cu")
		(net "PD_USB2AVRES")
	)
	(segment
		(start 55.42534 -147.80006)
		(end 55.299864 -147.80006)
		(width 0.127)
		(layer "F.Cu")
		(net "PD_USB2AVRES")
	)
	(segment
		(start 62.587378 -149.2631)
		(end 61.914278 -148.59)
		(width 0.127)
		(layer "F.Cu")
		(net "PD_USB2AVRES")
	)
	(segment
		(start 63.246 -149.2631)
		(end 62.587378 -149.2631)
		(width 0.127)
		(layer "F.Cu")
		(net "PD_USB2AVRES")
	)
	(segment
		(start 58.051192 -148.586952)
		(end 56.9214 -147.45716)
		(width 0.127)
		(layer "F.Cu")
		(net "PD_USB2AVRES")
	)
	(segment
		(start 59.693048 -149.3901)
		(end 58.8899 -148.586952)
		(width 0.127)
		(layer "F.Cu")
		(net "PD_USB2AVRES")
	)
	(segment
		(start 63.8937 -149.9108)
		(end 63.246 -149.2631)
		(width 0.127)
		(layer "F.Cu")
		(net "PD_USB2AVRES")
	)
	(segment
		(start 61.0235 -149.5806)
		(end 60.608718 -149.5806)
		(width 0.127)
		(layer "F.Cu")
		(net "PD_USB2AVRES")
	)
	(segment
		(start 58.8899 -148.586952)
		(end 58.051192 -148.586952)
		(width 0.127)
		(layer "F.Cu")
		(net "PD_USB2AVRES")
	)
	(segment
		(start 61.0235 -148.8567)
		(end 61.0235 -149.5806)
		(width 0.127)
		(layer "F.Cu")
		(net "PD_USB2AVRES")
	)
	(via
		(at 61.2902 -148.59)
		(size 0.6604)
		(drill 0.3302)
		(layers "F.Cu" "B.Cu")
		(net "PD_USB2AVRES")
	)
	(via
		(at 88.69426 -173.35246)
		(size 0.6096)
		(drill 0.3048)
		(layers "F.Cu" "B.Cu")
		(net "PCIE_RST_R_N")
	)
	(segment
		(start 89.7382 -170.128946)
		(end 89.306654 -169.6974)
		(width 0.127)
		(layer "B.Cu")
		(net "PCIE_RST_R_N")
	)
	(segment
		(start 88.519 -173.1772)
		(end 88.519 -171.64812)
		(width 0.127)
		(layer "B.Cu")
		(net "PCIE_RST_R_N")
	)
	(segment
		(start 88.519 -171.64812)
		(end 89.3445 -171.64812)
		(width 0.127)
		(layer "B.Cu")
		(net "PCIE_RST_R_N")
	)
	(segment
		(start 88.69426 -173.35246)
		(end 88.519 -173.1772)
		(width 0.127)
		(layer "B.Cu")
		(net "PCIE_RST_R_N")
	)
	(segment
		(start 89.8017 -173.5836)
		(end 88.9254 -173.5836)
		(width 0.127)
		(layer "B.Cu")
		(net "PCIE_RST_R_N")
	)
	(segment
		(start 89.7382 -171.25442)
		(end 89.7382 -170.128946)
		(width 0.127)
		(layer "B.Cu")
		(net "PCIE_RST_R_N")
	)
	(segment
		(start 89.306654 -169.6974)
		(end 88.519 -169.6974)
		(width 0.127)
		(layer "B.Cu")
		(net "PCIE_RST_R_N")
	)
	(segment
		(start 89.3445 -171.64812)
		(end 89.7382 -171.25442)
		(width 0.127)
		(layer "B.Cu")
		(net "PCIE_RST_R_N")
	)
	(segment
		(start 88.9254 -173.5836)
		(end 88.69426 -173.35246)
		(width 0.127)
		(layer "B.Cu")
		(net "PCIE_RST_R_N")
	)
	(segment
		(start 198.809102 -74.299826)
		(end 199.201532 -74.692256)
		(width 0.09525)
		(layer "F.Cu")
		(net "PCIE_IOM_TO_COMP_9_DP_C")
	)
	(segment
		(start 198.799958 -74.299826)
		(end 198.809102 -74.299826)
		(width 0.09525)
		(layer "F.Cu")
		(net "PCIE_IOM_TO_COMP_9_DP_C")
	)
	(via
		(at 199.201532 -74.692256)
		(size 0.4572)
		(drill 0.2032)
		(layers "F.Cu" "B.Cu")
		(net "PCIE_IOM_TO_COMP_9_DP_C")
	)
	(segment
		(start 200.238614 -80.752696)
		(end 200.359518 -80.8736)
		(width 0.14605)
		(layer "B.Cu")
		(net "PCIE_IOM_TO_COMP_9_DP_C")
	)
	(segment
		(start 200.238614 -77.586332)
		(end 200.238614 -80.752696)
		(width 0.14605)
		(layer "B.Cu")
		(net "PCIE_IOM_TO_COMP_9_DP_C")
	)
	(segment
		(start 199.730614 -77.078332)
		(end 200.238614 -77.586332)
		(width 0.14605)
		(layer "B.Cu")
		(net "PCIE_IOM_TO_COMP_9_DP_C")
	)
	(segment
		(start 199.71385 -77.061568)
		(end 199.730614 -77.078332)
		(width 0.09525)
		(layer "B.Cu")
		(net "PCIE_IOM_TO_COMP_9_DP_C")
	)
	(segment
		(start 199.623934 -77.061314)
		(end 199.624188 -77.061568)
		(width 0.09525)
		(layer "B.Cu")
		(net "PCIE_IOM_TO_COMP_9_DP_C")
	)
	(segment
		(start 199.10425 -76.542646)
		(end 199.623934 -77.061314)
		(width 0.09525)
		(layer "B.Cu")
		(net "PCIE_IOM_TO_COMP_9_DP_C")
	)
	(segment
		(start 199.624188 -77.061568)
		(end 199.71385 -77.061568)
		(width 0.09525)
		(layer "B.Cu")
		(net "PCIE_IOM_TO_COMP_9_DP_C")
	)
	(segment
		(start 199.10425 -74.776838)
		(end 199.10425 -76.542646)
		(width 0.09525)
		(layer "B.Cu")
		(net "PCIE_IOM_TO_COMP_9_DP_C")
	)
	(segment
		(start 199.201532 -74.692256)
		(end 199.10425 -74.776838)
		(width 0.09525)
		(layer "B.Cu")
		(net "PCIE_IOM_TO_COMP_9_DP_C")
	)
	(segment
		(start 188.146944 -93.891862)
		(end 188.576712 -93.80601)
		(width 0.14605)
		(layer "B.Cu")
		(net "PCIE_IOM_TO_COMP_9_DP")
	)
	(segment
		(start 148.50618 -45.089572)
		(end 148.592032 -45.519086)
		(width 0.14605)
		(layer "B.Cu")
		(net "PCIE_IOM_TO_COMP_9_DP")
	)
	(segment
		(start 146.586448 -34.712148)
		(end 146.466814 -34.891472)
		(width 0.14605)
		(layer "B.Cu")
		(net "PCIE_IOM_TO_COMP_9_DP")
	)
	(segment
		(start 185.101992 -94.500954)
		(end 185.221372 -94.32163)
		(width 0.14605)
		(layer "B.Cu")
		(net "PCIE_IOM_TO_COMP_9_DP")
	)
	(segment
		(start 146.732244 -35.44062)
		(end 146.818096 -35.870388)
		(width 0.14605)
		(layer "B.Cu")
		(net "PCIE_IOM_TO_COMP_9_DP")
	)
	(segment
		(start 148.162518 -42.593768)
		(end 148.042884 -42.773092)
		(width 0.14605)
		(layer "B.Cu")
		(net "PCIE_IOM_TO_COMP_9_DP")
	)
	(segment
		(start 146.784314 -36.479226)
		(end 146.963638 -36.59886)
		(width 0.14605)
		(layer "B.Cu")
		(net "PCIE_IOM_TO_COMP_9_DP")
	)
	(segment
		(start 148.737828 -46.247558)
		(end 148.82368 -46.677326)
		(width 0.14605)
		(layer "B.Cu")
		(net "PCIE_IOM_TO_COMP_9_DP")
	)
	(segment
		(start 149.088856 -47.226474)
		(end 146.710146 -59.13374)
		(width 0.14605)
		(layer "B.Cu")
		(net "PCIE_IOM_TO_COMP_9_DP")
	)
	(segment
		(start 149.003004 -46.796706)
		(end 149.088856 -47.226474)
		(width 0.14605)
		(layer "B.Cu")
		(net "PCIE_IOM_TO_COMP_9_DP")
	)
	(segment
		(start 146.23542 -33.733486)
		(end 146.321272 -34.163)
		(width 0.14605)
		(layer "B.Cu")
		(net "PCIE_IOM_TO_COMP_9_DP")
	)
	(segment
		(start 186.988704 -94.12351)
		(end 187.418472 -94.037658)
		(width 0.14605)
		(layer "B.Cu")
		(net "PCIE_IOM_TO_COMP_9_DP")
	)
	(segment
		(start 147.195286 -37.7571)
		(end 148.162518 -42.593768)
		(width 0.14605)
		(layer "B.Cu")
		(net "PCIE_IOM_TO_COMP_9_DP")
	)
	(segment
		(start 146.466814 -34.891472)
		(end 146.55292 -35.32124)
		(width 0.14605)
		(layer "B.Cu")
		(net "PCIE_IOM_TO_COMP_9_DP")
	)
	(segment
		(start 185.65114 -94.235778)
		(end 185.830464 -94.355158)
		(width 0.14605)
		(layer "B.Cu")
		(net "PCIE_IOM_TO_COMP_9_DP")
	)
	(segment
		(start 138.755374 -37.053774)
		(end 138.755374 -30.18028)
		(width 0.14605)
		(layer "B.Cu")
		(net "PCIE_IOM_TO_COMP_9_DP")
	)
	(segment
		(start 148.62556 -44.910248)
		(end 148.50618 -45.089572)
		(width 0.14605)
		(layer "B.Cu")
		(net "PCIE_IOM_TO_COMP_9_DP")
	)
	(segment
		(start 189.12586 -93.540834)
		(end 194.566032 -89.914476)
		(width 0.14605)
		(layer "B.Cu")
		(net "PCIE_IOM_TO_COMP_9_DP")
	)
	(segment
		(start 188.696092 -93.626686)
		(end 189.12586 -93.540834)
		(width 0.14605)
		(layer "B.Cu")
		(net "PCIE_IOM_TO_COMP_9_DP")
	)
	(segment
		(start 194.566032 -89.914476)
		(end 200.243948 -84.236306)
		(width 0.14605)
		(layer "B.Cu")
		(net "PCIE_IOM_TO_COMP_9_DP")
	)
	(segment
		(start 147.049744 -37.028628)
		(end 146.93011 -37.207952)
		(width 0.14605)
		(layer "B.Cu")
		(net "PCIE_IOM_TO_COMP_9_DP")
	)
	(segment
		(start 148.394166 -43.752008)
		(end 148.274532 -43.931332)
		(width 0.14605)
		(layer "B.Cu")
		(net "PCIE_IOM_TO_COMP_9_DP")
	)
	(segment
		(start 139.499848 -36.800028)
		(end 139.499848 -37.11829)
		(width 0.14605)
		(layer "B.Cu")
		(net "PCIE_IOM_TO_COMP_9_DP")
	)
	(segment
		(start 186.80938 -94.00413)
		(end 186.988704 -94.12351)
		(width 0.14605)
		(layer "B.Cu")
		(net "PCIE_IOM_TO_COMP_9_DP")
	)
	(segment
		(start 151.654256 -78.504796)
		(end 161.77641 -85.227414)
		(width 0.14605)
		(layer "B.Cu")
		(net "PCIE_IOM_TO_COMP_9_DP")
	)
	(segment
		(start 148.82368 -46.677326)
		(end 149.003004 -46.796706)
		(width 0.14605)
		(layer "B.Cu")
		(net "PCIE_IOM_TO_COMP_9_DP")
	)
	(segment
		(start 148.360384 -44.360846)
		(end 148.539708 -44.48048)
		(width 0.14605)
		(layer "B.Cu")
		(net "PCIE_IOM_TO_COMP_9_DP")
	)
	(segment
		(start 148.857208 -46.068234)
		(end 148.737828 -46.247558)
		(width 0.14605)
		(layer "B.Cu")
		(net "PCIE_IOM_TO_COMP_9_DP")
	)
	(segment
		(start 138.755374 -30.18028)
		(end 139.786868 -29.148786)
		(width 0.14605)
		(layer "B.Cu")
		(net "PCIE_IOM_TO_COMP_9_DP")
	)
	(segment
		(start 142.895574 -29.148786)
		(end 144.20088 -30.019498)
		(width 0.14605)
		(layer "B.Cu")
		(net "PCIE_IOM_TO_COMP_9_DP")
	)
	(segment
		(start 139.274042 -37.34435)
		(end 139.04595 -37.34435)
		(width 0.14605)
		(layer "B.Cu")
		(net "PCIE_IOM_TO_COMP_9_DP")
	)
	(segment
		(start 147.015962 -37.637466)
		(end 147.195286 -37.7571)
		(width 0.14605)
		(layer "B.Cu")
		(net "PCIE_IOM_TO_COMP_9_DP")
	)
	(segment
		(start 187.96762 -93.772482)
		(end 188.146944 -93.891862)
		(width 0.14605)
		(layer "B.Cu")
		(net "PCIE_IOM_TO_COMP_9_DP")
	)
	(segment
		(start 184.672224 -94.586806)
		(end 185.101992 -94.500954)
		(width 0.14605)
		(layer "B.Cu")
		(net "PCIE_IOM_TO_COMP_9_DP")
	)
	(segment
		(start 146.93011 -37.207952)
		(end 147.015962 -37.637466)
		(width 0.14605)
		(layer "B.Cu")
		(net "PCIE_IOM_TO_COMP_9_DP")
	)
	(segment
		(start 144.20088 -30.019498)
		(end 146.268948 -33.124394)
		(width 0.14605)
		(layer "B.Cu")
		(net "PCIE_IOM_TO_COMP_9_DP")
	)
	(segment
		(start 146.3548 -33.554162)
		(end 146.23542 -33.733486)
		(width 0.14605)
		(layer "B.Cu")
		(net "PCIE_IOM_TO_COMP_9_DP")
	)
	(segment
		(start 200.243948 -81.54797)
		(end 200.359518 -81.4324)
		(width 0.14605)
		(layer "B.Cu")
		(net "PCIE_IOM_TO_COMP_9_DP")
	)
	(segment
		(start 200.243948 -84.236306)
		(end 200.243948 -81.54797)
		(width 0.14605)
		(layer "B.Cu")
		(net "PCIE_IOM_TO_COMP_9_DP")
	)
	(segment
		(start 148.771356 -45.63872)
		(end 148.857208 -46.068234)
		(width 0.14605)
		(layer "B.Cu")
		(net "PCIE_IOM_TO_COMP_9_DP")
	)
	(segment
		(start 148.042884 -42.773092)
		(end 148.128736 -43.20286)
		(width 0.14605)
		(layer "B.Cu")
		(net "PCIE_IOM_TO_COMP_9_DP")
	)
	(segment
		(start 186.379612 -94.089982)
		(end 186.80938 -94.00413)
		(width 0.14605)
		(layer "B.Cu")
		(net "PCIE_IOM_TO_COMP_9_DP")
	)
	(segment
		(start 148.274532 -43.931332)
		(end 148.360384 -44.360846)
		(width 0.14605)
		(layer "B.Cu")
		(net "PCIE_IOM_TO_COMP_9_DP")
	)
	(segment
		(start 146.55292 -35.32124)
		(end 146.732244 -35.44062)
		(width 0.14605)
		(layer "B.Cu")
		(net "PCIE_IOM_TO_COMP_9_DP")
	)
	(segment
		(start 148.30806 -43.32224)
		(end 148.394166 -43.752008)
		(width 0.14605)
		(layer "B.Cu")
		(net "PCIE_IOM_TO_COMP_9_DP")
	)
	(segment
		(start 184.4929 -94.467426)
		(end 184.672224 -94.586806)
		(width 0.14605)
		(layer "B.Cu")
		(net "PCIE_IOM_TO_COMP_9_DP")
	)
	(segment
		(start 185.830464 -94.355158)
		(end 186.260232 -94.269306)
		(width 0.14605)
		(layer "B.Cu")
		(net "PCIE_IOM_TO_COMP_9_DP")
	)
	(segment
		(start 185.221372 -94.32163)
		(end 185.65114 -94.235778)
		(width 0.14605)
		(layer "B.Cu")
		(net "PCIE_IOM_TO_COMP_9_DP")
	)
	(segment
		(start 172.762418 -92.523818)
		(end 183.486044 -94.668594)
		(width 0.14605)
		(layer "B.Cu")
		(net "PCIE_IOM_TO_COMP_9_DP")
	)
	(segment
		(start 146.268948 -33.124394)
		(end 146.3548 -33.554162)
		(width 0.14605)
		(layer "B.Cu")
		(net "PCIE_IOM_TO_COMP_9_DP")
	)
	(segment
		(start 187.537852 -93.858334)
		(end 187.96762 -93.772482)
		(width 0.14605)
		(layer "B.Cu")
		(net "PCIE_IOM_TO_COMP_9_DP")
	)
	(segment
		(start 146.500596 -34.282634)
		(end 146.586448 -34.712148)
		(width 0.14605)
		(layer "B.Cu")
		(net "PCIE_IOM_TO_COMP_9_DP")
	)
	(segment
		(start 146.321272 -34.163)
		(end 146.500596 -34.282634)
		(width 0.14605)
		(layer "B.Cu")
		(net "PCIE_IOM_TO_COMP_9_DP")
	)
	(segment
		(start 186.260232 -94.269306)
		(end 186.379612 -94.089982)
		(width 0.14605)
		(layer "B.Cu")
		(net "PCIE_IOM_TO_COMP_9_DP")
	)
	(segment
		(start 139.786868 -29.148786)
		(end 142.895574 -29.148786)
		(width 0.14605)
		(layer "B.Cu")
		(net "PCIE_IOM_TO_COMP_9_DP")
	)
	(segment
		(start 169.977562 -90.67419)
		(end 172.762418 -92.523818)
		(width 0.14605)
		(layer "B.Cu")
		(net "PCIE_IOM_TO_COMP_9_DP")
	)
	(segment
		(start 148.539708 -44.48048)
		(end 148.62556 -44.910248)
		(width 0.14605)
		(layer "B.Cu")
		(net "PCIE_IOM_TO_COMP_9_DP")
	)
	(segment
		(start 150.902416 -77.414374)
		(end 151.654256 -78.504796)
		(width 0.14605)
		(layer "B.Cu")
		(net "PCIE_IOM_TO_COMP_9_DP")
	)
	(segment
		(start 183.486044 -94.668594)
		(end 184.4929 -94.467426)
		(width 0.14605)
		(layer "B.Cu")
		(net "PCIE_IOM_TO_COMP_9_DP")
	)
	(segment
		(start 146.963638 -36.59886)
		(end 147.049744 -37.028628)
		(width 0.14605)
		(layer "B.Cu")
		(net "PCIE_IOM_TO_COMP_9_DP")
	)
	(segment
		(start 148.128736 -43.20286)
		(end 148.30806 -43.32224)
		(width 0.14605)
		(layer "B.Cu")
		(net "PCIE_IOM_TO_COMP_9_DP")
	)
	(segment
		(start 148.592032 -45.519086)
		(end 148.771356 -45.63872)
		(width 0.14605)
		(layer "B.Cu")
		(net "PCIE_IOM_TO_COMP_9_DP")
	)
	(segment
		(start 148.429218 -67.727068)
		(end 150.149052 -76.32192)
		(width 0.14605)
		(layer "B.Cu")
		(net "PCIE_IOM_TO_COMP_9_DP")
	)
	(segment
		(start 146.818096 -35.870388)
		(end 146.698462 -36.049712)
		(width 0.14605)
		(layer "B.Cu")
		(net "PCIE_IOM_TO_COMP_9_DP")
	)
	(segment
		(start 150.149052 -76.32192)
		(end 150.543768 -76.89469)
		(width 0.14605)
		(layer "B.Cu")
		(net "PCIE_IOM_TO_COMP_9_DP")
	)
	(segment
		(start 150.543768 -76.89469)
		(end 150.902416 -77.414374)
		(width 0.14605)
		(layer "B.Cu")
		(net "PCIE_IOM_TO_COMP_9_DP")
	)
	(segment
		(start 146.710146 -59.13374)
		(end 148.429218 -67.727068)
		(width 0.14605)
		(layer "B.Cu")
		(net "PCIE_IOM_TO_COMP_9_DP")
	)
	(segment
		(start 146.698462 -36.049712)
		(end 146.784314 -36.479226)
		(width 0.14605)
		(layer "B.Cu")
		(net "PCIE_IOM_TO_COMP_9_DP")
	)
	(segment
		(start 187.418472 -94.037658)
		(end 187.537852 -93.858334)
		(width 0.14605)
		(layer "B.Cu")
		(net "PCIE_IOM_TO_COMP_9_DP")
	)
	(segment
		(start 188.576712 -93.80601)
		(end 188.696092 -93.626686)
		(width 0.14605)
		(layer "B.Cu")
		(net "PCIE_IOM_TO_COMP_9_DP")
	)
	(segment
		(start 161.77641 -85.227414)
		(end 169.977562 -90.67419)
		(width 0.14605)
		(layer "B.Cu")
		(net "PCIE_IOM_TO_COMP_9_DP")
	)
	(arc
		(start 139.433554 -37.27831)
		(mid 139.360369 -37.32721)
		(end 139.274042 -37.34435)
		(width 0.14605)
		(layer "B.Cu")
		(net "PCIE_IOM_TO_COMP_9_DP")
	)
	(arc
		(start 139.499848 -37.11829)
		(mid 139.482621 -37.204897)
		(end 139.433554 -37.27831)
		(width 0.14605)
		(layer "B.Cu")
		(net "PCIE_IOM_TO_COMP_9_DP")
	)
	(arc
		(start 139.04595 -37.34435)
		(mid 138.840482 -37.259242)
		(end 138.755374 -37.053774)
		(width 0.14605)
		(layer "B.Cu")
		(net "PCIE_IOM_TO_COMP_9_DP")
	)
	(segment
		(start 198.799958 -73.49998)
		(end 199.199754 -73.899776)
		(width 0.09525)
		(layer "F.Cu")
		(net "PCIE_IOM_TO_COMP_9_DN_C")
	)
	(via
		(at 199.199754 -73.899776)
		(size 0.4572)
		(drill 0.2032)
		(layers "F.Cu" "B.Cu")
		(net "PCIE_IOM_TO_COMP_9_DN_C")
	)
	(segment
		(start 198.974202 -76.673202)
		(end 199.493886 -77.19187)
		(width 0.09525)
		(layer "B.Cu")
		(net "PCIE_IOM_TO_COMP_9_DN_C")
	)
	(segment
		(start 199.493886 -77.281786)
		(end 199.51065 -77.29855)
		(width 0.09525)
		(layer "B.Cu")
		(net "PCIE_IOM_TO_COMP_9_DN_C")
	)
	(segment
		(start 198.9201 -76.6191)
		(end 198.974202 -76.673202)
		(width 0.09525)
		(layer "B.Cu")
		(net "PCIE_IOM_TO_COMP_9_DN_C")
	)
	(segment
		(start 198.7931 -74.30643)
		(end 198.7931 -74.867008)
		(width 0.09525)
		(layer "B.Cu")
		(net "PCIE_IOM_TO_COMP_9_DN_C")
	)
	(segment
		(start 199.927464 -77.715364)
		(end 199.927464 -80.746854)
		(width 0.14605)
		(layer "B.Cu")
		(net "PCIE_IOM_TO_COMP_9_DN_C")
	)
	(segment
		(start 198.9201 -74.994008)
		(end 198.9201 -76.6191)
		(width 0.09525)
		(layer "B.Cu")
		(net "PCIE_IOM_TO_COMP_9_DN_C")
	)
	(segment
		(start 199.199754 -73.899776)
		(end 198.7931 -74.30643)
		(width 0.09525)
		(layer "B.Cu")
		(net "PCIE_IOM_TO_COMP_9_DN_C")
	)
	(segment
		(start 199.493886 -77.19187)
		(end 199.493886 -77.281786)
		(width 0.09525)
		(layer "B.Cu")
		(net "PCIE_IOM_TO_COMP_9_DN_C")
	)
	(segment
		(start 198.7931 -74.867008)
		(end 198.9201 -74.994008)
		(width 0.09525)
		(layer "B.Cu")
		(net "PCIE_IOM_TO_COMP_9_DN_C")
	)
	(segment
		(start 199.51065 -77.29855)
		(end 199.927464 -77.715364)
		(width 0.14605)
		(layer "B.Cu")
		(net "PCIE_IOM_TO_COMP_9_DN_C")
	)
	(segment
		(start 199.927464 -80.746854)
		(end 199.800718 -80.8736)
		(width 0.14605)
		(layer "B.Cu")
		(net "PCIE_IOM_TO_COMP_9_DN_C")
	)
	(segment
		(start 144.425416 -29.795216)
		(end 142.990062 -28.837636)
		(width 0.14605)
		(layer "B.Cu")
		(net "PCIE_IOM_TO_COMP_9_DN")
	)
	(segment
		(start 138.444224 -30.051248)
		(end 138.444224 -37.053774)
		(width 0.14605)
		(layer "B.Cu")
		(net "PCIE_IOM_TO_COMP_9_DN")
	)
	(segment
		(start 146.562064 -33.002982)
		(end 144.425416 -29.795216)
		(width 0.14605)
		(layer "B.Cu")
		(net "PCIE_IOM_TO_COMP_9_DN")
	)
	(segment
		(start 151.158956 -77.238098)
		(end 151.158702 -77.237844)
		(width 0.14605)
		(layer "B.Cu")
		(net "PCIE_IOM_TO_COMP_9_DN")
	)
	(segment
		(start 142.990062 -28.837636)
		(end 139.657836 -28.837636)
		(width 0.14605)
		(layer "B.Cu")
		(net "PCIE_IOM_TO_COMP_9_DN")
	)
	(segment
		(start 149.406356 -47.226474)
		(end 146.562064 -33.002982)
		(width 0.14605)
		(layer "B.Cu")
		(net "PCIE_IOM_TO_COMP_9_DN")
	)
	(segment
		(start 199.932798 -81.56448)
		(end 199.932798 -84.107274)
		(width 0.14605)
		(layer "B.Cu")
		(net "PCIE_IOM_TO_COMP_9_DN")
	)
	(segment
		(start 178.184556 -93.290644)
		(end 172.883576 -92.230702)
		(width 0.14605)
		(layer "B.Cu")
		(net "PCIE_IOM_TO_COMP_9_DN")
	)
	(segment
		(start 150.44166 -76.197968)
		(end 147.027646 -59.13374)
		(width 0.14605)
		(layer "B.Cu")
		(net "PCIE_IOM_TO_COMP_9_DN")
	)
	(segment
		(start 139.04595 -37.6555)
		(end 139.328398 -37.6555)
		(width 0.14605)
		(layer "B.Cu")
		(net "PCIE_IOM_TO_COMP_9_DN")
	)
	(segment
		(start 151.876506 -78.278482)
		(end 151.158956 -77.238098)
		(width 0.14605)
		(layer "B.Cu")
		(net "PCIE_IOM_TO_COMP_9_DN")
	)
	(segment
		(start 139.657836 -28.837636)
		(end 138.444224 -30.051248)
		(width 0.14605)
		(layer "B.Cu")
		(net "PCIE_IOM_TO_COMP_9_DN")
	)
	(segment
		(start 172.883576 -92.230702)
		(end 166.048944 -87.691214)
		(width 0.14605)
		(layer "B.Cu")
		(net "PCIE_IOM_TO_COMP_9_DN")
	)
	(segment
		(start 183.486044 -94.35084)
		(end 178.184556 -93.290644)
		(width 0.14605)
		(layer "B.Cu")
		(net "PCIE_IOM_TO_COMP_9_DN")
	)
	(segment
		(start 183.486044 -94.351094)
		(end 183.486044 -94.35084)
		(width 0.14605)
		(layer "B.Cu")
		(net "PCIE_IOM_TO_COMP_9_DN")
	)
	(segment
		(start 147.027646 -59.13374)
		(end 149.406356 -47.226474)
		(width 0.14605)
		(layer "B.Cu")
		(net "PCIE_IOM_TO_COMP_9_DN")
	)
	(segment
		(start 199.932798 -84.107274)
		(end 194.367658 -89.672414)
		(width 0.14605)
		(layer "B.Cu")
		(net "PCIE_IOM_TO_COMP_9_DN")
	)
	(segment
		(start 166.048944 -87.691214)
		(end 161.948622 -84.96808)
		(width 0.14605)
		(layer "B.Cu")
		(net "PCIE_IOM_TO_COMP_9_DN")
	)
	(segment
		(start 194.367658 -89.672414)
		(end 189.004448 -93.247718)
		(width 0.14605)
		(layer "B.Cu")
		(net "PCIE_IOM_TO_COMP_9_DN")
	)
	(segment
		(start 161.948622 -84.96808)
		(end 151.876506 -78.278482)
		(width 0.14605)
		(layer "B.Cu")
		(net "PCIE_IOM_TO_COMP_9_DN")
	)
	(segment
		(start 139.499848 -37.826696)
		(end 139.499848 -38.200076)
		(width 0.14605)
		(layer "B.Cu")
		(net "PCIE_IOM_TO_COMP_9_DN")
	)
	(segment
		(start 189.004448 -93.247718)
		(end 183.486044 -94.351094)
		(width 0.14605)
		(layer "B.Cu")
		(net "PCIE_IOM_TO_COMP_9_DN")
	)
	(segment
		(start 199.800718 -81.4324)
		(end 199.932798 -81.56448)
		(width 0.136652)
		(layer "B.Cu")
		(net "PCIE_IOM_TO_COMP_9_DN")
	)
	(segment
		(start 151.158702 -77.237844)
		(end 150.44166 -76.197968)
		(width 0.14605)
		(layer "B.Cu")
		(net "PCIE_IOM_TO_COMP_9_DN")
	)
	(arc
		(start 138.444224 -37.053774)
		(mid 138.620465 -37.479259)
		(end 139.04595 -37.6555)
		(width 0.14605)
		(layer "B.Cu")
		(net "PCIE_IOM_TO_COMP_9_DN")
	)
	(arc
		(start 139.44981 -37.705792)
		(mid 139.486821 -37.761277)
		(end 139.499848 -37.826696)
		(width 0.14605)
		(layer "B.Cu")
		(net "PCIE_IOM_TO_COMP_9_DN")
	)
	(arc
		(start 139.328398 -37.6555)
		(mid 139.394106 -37.66857)
		(end 139.44981 -37.705792)
		(width 0.14605)
		(layer "B.Cu")
		(net "PCIE_IOM_TO_COMP_9_DN")
	)
	(segment
		(start 199.600058 -74.299826)
		(end 199.606662 -74.299826)
		(width 0.09525)
		(layer "F.Cu")
		(net "PCIE_IOM_TO_COMP_8_DP_C")
	)
	(segment
		(start 199.606662 -74.299826)
		(end 200.001632 -74.694796)
		(width 0.09525)
		(layer "F.Cu")
		(net "PCIE_IOM_TO_COMP_8_DP_C")
	)
	(via
		(at 200.001632 -74.694796)
		(size 0.4572)
		(drill 0.2032)
		(layers "F.Cu" "B.Cu")
		(net "PCIE_IOM_TO_COMP_8_DP_C")
	)
	(segment
		(start 199.855328 -75.011026)
		(end 200.001632 -74.694796)
		(width 0.09525)
		(layer "B.Cu")
		(net "PCIE_IOM_TO_COMP_8_DP_C")
	)
	(segment
		(start 201.508614 -77.776832)
		(end 200.245218 -76.513436)
		(width 0.14605)
		(layer "B.Cu")
		(net "PCIE_IOM_TO_COMP_8_DP_C")
	)
	(segment
		(start 200.245218 -76.513436)
		(end 200.228454 -76.496672)
		(width 0.09525)
		(layer "B.Cu")
		(net "PCIE_IOM_TO_COMP_8_DP_C")
	)
	(segment
		(start 201.629518 -80.8736)
		(end 201.508614 -80.752696)
		(width 0.14605)
		(layer "B.Cu")
		(net "PCIE_IOM_TO_COMP_8_DP_C")
	)
	(segment
		(start 200.228454 -76.496672)
		(end 200.138792 -76.496672)
		(width 0.09525)
		(layer "B.Cu")
		(net "PCIE_IOM_TO_COMP_8_DP_C")
	)
	(segment
		(start 201.508614 -80.752696)
		(end 201.508614 -77.776832)
		(width 0.14605)
		(layer "B.Cu")
		(net "PCIE_IOM_TO_COMP_8_DP_C")
	)
	(segment
		(start 199.576182 -75.290172)
		(end 199.855328 -75.011026)
		(width 0.09525)
		(layer "B.Cu")
		(net "PCIE_IOM_TO_COMP_8_DP_C")
	)
	(segment
		(start 199.576182 -75.934062)
		(end 199.576182 -75.290172)
		(width 0.09525)
		(layer "B.Cu")
		(net "PCIE_IOM_TO_COMP_8_DP_C")
	)
	(segment
		(start 200.138792 -76.496672)
		(end 199.576182 -75.934062)
		(width 0.09525)
		(layer "B.Cu")
		(net "PCIE_IOM_TO_COMP_8_DP_C")
	)
	(segment
		(start 141.299946 -35.600132)
		(end 141.299946 -35.918394)
		(width 0.14605)
		(layer "B.Cu")
		(net "PCIE_IOM_TO_COMP_8_DP")
	)
	(segment
		(start 149.087078 -76.92009)
		(end 151.09063 -79.746348)
		(width 0.14605)
		(layer "B.Cu")
		(net "PCIE_IOM_TO_COMP_8_DP")
	)
	(segment
		(start 146.711416 -42.027348)
		(end 146.591782 -42.206672)
		(width 0.14605)
		(layer "B.Cu")
		(net "PCIE_IOM_TO_COMP_8_DP")
	)
	(segment
		(start 201.500486 -81.561178)
		(end 201.629518 -81.4324)
		(width 0.14605)
		(layer "B.Cu")
		(net "PCIE_IOM_TO_COMP_8_DP")
	)
	(segment
		(start 147.371562 -46.11116)
		(end 147.550886 -46.23054)
		(width 0.14605)
		(layer "B.Cu")
		(net "PCIE_IOM_TO_COMP_8_DP")
	)
	(segment
		(start 201.500486 -84.630768)
		(end 201.500486 -81.561178)
		(width 0.14605)
		(layer "B.Cu")
		(net "PCIE_IOM_TO_COMP_8_DP")
	)
	(segment
		(start 195.38188 -90.749628)
		(end 201.500486 -84.630768)
		(width 0.14605)
		(layer "B.Cu")
		(net "PCIE_IOM_TO_COMP_8_DP")
	)
	(segment
		(start 147.569174 -69.341492)
		(end 149.087078 -76.92009)
		(width 0.14605)
		(layer "B.Cu")
		(net "PCIE_IOM_TO_COMP_8_DP")
	)
	(segment
		(start 145.782792 -37.37737)
		(end 145.663158 -37.556694)
		(width 0.14605)
		(layer "B.Cu")
		(net "PCIE_IOM_TO_COMP_8_DP")
	)
	(segment
		(start 145.431764 -36.398454)
		(end 145.517616 -36.828222)
		(width 0.14605)
		(layer "B.Cu")
		(net "PCIE_IOM_TO_COMP_8_DP")
	)
	(segment
		(start 191.283844 -93.664532)
		(end 191.648334 -93.421454)
		(width 0.14605)
		(layer "B.Cu")
		(net "PCIE_IOM_TO_COMP_8_DP")
	)
	(segment
		(start 151.09063 -79.746348)
		(end 172.468286 -93.712538)
		(width 0.14605)
		(layer "B.Cu")
		(net "PCIE_IOM_TO_COMP_8_DP")
	)
	(segment
		(start 147.636738 -46.660308)
		(end 145.534634 -59.179968)
		(width 0.14605)
		(layer "B.Cu")
		(net "PCIE_IOM_TO_COMP_8_DP")
	)
	(segment
		(start 186.470036 -95.446342)
		(end 189.137544 -94.91218)
		(width 0.14605)
		(layer "B.Cu")
		(net "PCIE_IOM_TO_COMP_8_DP")
	)
	(segment
		(start 140.555472 -35.853878)
		(end 140.555472 -30.57144)
		(width 0.14605)
		(layer "B.Cu")
		(net "PCIE_IOM_TO_COMP_8_DP")
	)
	(segment
		(start 147.05457 -44.523152)
		(end 147.140422 -44.95292)
		(width 0.14605)
		(layer "B.Cu")
		(net "PCIE_IOM_TO_COMP_8_DP")
	)
	(segment
		(start 183.80202 -95.979742)
		(end 186.470036 -95.446342)
		(width 0.14605)
		(layer "B.Cu")
		(net "PCIE_IOM_TO_COMP_8_DP")
	)
	(segment
		(start 147.405344 -45.502068)
		(end 147.28571 -45.681392)
		(width 0.14605)
		(layer "B.Cu")
		(net "PCIE_IOM_TO_COMP_8_DP")
	)
	(segment
		(start 145.663158 -37.556694)
		(end 145.74901 -37.986462)
		(width 0.14605)
		(layer "B.Cu")
		(net "PCIE_IOM_TO_COMP_8_DP")
	)
	(segment
		(start 142.40764 -30.291786)
		(end 143.274034 -30.876494)
		(width 0.14605)
		(layer "B.Cu")
		(net "PCIE_IOM_TO_COMP_8_DP")
	)
	(segment
		(start 147.088352 -43.91406)
		(end 147.174204 -44.343828)
		(width 0.14605)
		(layer "B.Cu")
		(net "PCIE_IOM_TO_COMP_8_DP")
	)
	(segment
		(start 147.319492 -45.0723)
		(end 147.405344 -45.502068)
		(width 0.14605)
		(layer "B.Cu")
		(net "PCIE_IOM_TO_COMP_8_DP")
	)
	(segment
		(start 146.430492 -63.656464)
		(end 146.430746 -63.656464)
		(width 0.14605)
		(layer "B.Cu")
		(net "PCIE_IOM_TO_COMP_8_DP")
	)
	(segment
		(start 145.200624 -35.240214)
		(end 145.286222 -35.669982)
		(width 0.14605)
		(layer "B.Cu")
		(net "PCIE_IOM_TO_COMP_8_DP")
	)
	(segment
		(start 144.96923 -34.081974)
		(end 145.055082 -34.511742)
		(width 0.14605)
		(layer "B.Cu")
		(net "PCIE_IOM_TO_COMP_8_DP")
	)
	(segment
		(start 140.835126 -30.291786)
		(end 142.40764 -30.291786)
		(width 0.14605)
		(layer "B.Cu")
		(net "PCIE_IOM_TO_COMP_8_DP")
	)
	(segment
		(start 145.74901 -37.986462)
		(end 145.928334 -38.106096)
		(width 0.14605)
		(layer "B.Cu")
		(net "PCIE_IOM_TO_COMP_8_DP")
	)
	(segment
		(start 190.301118 -94.319852)
		(end 190.665608 -94.076774)
		(width 0.14605)
		(layer "B.Cu")
		(net "PCIE_IOM_TO_COMP_8_DP")
	)
	(segment
		(start 145.465546 -35.789616)
		(end 145.551398 -36.219384)
		(width 0.14605)
		(layer "B.Cu")
		(net "PCIE_IOM_TO_COMP_8_DP")
	)
	(segment
		(start 147.174204 -44.343828)
		(end 147.05457 -44.523152)
		(width 0.14605)
		(layer "B.Cu")
		(net "PCIE_IOM_TO_COMP_8_DP")
	)
	(segment
		(start 146.677634 -42.63644)
		(end 146.856958 -42.756074)
		(width 0.14605)
		(layer "B.Cu")
		(net "PCIE_IOM_TO_COMP_8_DP")
	)
	(segment
		(start 191.690752 -93.210126)
		(end 192.055242 -92.967302)
		(width 0.14605)
		(layer "B.Cu")
		(net "PCIE_IOM_TO_COMP_8_DP")
	)
	(segment
		(start 147.550886 -46.23054)
		(end 147.636738 -46.660308)
		(width 0.14605)
		(layer "B.Cu")
		(net "PCIE_IOM_TO_COMP_8_DP")
	)
	(segment
		(start 145.534634 -59.179968)
		(end 146.304254 -63.024766)
		(width 0.14605)
		(layer "B.Cu")
		(net "PCIE_IOM_TO_COMP_8_DP")
	)
	(segment
		(start 190.08979 -94.277434)
		(end 190.301118 -94.319852)
		(width 0.14605)
		(layer "B.Cu")
		(net "PCIE_IOM_TO_COMP_8_DP")
	)
	(segment
		(start 172.468286 -93.712538)
		(end 172.468794 -93.712792)
		(width 0.14605)
		(layer "B.Cu")
		(net "PCIE_IOM_TO_COMP_8_DP")
	)
	(segment
		(start 145.088864 -33.902904)
		(end 144.96923 -34.081974)
		(width 0.14605)
		(layer "B.Cu")
		(net "PCIE_IOM_TO_COMP_8_DP")
	)
	(segment
		(start 192.26657 -93.009466)
		(end 192.63106 -92.766388)
		(width 0.14605)
		(layer "B.Cu")
		(net "PCIE_IOM_TO_COMP_8_DP")
	)
	(segment
		(start 147.140422 -44.95292)
		(end 147.319492 -45.0723)
		(width 0.14605)
		(layer "B.Cu")
		(net "PCIE_IOM_TO_COMP_8_DP")
	)
	(segment
		(start 172.468794 -93.712792)
		(end 183.80202 -95.979742)
		(width 0.14605)
		(layer "B.Cu")
		(net "PCIE_IOM_TO_COMP_8_DP")
	)
	(segment
		(start 146.591782 -42.206672)
		(end 146.677634 -42.63644)
		(width 0.14605)
		(layer "B.Cu")
		(net "PCIE_IOM_TO_COMP_8_DP")
	)
	(segment
		(start 145.055082 -34.511742)
		(end 145.234406 -34.631376)
		(width 0.14605)
		(layer "B.Cu")
		(net "PCIE_IOM_TO_COMP_8_DP")
	)
	(segment
		(start 146.367246 -63.340488)
		(end 146.430492 -63.656464)
		(width 0.14605)
		(layer "B.Cu")
		(net "PCIE_IOM_TO_COMP_8_DP")
	)
	(segment
		(start 145.551398 -36.219384)
		(end 145.431764 -36.398454)
		(width 0.14605)
		(layer "B.Cu")
		(net "PCIE_IOM_TO_COMP_8_DP")
	)
	(segment
		(start 191.072516 -93.622368)
		(end 191.283844 -93.664532)
		(width 0.14605)
		(layer "B.Cu")
		(net "PCIE_IOM_TO_COMP_8_DP")
	)
	(segment
		(start 145.928334 -38.106096)
		(end 146.711416 -42.027348)
		(width 0.14605)
		(layer "B.Cu")
		(net "PCIE_IOM_TO_COMP_8_DP")
	)
	(segment
		(start 146.94281 -43.185588)
		(end 146.823176 -43.364912)
		(width 0.14605)
		(layer "B.Cu")
		(net "PCIE_IOM_TO_COMP_8_DP")
	)
	(segment
		(start 189.137544 -94.91218)
		(end 190.08979 -94.277434)
		(width 0.14605)
		(layer "B.Cu")
		(net "PCIE_IOM_TO_COMP_8_DP")
	)
	(segment
		(start 190.708026 -93.865446)
		(end 191.072516 -93.622368)
		(width 0.14605)
		(layer "B.Cu")
		(net "PCIE_IOM_TO_COMP_8_DP")
	)
	(segment
		(start 145.517616 -36.828222)
		(end 145.69694 -36.947856)
		(width 0.14605)
		(layer "B.Cu")
		(net "PCIE_IOM_TO_COMP_8_DP")
	)
	(segment
		(start 145.320258 -35.061144)
		(end 145.200624 -35.240214)
		(width 0.14605)
		(layer "B.Cu")
		(net "PCIE_IOM_TO_COMP_8_DP")
	)
	(segment
		(start 145.003012 -33.473136)
		(end 145.088864 -33.902904)
		(width 0.14605)
		(layer "B.Cu")
		(net "PCIE_IOM_TO_COMP_8_DP")
	)
	(segment
		(start 192.63106 -92.766388)
		(end 192.673478 -92.55506)
		(width 0.14605)
		(layer "B.Cu")
		(net "PCIE_IOM_TO_COMP_8_DP")
	)
	(segment
		(start 190.665608 -94.076774)
		(end 190.708026 -93.865446)
		(width 0.14605)
		(layer "B.Cu")
		(net "PCIE_IOM_TO_COMP_8_DP")
	)
	(segment
		(start 146.304254 -63.024766)
		(end 146.367246 -63.340488)
		(width 0.14605)
		(layer "B.Cu")
		(net "PCIE_IOM_TO_COMP_8_DP")
	)
	(segment
		(start 145.234406 -34.631376)
		(end 145.320258 -35.061144)
		(width 0.14605)
		(layer "B.Cu")
		(net "PCIE_IOM_TO_COMP_8_DP")
	)
	(segment
		(start 146.823176 -43.364912)
		(end 146.909028 -43.79468)
		(width 0.14605)
		(layer "B.Cu")
		(net "PCIE_IOM_TO_COMP_8_DP")
	)
	(segment
		(start 191.648334 -93.421454)
		(end 191.690752 -93.210126)
		(width 0.14605)
		(layer "B.Cu")
		(net "PCIE_IOM_TO_COMP_8_DP")
	)
	(segment
		(start 146.856958 -42.756074)
		(end 146.94281 -43.185588)
		(width 0.14605)
		(layer "B.Cu")
		(net "PCIE_IOM_TO_COMP_8_DP")
	)
	(segment
		(start 192.673478 -92.55506)
		(end 195.38188 -90.749628)
		(width 0.14605)
		(layer "B.Cu")
		(net "PCIE_IOM_TO_COMP_8_DP")
	)
	(segment
		(start 140.555472 -30.57144)
		(end 140.835126 -30.291786)
		(width 0.14605)
		(layer "B.Cu")
		(net "PCIE_IOM_TO_COMP_8_DP")
	)
	(segment
		(start 192.055242 -92.967302)
		(end 192.26657 -93.009466)
		(width 0.14605)
		(layer "B.Cu")
		(net "PCIE_IOM_TO_COMP_8_DP")
	)
	(segment
		(start 141.07414 -36.144454)
		(end 140.846048 -36.144454)
		(width 0.14605)
		(layer "B.Cu")
		(net "PCIE_IOM_TO_COMP_8_DP")
	)
	(segment
		(start 143.274034 -30.876494)
		(end 145.002758 -33.473136)
		(width 0.14605)
		(layer "B.Cu")
		(net "PCIE_IOM_TO_COMP_8_DP")
	)
	(segment
		(start 145.69694 -36.947856)
		(end 145.782792 -37.37737)
		(width 0.14605)
		(layer "B.Cu")
		(net "PCIE_IOM_TO_COMP_8_DP")
	)
	(segment
		(start 145.286222 -35.669982)
		(end 145.465546 -35.789616)
		(width 0.14605)
		(layer "B.Cu")
		(net "PCIE_IOM_TO_COMP_8_DP")
	)
	(segment
		(start 146.430746 -63.656464)
		(end 147.569174 -69.341492)
		(width 0.14605)
		(layer "B.Cu")
		(net "PCIE_IOM_TO_COMP_8_DP")
	)
	(segment
		(start 146.909028 -43.79468)
		(end 147.088352 -43.91406)
		(width 0.14605)
		(layer "B.Cu")
		(net "PCIE_IOM_TO_COMP_8_DP")
	)
	(segment
		(start 145.002758 -33.473136)
		(end 145.003012 -33.473136)
		(width 0.14605)
		(layer "B.Cu")
		(net "PCIE_IOM_TO_COMP_8_DP")
	)
	(segment
		(start 147.28571 -45.681392)
		(end 147.371562 -46.11116)
		(width 0.14605)
		(layer "B.Cu")
		(net "PCIE_IOM_TO_COMP_8_DP")
	)
	(arc
		(start 141.299946 -35.918394)
		(mid 141.282719 -36.005001)
		(end 141.233652 -36.078414)
		(width 0.14605)
		(layer "B.Cu")
		(net "PCIE_IOM_TO_COMP_8_DP")
	)
	(arc
		(start 141.233652 -36.078414)
		(mid 141.160467 -36.127314)
		(end 141.07414 -36.144454)
		(width 0.14605)
		(layer "B.Cu")
		(net "PCIE_IOM_TO_COMP_8_DP")
	)
	(arc
		(start 140.846048 -36.144454)
		(mid 140.64058 -36.059346)
		(end 140.555472 -35.853878)
		(width 0.14605)
		(layer "B.Cu")
		(net "PCIE_IOM_TO_COMP_8_DP")
	)
	(segment
		(start 199.600058 -73.49998)
		(end 199.999854 -73.899776)
		(width 0.09525)
		(layer "F.Cu")
		(net "PCIE_IOM_TO_COMP_8_DN_C")
	)
	(via
		(at 199.999854 -73.899776)
		(size 0.4572)
		(drill 0.2032)
		(layers "F.Cu" "B.Cu")
		(net "PCIE_IOM_TO_COMP_8_DN_C")
	)
	(segment
		(start 201.070718 -80.8736)
		(end 201.197464 -80.746854)
		(width 0.14605)
		(layer "B.Cu")
		(net "PCIE_IOM_TO_COMP_8_DN_C")
	)
	(segment
		(start 201.197464 -77.905864)
		(end 200.025 -76.7334)
		(width 0.14605)
		(layer "B.Cu")
		(net "PCIE_IOM_TO_COMP_8_DN_C")
	)
	(segment
		(start 199.392032 -76.010516)
		(end 199.392032 -75.213718)
		(width 0.09525)
		(layer "B.Cu")
		(net "PCIE_IOM_TO_COMP_8_DN_C")
	)
	(segment
		(start 199.392032 -75.213718)
		(end 199.6059 -74.99985)
		(width 0.09525)
		(layer "B.Cu")
		(net "PCIE_IOM_TO_COMP_8_DN_C")
	)
	(segment
		(start 199.6059 -74.99985)
		(end 199.6059 -74.29373)
		(width 0.09525)
		(layer "B.Cu")
		(net "PCIE_IOM_TO_COMP_8_DN_C")
	)
	(segment
		(start 200.008236 -76.716636)
		(end 200.008236 -76.62672)
		(width 0.09525)
		(layer "B.Cu")
		(net "PCIE_IOM_TO_COMP_8_DN_C")
	)
	(segment
		(start 201.197464 -80.746854)
		(end 201.197464 -77.905864)
		(width 0.14605)
		(layer "B.Cu")
		(net "PCIE_IOM_TO_COMP_8_DN_C")
	)
	(segment
		(start 199.6059 -74.29373)
		(end 199.999854 -73.899776)
		(width 0.09525)
		(layer "B.Cu")
		(net "PCIE_IOM_TO_COMP_8_DN_C")
	)
	(segment
		(start 200.008236 -76.62672)
		(end 199.392032 -76.010516)
		(width 0.09525)
		(layer "B.Cu")
		(net "PCIE_IOM_TO_COMP_8_DN_C")
	)
	(segment
		(start 200.025 -76.7334)
		(end 200.008236 -76.716636)
		(width 0.09525)
		(layer "B.Cu")
		(net "PCIE_IOM_TO_COMP_8_DN_C")
	)
	(segment
		(start 140.244322 -35.853878)
		(end 140.244322 -30.442408)
		(width 0.14605)
		(layer "B.Cu")
		(net "PCIE_IOM_TO_COMP_8_DN")
	)
	(segment
		(start 147.874482 -69.27977)
		(end 149.379178 -76.794106)
		(width 0.14605)
		(layer "B.Cu")
		(net "PCIE_IOM_TO_COMP_8_DN")
	)
	(segment
		(start 195.183506 -90.507566)
		(end 201.189336 -84.501736)
		(width 0.14605)
		(layer "B.Cu")
		(net "PCIE_IOM_TO_COMP_8_DN")
	)
	(segment
		(start 201.189336 -84.501736)
		(end 201.189336 -81.551018)
		(width 0.14605)
		(layer "B.Cu")
		(net "PCIE_IOM_TO_COMP_8_DN")
	)
	(segment
		(start 151.31034 -79.518002)
		(end 172.588174 -93.419168)
		(width 0.14605)
		(layer "B.Cu")
		(net "PCIE_IOM_TO_COMP_8_DN")
	)
	(segment
		(start 147.953476 -46.654974)
		(end 145.851118 -59.175142)
		(width 0.14605)
		(layer "B.Cu")
		(net "PCIE_IOM_TO_COMP_8_DN")
	)
	(segment
		(start 149.379178 -76.794106)
		(end 151.31034 -79.518002)
		(width 0.14605)
		(layer "B.Cu")
		(net "PCIE_IOM_TO_COMP_8_DN")
	)
	(segment
		(start 145.296128 -33.351724)
		(end 147.953476 -46.654974)
		(width 0.14605)
		(layer "B.Cu")
		(net "PCIE_IOM_TO_COMP_8_DN")
	)
	(segment
		(start 183.80202 -95.662242)
		(end 189.016132 -94.619064)
		(width 0.14605)
		(layer "B.Cu")
		(net "PCIE_IOM_TO_COMP_8_DN")
	)
	(segment
		(start 201.189336 -81.551018)
		(end 201.070718 -81.4324)
		(width 0.14605)
		(layer "B.Cu")
		(net "PCIE_IOM_TO_COMP_8_DN")
	)
	(segment
		(start 146.862546 -64.227202)
		(end 147.874482 -69.27977)
		(width 0.14605)
		(layer "B.Cu")
		(net "PCIE_IOM_TO_COMP_8_DN")
	)
	(segment
		(start 146.862546 -64.226948)
		(end 146.862546 -64.227202)
		(width 0.14605)
		(layer "B.Cu")
		(net "PCIE_IOM_TO_COMP_8_DN")
	)
	(segment
		(start 142.50289 -29.980636)
		(end 143.499078 -30.652974)
		(width 0.14605)
		(layer "B.Cu")
		(net "PCIE_IOM_TO_COMP_8_DN")
	)
	(segment
		(start 141.128496 -36.455604)
		(end 140.846048 -36.455604)
		(width 0.14605)
		(layer "B.Cu")
		(net "PCIE_IOM_TO_COMP_8_DN")
	)
	(segment
		(start 146.609562 -62.963806)
		(end 146.862546 -64.226948)
		(width 0.14605)
		(layer "B.Cu")
		(net "PCIE_IOM_TO_COMP_8_DN")
	)
	(segment
		(start 145.851118 -59.175142)
		(end 146.609562 -62.963806)
		(width 0.14605)
		(layer "B.Cu")
		(net "PCIE_IOM_TO_COMP_8_DN")
	)
	(segment
		(start 189.016132 -94.619064)
		(end 195.183506 -90.507566)
		(width 0.14605)
		(layer "B.Cu")
		(net "PCIE_IOM_TO_COMP_8_DN")
	)
	(segment
		(start 143.499078 -30.652974)
		(end 145.296128 -33.351724)
		(width 0.14605)
		(layer "B.Cu")
		(net "PCIE_IOM_TO_COMP_8_DN")
	)
	(segment
		(start 141.299946 -37.00018)
		(end 141.299946 -36.6268)
		(width 0.14605)
		(layer "B.Cu")
		(net "PCIE_IOM_TO_COMP_8_DN")
	)
	(segment
		(start 172.588174 -93.419168)
		(end 183.80202 -95.662242)
		(width 0.14605)
		(layer "B.Cu")
		(net "PCIE_IOM_TO_COMP_8_DN")
	)
	(segment
		(start 140.706094 -29.980636)
		(end 142.50289 -29.980636)
		(width 0.14605)
		(layer "B.Cu")
		(net "PCIE_IOM_TO_COMP_8_DN")
	)
	(segment
		(start 140.244322 -30.442408)
		(end 140.706094 -29.980636)
		(width 0.14605)
		(layer "B.Cu")
		(net "PCIE_IOM_TO_COMP_8_DN")
	)
	(arc
		(start 140.846048 -36.455604)
		(mid 140.420563 -36.279363)
		(end 140.244322 -35.853878)
		(width 0.14605)
		(layer "B.Cu")
		(net "PCIE_IOM_TO_COMP_8_DN")
	)
	(arc
		(start 141.249908 -36.505896)
		(mid 141.194204 -36.468676)
		(end 141.128496 -36.455604)
		(width 0.14605)
		(layer "B.Cu")
		(net "PCIE_IOM_TO_COMP_8_DN")
	)
	(arc
		(start 141.299946 -36.6268)
		(mid 141.286949 -36.561369)
		(end 141.249908 -36.505896)
		(width 0.14605)
		(layer "B.Cu")
		(net "PCIE_IOM_TO_COMP_8_DN")
	)
	(segment
		(start 79.925164 -94.549976)
		(end 81.111598 -94.549976)
		(width 0.14605)
		(layer "F.Cu")
		(net "PCIE_IOM_TO_COMP_23_DP")
	)
	(segment
		(start 81.355946 -94.794324)
		(end 83.056476 -94.794324)
		(width 0.14605)
		(layer "F.Cu")
		(net "PCIE_IOM_TO_COMP_23_DP")
	)
	(segment
		(start 81.111598 -94.549976)
		(end 81.355946 -94.794324)
		(width 0.14605)
		(layer "F.Cu")
		(net "PCIE_IOM_TO_COMP_23_DP")
	)
	(arc
		(start 83.056476 -94.794324)
		(mid 83.269847 -94.705943)
		(end 83.358228 -94.492572)
		(width 0.14605)
		(layer "F.Cu")
		(net "PCIE_IOM_TO_COMP_23_DP")
	)
	(segment
		(start 83.358228 -94.492572)
		(end 83.358228 -94.535498)
		(width 0.1397)
		(layer "In5.Cu")
		(net "PCIE_IOM_TO_COMP_23_DP")
	)
	(segment
		(start 83.599528 -94.776798)
		(end 85.319362 -94.776798)
		(width 0.1397)
		(layer "In5.Cu")
		(net "PCIE_IOM_TO_COMP_23_DP")
	)
	(segment
		(start 104.238552 -37.334952)
		(end 106.8959 -37.334952)
		(width 0.1397)
		(layer "In5.Cu")
		(net "PCIE_IOM_TO_COMP_23_DP")
	)
	(segment
		(start 107.099862 -37.13099)
		(end 107.099862 -36.800028)
		(width 0.1397)
		(layer "In5.Cu")
		(net "PCIE_IOM_TO_COMP_23_DP")
	)
	(segment
		(start 99.99472 -36.642294)
		(end 100.091494 -36.54552)
		(width 0.1397)
		(layer "In5.Cu")
		(net "PCIE_IOM_TO_COMP_23_DP")
	)
	(segment
		(start 103.44912 -36.54552)
		(end 104.238552 -37.334952)
		(width 0.1397)
		(layer "In5.Cu")
		(net "PCIE_IOM_TO_COMP_23_DP")
	)
	(segment
		(start 96.15424 -46.95952)
		(end 97.679764 -39.325296)
		(width 0.1397)
		(layer "In5.Cu")
		(net "PCIE_IOM_TO_COMP_23_DP")
	)
	(segment
		(start 98.418904 -38.217856)
		(end 99.99472 -36.64204)
		(width 0.1397)
		(layer "In5.Cu")
		(net "PCIE_IOM_TO_COMP_23_DP")
	)
	(segment
		(start 92.217748 -85.22335)
		(end 98.01225 -56.251094)
		(width 0.1397)
		(layer "In5.Cu")
		(net "PCIE_IOM_TO_COMP_23_DP")
	)
	(segment
		(start 98.01225 -56.251094)
		(end 96.15424 -46.959774)
		(width 0.1397)
		(layer "In5.Cu")
		(net "PCIE_IOM_TO_COMP_23_DP")
	)
	(segment
		(start 96.15424 -46.959774)
		(end 96.15424 -46.95952)
		(width 0.1397)
		(layer "In5.Cu")
		(net "PCIE_IOM_TO_COMP_23_DP")
	)
	(segment
		(start 97.679764 -39.325296)
		(end 98.418904 -38.217856)
		(width 0.1397)
		(layer "In5.Cu")
		(net "PCIE_IOM_TO_COMP_23_DP")
	)
	(segment
		(start 99.99472 -36.64204)
		(end 99.99472 -36.642294)
		(width 0.1397)
		(layer "In5.Cu")
		(net "PCIE_IOM_TO_COMP_23_DP")
	)
	(segment
		(start 100.091494 -36.54552)
		(end 103.44912 -36.54552)
		(width 0.1397)
		(layer "In5.Cu")
		(net "PCIE_IOM_TO_COMP_23_DP")
	)
	(segment
		(start 85.757766 -94.595188)
		(end 87.171784 -93.180916)
		(width 0.1397)
		(layer "In5.Cu")
		(net "PCIE_IOM_TO_COMP_23_DP")
	)
	(segment
		(start 87.171784 -93.180916)
		(end 92.217748 -85.22335)
		(width 0.1397)
		(layer "In5.Cu")
		(net "PCIE_IOM_TO_COMP_23_DP")
	)
	(arc
		(start 85.319362 -94.776798)
		(mid 85.556631 -94.729602)
		(end 85.757766 -94.595188)
		(width 0.1397)
		(layer "In5.Cu")
		(net "PCIE_IOM_TO_COMP_23_DP")
	)
	(arc
		(start 83.358228 -94.535498)
		(mid 83.428903 -94.706123)
		(end 83.599528 -94.776798)
		(width 0.1397)
		(layer "In5.Cu")
		(net "PCIE_IOM_TO_COMP_23_DP")
	)
	(arc
		(start 106.8959 -37.334952)
		(mid 107.040123 -37.275213)
		(end 107.099862 -37.13099)
		(width 0.1397)
		(layer "In5.Cu")
		(net "PCIE_IOM_TO_COMP_23_DP")
	)
	(segment
		(start 79.925164 -95.350076)
		(end 81.111344 -95.350076)
		(width 0.14605)
		(layer "F.Cu")
		(net "PCIE_IOM_TO_COMP_23_DN")
	)
	(segment
		(start 81.111344 -95.350076)
		(end 81.355946 -95.105474)
		(width 0.14605)
		(layer "F.Cu")
		(net "PCIE_IOM_TO_COMP_23_DN")
	)
	(segment
		(start 81.355946 -95.105474)
		(end 83.08213 -95.105474)
		(width 0.14605)
		(layer "F.Cu")
		(net "PCIE_IOM_TO_COMP_23_DN")
	)
	(arc
		(start 83.08213 -95.105474)
		(mid 83.277361 -95.186341)
		(end 83.358228 -95.381572)
		(width 0.14605)
		(layer "F.Cu")
		(net "PCIE_IOM_TO_COMP_23_DN")
	)
	(segment
		(start 107.099862 -37.869114)
		(end 107.099862 -38.200076)
		(width 0.1397)
		(layer "In5.Cu")
		(net "PCIE_IOM_TO_COMP_23_DN")
	)
	(segment
		(start 98.349054 -56.251094)
		(end 96.491044 -46.95952)
		(width 0.1397)
		(layer "In5.Cu")
		(net "PCIE_IOM_TO_COMP_23_DN")
	)
	(segment
		(start 85.991446 -94.828868)
		(end 87.431118 -93.388688)
		(width 0.1397)
		(layer "In5.Cu")
		(net "PCIE_IOM_TO_COMP_23_DN")
	)
	(segment
		(start 83.358228 -95.381572)
		(end 83.358228 -95.348298)
		(width 0.1397)
		(layer "In5.Cu")
		(net "PCIE_IOM_TO_COMP_23_DN")
	)
	(segment
		(start 98.675698 -38.428422)
		(end 100.2284 -36.87572)
		(width 0.1397)
		(layer "In5.Cu")
		(net "PCIE_IOM_TO_COMP_23_DN")
	)
	(segment
		(start 83.599528 -95.106998)
		(end 85.319362 -95.106998)
		(width 0.1397)
		(layer "In5.Cu")
		(net "PCIE_IOM_TO_COMP_23_DN")
	)
	(segment
		(start 103.312214 -36.87572)
		(end 104.101646 -37.665152)
		(width 0.1397)
		(layer "In5.Cu")
		(net "PCIE_IOM_TO_COMP_23_DN")
	)
	(segment
		(start 92.52966 -85.348318)
		(end 98.349054 -56.251094)
		(width 0.1397)
		(layer "In5.Cu")
		(net "PCIE_IOM_TO_COMP_23_DN")
	)
	(segment
		(start 96.491044 -46.95952)
		(end 97.990914 -39.454328)
		(width 0.1397)
		(layer "In5.Cu")
		(net "PCIE_IOM_TO_COMP_23_DN")
	)
	(segment
		(start 97.990914 -39.454328)
		(end 98.675698 -38.428422)
		(width 0.1397)
		(layer "In5.Cu")
		(net "PCIE_IOM_TO_COMP_23_DN")
	)
	(segment
		(start 87.431118 -93.388688)
		(end 92.52966 -85.348318)
		(width 0.1397)
		(layer "In5.Cu")
		(net "PCIE_IOM_TO_COMP_23_DN")
	)
	(segment
		(start 100.2284 -36.87572)
		(end 103.312214 -36.87572)
		(width 0.1397)
		(layer "In5.Cu")
		(net "PCIE_IOM_TO_COMP_23_DN")
	)
	(segment
		(start 104.101646 -37.665152)
		(end 106.8959 -37.665152)
		(width 0.1397)
		(layer "In5.Cu")
		(net "PCIE_IOM_TO_COMP_23_DN")
	)
	(arc
		(start 106.8959 -37.665152)
		(mid 107.040123 -37.724891)
		(end 107.099862 -37.869114)
		(width 0.1397)
		(layer "In5.Cu")
		(net "PCIE_IOM_TO_COMP_23_DN")
	)
	(arc
		(start 83.358228 -95.348298)
		(mid 83.428903 -95.177673)
		(end 83.599528 -95.106998)
		(width 0.1397)
		(layer "In5.Cu")
		(net "PCIE_IOM_TO_COMP_23_DN")
	)
	(arc
		(start 85.319362 -95.106998)
		(mid 85.683047 -95.03475)
		(end 85.991446 -94.828868)
		(width 0.1397)
		(layer "In5.Cu")
		(net "PCIE_IOM_TO_COMP_23_DN")
	)
	(segment
		(start 79.925164 -91.350084)
		(end 81.111344 -91.350084)
		(width 0.14605)
		(layer "F.Cu")
		(net "PCIE_IOM_TO_COMP_22_DP")
	)
	(segment
		(start 84.983828 -91.315032)
		(end 84.983828 -91.306396)
		(width 0.14605)
		(layer "F.Cu")
		(net "PCIE_IOM_TO_COMP_22_DP")
	)
	(segment
		(start 81.111344 -91.350084)
		(end 81.355692 -91.594432)
		(width 0.14605)
		(layer "F.Cu")
		(net "PCIE_IOM_TO_COMP_22_DP")
	)
	(segment
		(start 81.355692 -91.594432)
		(end 84.704428 -91.594432)
		(width 0.14605)
		(layer "F.Cu")
		(net "PCIE_IOM_TO_COMP_22_DP")
	)
	(arc
		(start 84.704428 -91.594432)
		(mid 84.901994 -91.512598)
		(end 84.983828 -91.315032)
		(width 0.14605)
		(layer "F.Cu")
		(net "PCIE_IOM_TO_COMP_22_DP")
	)
	(segment
		(start 108.5342 -36.135056)
		(end 108.712 -36.135056)
		(width 0.1397)
		(layer "In5.Cu")
		(net "PCIE_IOM_TO_COMP_22_DP")
	)
	(segment
		(start 85.263228 -91.585796)
		(end 86.003892 -91.585796)
		(width 0.1397)
		(layer "In5.Cu")
		(net "PCIE_IOM_TO_COMP_22_DP")
	)
	(segment
		(start 91.719908 -83.496404)
		(end 97.194116 -56.129428)
		(width 0.1397)
		(layer "In5.Cu")
		(net "PCIE_IOM_TO_COMP_22_DP")
	)
	(segment
		(start 95.273876 -46.531276)
		(end 96.96323 -38.089586)
		(width 0.1397)
		(layer "In5.Cu")
		(net "PCIE_IOM_TO_COMP_22_DP")
	)
	(segment
		(start 97.704656 -36.987988)
		(end 102.225856 -33.986724)
		(width 0.1397)
		(layer "In5.Cu")
		(net "PCIE_IOM_TO_COMP_22_DP")
	)
	(segment
		(start 86.35873 -91.438476)
		(end 86.572852 -91.224354)
		(width 0.1397)
		(layer "In5.Cu")
		(net "PCIE_IOM_TO_COMP_22_DP")
	)
	(segment
		(start 107.473242 -30.966918)
		(end 108.165138 -31.658814)
		(width 0.1397)
		(layer "In5.Cu")
		(net "PCIE_IOM_TO_COMP_22_DP")
	)
	(segment
		(start 108.89996 -35.947096)
		(end 108.89996 -35.600132)
		(width 0.1397)
		(layer "In5.Cu")
		(net "PCIE_IOM_TO_COMP_22_DP")
	)
	(segment
		(start 102.225856 -33.986978)
		(end 106.775758 -30.966918)
		(width 0.1397)
		(layer "In5.Cu")
		(net "PCIE_IOM_TO_COMP_22_DP")
	)
	(segment
		(start 97.194116 -56.129428)
		(end 95.273876 -46.531276)
		(width 0.1397)
		(layer "In5.Cu")
		(net "PCIE_IOM_TO_COMP_22_DP")
	)
	(segment
		(start 86.572852 -91.224354)
		(end 91.719908 -83.496404)
		(width 0.1397)
		(layer "In5.Cu")
		(net "PCIE_IOM_TO_COMP_22_DP")
	)
	(segment
		(start 106.775758 -30.966918)
		(end 107.473242 -30.966918)
		(width 0.1397)
		(layer "In5.Cu")
		(net "PCIE_IOM_TO_COMP_22_DP")
	)
	(segment
		(start 108.165138 -31.658814)
		(end 108.165138 -35.765994)
		(width 0.1397)
		(layer "In5.Cu")
		(net "PCIE_IOM_TO_COMP_22_DP")
	)
	(segment
		(start 102.225856 -33.986724)
		(end 102.225856 -33.986978)
		(width 0.1397)
		(layer "In5.Cu")
		(net "PCIE_IOM_TO_COMP_22_DP")
	)
	(segment
		(start 96.96323 -38.089586)
		(end 97.704656 -36.987988)
		(width 0.1397)
		(layer "In5.Cu")
		(net "PCIE_IOM_TO_COMP_22_DP")
	)
	(arc
		(start 108.165138 -35.765994)
		(mid 108.273234 -36.02696)
		(end 108.5342 -36.135056)
		(width 0.1397)
		(layer "In5.Cu")
		(net "PCIE_IOM_TO_COMP_22_DP")
	)
	(arc
		(start 108.712 -36.135056)
		(mid 108.844908 -36.080004)
		(end 108.89996 -35.947096)
		(width 0.1397)
		(layer "In5.Cu")
		(net "PCIE_IOM_TO_COMP_22_DP")
	)
	(arc
		(start 84.983828 -91.306396)
		(mid 85.065662 -91.503962)
		(end 85.263228 -91.585796)
		(width 0.1397)
		(layer "In5.Cu")
		(net "PCIE_IOM_TO_COMP_22_DP")
	)
	(arc
		(start 86.003892 -91.585796)
		(mid 86.195992 -91.547473)
		(end 86.35873 -91.438476)
		(width 0.1397)
		(layer "In5.Cu")
		(net "PCIE_IOM_TO_COMP_22_DP")
	)
	(segment
		(start 79.925164 -92.14993)
		(end 81.111344 -92.14993)
		(width 0.14605)
		(layer "F.Cu")
		(net "PCIE_IOM_TO_COMP_22_DN")
	)
	(segment
		(start 81.111344 -92.14993)
		(end 81.355692 -91.905582)
		(width 0.14605)
		(layer "F.Cu")
		(net "PCIE_IOM_TO_COMP_22_DN")
	)
	(segment
		(start 81.355692 -91.905582)
		(end 84.704428 -91.905582)
		(width 0.14605)
		(layer "F.Cu")
		(net "PCIE_IOM_TO_COMP_22_DN")
	)
	(segment
		(start 84.983828 -92.184982)
		(end 84.983828 -92.195396)
		(width 0.14605)
		(layer "F.Cu")
		(net "PCIE_IOM_TO_COMP_22_DN")
	)
	(arc
		(start 84.704428 -91.905582)
		(mid 84.901994 -91.987416)
		(end 84.983828 -92.184982)
		(width 0.14605)
		(layer "F.Cu")
		(net "PCIE_IOM_TO_COMP_22_DN")
	)
	(segment
		(start 96.44253 -42.37482)
		(end 96.442784 -42.37482)
		(width 0.1397)
		(layer "In5.Cu")
		(net "PCIE_IOM_TO_COMP_22_DN")
	)
	(segment
		(start 106.87558 -31.297118)
		(end 107.336336 -31.297118)
		(width 0.1397)
		(layer "In5.Cu")
		(net "PCIE_IOM_TO_COMP_22_DN")
	)
	(segment
		(start 97.942146 -37.227002)
		(end 106.87558 -31.297118)
		(width 0.1397)
		(layer "In5.Cu")
		(net "PCIE_IOM_TO_COMP_22_DN")
	)
	(segment
		(start 107.834938 -31.79572)
		(end 107.834938 -35.765994)
		(width 0.1397)
		(layer "In5.Cu")
		(net "PCIE_IOM_TO_COMP_22_DN")
	)
	(segment
		(start 86.828884 -91.435682)
		(end 92.031058 -83.625182)
		(width 0.1397)
		(layer "In5.Cu")
		(net "PCIE_IOM_TO_COMP_22_DN")
	)
	(segment
		(start 95.61068 -46.531276)
		(end 96.44253 -42.37482)
		(width 0.1397)
		(layer "In5.Cu")
		(net "PCIE_IOM_TO_COMP_22_DN")
	)
	(segment
		(start 97.274126 -38.219126)
		(end 97.942146 -37.227002)
		(width 0.1397)
		(layer "In5.Cu")
		(net "PCIE_IOM_TO_COMP_22_DN")
	)
	(segment
		(start 96.442784 -42.37482)
		(end 97.274126 -38.219126)
		(width 0.1397)
		(layer "In5.Cu")
		(net "PCIE_IOM_TO_COMP_22_DN")
	)
	(segment
		(start 85.263228 -91.915996)
		(end 86.003892 -91.915996)
		(width 0.1397)
		(layer "In5.Cu")
		(net "PCIE_IOM_TO_COMP_22_DN")
	)
	(segment
		(start 92.031058 -83.625182)
		(end 97.53092 -56.129428)
		(width 0.1397)
		(layer "In5.Cu")
		(net "PCIE_IOM_TO_COMP_22_DN")
	)
	(segment
		(start 107.336336 -31.297118)
		(end 107.834938 -31.79572)
		(width 0.1397)
		(layer "In5.Cu")
		(net "PCIE_IOM_TO_COMP_22_DN")
	)
	(segment
		(start 108.5342 -36.465256)
		(end 108.712 -36.465256)
		(width 0.1397)
		(layer "In5.Cu")
		(net "PCIE_IOM_TO_COMP_22_DN")
	)
	(segment
		(start 97.53092 -56.129428)
		(end 95.61068 -46.531276)
		(width 0.1397)
		(layer "In5.Cu")
		(net "PCIE_IOM_TO_COMP_22_DN")
	)
	(segment
		(start 86.59241 -91.672156)
		(end 86.828884 -91.435682)
		(width 0.1397)
		(layer "In5.Cu")
		(net "PCIE_IOM_TO_COMP_22_DN")
	)
	(segment
		(start 108.89996 -36.653216)
		(end 108.89996 -37.00018)
		(width 0.1397)
		(layer "In5.Cu")
		(net "PCIE_IOM_TO_COMP_22_DN")
	)
	(arc
		(start 107.834938 -35.765994)
		(mid 108.039747 -36.260447)
		(end 108.5342 -36.465256)
		(width 0.1397)
		(layer "In5.Cu")
		(net "PCIE_IOM_TO_COMP_22_DN")
	)
	(arc
		(start 108.712 -36.465256)
		(mid 108.844908 -36.520308)
		(end 108.89996 -36.653216)
		(width 0.1397)
		(layer "In5.Cu")
		(net "PCIE_IOM_TO_COMP_22_DN")
	)
	(arc
		(start 86.003892 -91.915996)
		(mid 86.322407 -91.852621)
		(end 86.59241 -91.672156)
		(width 0.1397)
		(layer "In5.Cu")
		(net "PCIE_IOM_TO_COMP_22_DN")
	)
	(arc
		(start 84.983828 -92.195396)
		(mid 85.065662 -91.99783)
		(end 85.263228 -91.915996)
		(width 0.1397)
		(layer "In5.Cu")
		(net "PCIE_IOM_TO_COMP_22_DN")
	)
	(segment
		(start 81.111598 -88.149938)
		(end 81.355946 -88.394286)
		(width 0.14605)
		(layer "F.Cu")
		(net "PCIE_IOM_TO_COMP_21_DP")
	)
	(segment
		(start 79.925164 -88.149938)
		(end 81.111598 -88.149938)
		(width 0.14605)
		(layer "F.Cu")
		(net "PCIE_IOM_TO_COMP_21_DP")
	)
	(segment
		(start 83.358228 -88.152986)
		(end 83.358228 -88.105234)
		(width 0.14605)
		(layer "F.Cu")
		(net "PCIE_IOM_TO_COMP_21_DP")
	)
	(segment
		(start 81.355946 -88.394286)
		(end 83.116928 -88.394286)
		(width 0.14605)
		(layer "F.Cu")
		(net "PCIE_IOM_TO_COMP_21_DP")
	)
	(arc
		(start 83.116928 -88.394286)
		(mid 83.287553 -88.323611)
		(end 83.358228 -88.152986)
		(width 0.14605)
		(layer "F.Cu")
		(net "PCIE_IOM_TO_COMP_21_DP")
	)
	(segment
		(start 96.34347 -56.066182)
		(end 91.270836 -81.432146)
		(width 0.1397)
		(layer "In5.Cu")
		(net "PCIE_IOM_TO_COMP_21_DP")
	)
	(segment
		(start 94.400116 -46.317154)
		(end 94.400116 -46.317408)
		(width 0.1397)
		(layer "In5.Cu")
		(net "PCIE_IOM_TO_COMP_21_DP")
	)
	(segment
		(start 94.406466 -46.382178)
		(end 96.34347 -56.066182)
		(width 0.1397)
		(layer "In5.Cu")
		(net "PCIE_IOM_TO_COMP_21_DP")
	)
	(segment
		(start 94.400116 -46.317408)
		(end 94.406466 -46.382178)
		(width 0.1397)
		(layer "In5.Cu")
		(net "PCIE_IOM_TO_COMP_21_DP")
	)
	(segment
		(start 110.700058 -36.800028)
		(end 110.700058 -37.146992)
		(width 0.1397)
		(layer "In5.Cu")
		(net "PCIE_IOM_TO_COMP_21_DP")
	)
	(segment
		(start 91.270836 -81.432146)
		(end 86.951566 -87.91067)
		(width 0.1397)
		(layer "In5.Cu")
		(net "PCIE_IOM_TO_COMP_21_DP")
	)
	(segment
		(start 109.328712 -29.801312)
		(end 106.630724 -29.801312)
		(width 0.1397)
		(layer "In5.Cu")
		(net "PCIE_IOM_TO_COMP_21_DP")
	)
	(segment
		(start 86.313518 -88.384634)
		(end 83.637628 -88.384634)
		(width 0.1397)
		(layer "In5.Cu")
		(net "PCIE_IOM_TO_COMP_21_DP")
	)
	(segment
		(start 96.213168 -37.215826)
		(end 94.393512 -46.317154)
		(width 0.1397)
		(layer "In5.Cu")
		(net "PCIE_IOM_TO_COMP_21_DP")
	)
	(segment
		(start 110.512098 -37.334952)
		(end 110.334298 -37.334952)
		(width 0.1397)
		(layer "In5.Cu")
		(net "PCIE_IOM_TO_COMP_21_DP")
	)
	(segment
		(start 109.965236 -36.96589)
		(end 109.965236 -30.437836)
		(width 0.1397)
		(layer "In5.Cu")
		(net "PCIE_IOM_TO_COMP_21_DP")
	)
	(segment
		(start 106.630724 -29.801312)
		(end 96.835214 -36.282884)
		(width 0.1397)
		(layer "In5.Cu")
		(net "PCIE_IOM_TO_COMP_21_DP")
	)
	(segment
		(start 109.965236 -30.437836)
		(end 109.328712 -29.801312)
		(width 0.1397)
		(layer "In5.Cu")
		(net "PCIE_IOM_TO_COMP_21_DP")
	)
	(segment
		(start 86.951566 -87.91067)
		(end 86.594188 -88.268048)
		(width 0.1397)
		(layer "In5.Cu")
		(net "PCIE_IOM_TO_COMP_21_DP")
	)
	(segment
		(start 94.393512 -46.317154)
		(end 94.400116 -46.317154)
		(width 0.1397)
		(layer "In5.Cu")
		(net "PCIE_IOM_TO_COMP_21_DP")
	)
	(segment
		(start 96.835214 -36.282884)
		(end 96.213168 -37.215826)
		(width 0.1397)
		(layer "In5.Cu")
		(net "PCIE_IOM_TO_COMP_21_DP")
	)
	(arc
		(start 83.637628 -88.384634)
		(mid 83.440062 -88.3028)
		(end 83.358228 -88.105234)
		(width 0.1397)
		(layer "In5.Cu")
		(net "PCIE_IOM_TO_COMP_21_DP")
	)
	(arc
		(start 110.334298 -37.334952)
		(mid 110.073332 -37.226856)
		(end 109.965236 -36.96589)
		(width 0.1397)
		(layer "In5.Cu")
		(net "PCIE_IOM_TO_COMP_21_DP")
	)
	(arc
		(start 110.700058 -37.146992)
		(mid 110.645006 -37.2799)
		(end 110.512098 -37.334952)
		(width 0.1397)
		(layer "In5.Cu")
		(net "PCIE_IOM_TO_COMP_21_DP")
	)
	(arc
		(start 86.594188 -88.268048)
		(mid 86.465445 -88.354228)
		(end 86.313518 -88.384634)
		(width 0.1397)
		(layer "In5.Cu")
		(net "PCIE_IOM_TO_COMP_21_DP")
	)
	(segment
		(start 83.358228 -88.946736)
		(end 83.358228 -88.994234)
		(width 0.14605)
		(layer "F.Cu")
		(net "PCIE_IOM_TO_COMP_21_DN")
	)
	(segment
		(start 81.355946 -88.705436)
		(end 83.116928 -88.705436)
		(width 0.14605)
		(layer "F.Cu")
		(net "PCIE_IOM_TO_COMP_21_DN")
	)
	(segment
		(start 81.111344 -88.950038)
		(end 81.355946 -88.705436)
		(width 0.14605)
		(layer "F.Cu")
		(net "PCIE_IOM_TO_COMP_21_DN")
	)
	(segment
		(start 79.925164 -88.950038)
		(end 81.111344 -88.950038)
		(width 0.14605)
		(layer "F.Cu")
		(net "PCIE_IOM_TO_COMP_21_DN")
	)
	(arc
		(start 83.116928 -88.705436)
		(mid 83.287553 -88.776111)
		(end 83.358228 -88.946736)
		(width 0.14605)
		(layer "F.Cu")
		(net "PCIE_IOM_TO_COMP_21_DN")
	)
	(segment
		(start 109.191806 -30.131512)
		(end 106.730292 -30.131512)
		(width 0.1397)
		(layer "In5.Cu")
		(net "PCIE_IOM_TO_COMP_21_DN")
	)
	(segment
		(start 109.635036 -30.574742)
		(end 109.191806 -30.131512)
		(width 0.1397)
		(layer "In5.Cu")
		(net "PCIE_IOM_TO_COMP_21_DN")
	)
	(segment
		(start 97.073212 -36.521644)
		(end 96.524318 -37.344858)
		(width 0.1397)
		(layer "In5.Cu")
		(net "PCIE_IOM_TO_COMP_21_DN")
	)
	(segment
		(start 87.207852 -88.121744)
		(end 86.827868 -88.501728)
		(width 0.1397)
		(layer "In5.Cu")
		(net "PCIE_IOM_TO_COMP_21_DN")
	)
	(segment
		(start 106.730292 -30.131512)
		(end 97.073212 -36.521644)
		(width 0.1397)
		(layer "In5.Cu")
		(net "PCIE_IOM_TO_COMP_21_DN")
	)
	(segment
		(start 96.680274 -56.066182)
		(end 91.581986 -81.561178)
		(width 0.1397)
		(layer "In5.Cu")
		(net "PCIE_IOM_TO_COMP_21_DN")
	)
	(segment
		(start 86.313518 -88.714834)
		(end 83.637628 -88.714834)
		(width 0.1397)
		(layer "In5.Cu")
		(net "PCIE_IOM_TO_COMP_21_DN")
	)
	(segment
		(start 110.700058 -38.200076)
		(end 110.700058 -37.853112)
		(width 0.1397)
		(layer "In5.Cu")
		(net "PCIE_IOM_TO_COMP_21_DN")
	)
	(segment
		(start 94.730316 -46.317154)
		(end 94.730316 -46.317408)
		(width 0.1397)
		(layer "In5.Cu")
		(net "PCIE_IOM_TO_COMP_21_DN")
	)
	(segment
		(start 96.524318 -37.344858)
		(end 94.730316 -46.317154)
		(width 0.1397)
		(layer "In5.Cu")
		(net "PCIE_IOM_TO_COMP_21_DN")
	)
	(segment
		(start 110.512098 -37.665152)
		(end 110.334298 -37.665152)
		(width 0.1397)
		(layer "In5.Cu")
		(net "PCIE_IOM_TO_COMP_21_DN")
	)
	(segment
		(start 94.730316 -46.317408)
		(end 96.680274 -56.066182)
		(width 0.1397)
		(layer "In5.Cu")
		(net "PCIE_IOM_TO_COMP_21_DN")
	)
	(segment
		(start 109.635036 -36.96589)
		(end 109.635036 -30.574742)
		(width 0.1397)
		(layer "In5.Cu")
		(net "PCIE_IOM_TO_COMP_21_DN")
	)
	(segment
		(start 91.581986 -81.561178)
		(end 87.207852 -88.121744)
		(width 0.1397)
		(layer "In5.Cu")
		(net "PCIE_IOM_TO_COMP_21_DN")
	)
	(arc
		(start 110.700058 -37.853112)
		(mid 110.645006 -37.720204)
		(end 110.512098 -37.665152)
		(width 0.1397)
		(layer "In5.Cu")
		(net "PCIE_IOM_TO_COMP_21_DN")
	)
	(arc
		(start 110.334298 -37.665152)
		(mid 109.839845 -37.460343)
		(end 109.635036 -36.96589)
		(width 0.1397)
		(layer "In5.Cu")
		(net "PCIE_IOM_TO_COMP_21_DN")
	)
	(arc
		(start 86.827868 -88.501728)
		(mid 86.591896 -88.659462)
		(end 86.313518 -88.714834)
		(width 0.1397)
		(layer "In5.Cu")
		(net "PCIE_IOM_TO_COMP_21_DN")
	)
	(arc
		(start 83.637628 -88.714834)
		(mid 83.440062 -88.796668)
		(end 83.358228 -88.994234)
		(width 0.1397)
		(layer "In5.Cu")
		(net "PCIE_IOM_TO_COMP_21_DN")
	)
	(segment
		(start 81.355946 -85.194394)
		(end 84.780628 -85.194394)
		(width 0.14605)
		(layer "F.Cu")
		(net "PCIE_IOM_TO_COMP_20_DP")
	)
	(segment
		(start 79.925164 -84.950046)
		(end 81.111598 -84.950046)
		(width 0.14605)
		(layer "F.Cu")
		(net "PCIE_IOM_TO_COMP_20_DP")
	)
	(segment
		(start 84.983828 -84.991194)
		(end 84.983828 -84.904834)
		(width 0.14605)
		(layer "F.Cu")
		(net "PCIE_IOM_TO_COMP_20_DP")
	)
	(segment
		(start 81.111598 -84.950046)
		(end 81.355946 -85.194394)
		(width 0.14605)
		(layer "F.Cu")
		(net "PCIE_IOM_TO_COMP_20_DP")
	)
	(arc
		(start 84.780628 -85.194394)
		(mid 84.924312 -85.134878)
		(end 84.983828 -84.991194)
		(width 0.14605)
		(layer "F.Cu")
		(net "PCIE_IOM_TO_COMP_20_DP")
	)
	(segment
		(start 106.188764 -29.021532)
		(end 100.997258 -32.457644)
		(width 0.1397)
		(layer "In5.Cu")
		(net "PCIE_IOM_TO_COMP_20_DP")
	)
	(segment
		(start 110.479586 -29.021532)
		(end 106.188764 -29.021532)
		(width 0.1397)
		(layer "In5.Cu")
		(net "PCIE_IOM_TO_COMP_20_DP")
	)
	(segment
		(start 93.94825 -38.703504)
		(end 92.477336 -46.063154)
		(width 0.1397)
		(layer "In5.Cu")
		(net "PCIE_IOM_TO_COMP_20_DP")
	)
	(segment
		(start 86.156546 -85.184234)
		(end 85.263228 -85.184234)
		(width 0.1397)
		(layer "In5.Cu")
		(net "PCIE_IOM_TO_COMP_20_DP")
	)
	(segment
		(start 89.77884 -80.354424)
		(end 86.776306 -84.85886)
		(width 0.1397)
		(layer "In5.Cu")
		(net "PCIE_IOM_TO_COMP_20_DP")
	)
	(segment
		(start 98.443034 -34.148268)
		(end 95.833438 -35.875214)
		(width 0.1397)
		(layer "In5.Cu")
		(net "PCIE_IOM_TO_COMP_20_DP")
	)
	(segment
		(start 112.499902 -35.600132)
		(end 112.499902 -35.947096)
		(width 0.1397)
		(layer "In5.Cu")
		(net "PCIE_IOM_TO_COMP_20_DP")
	)
	(segment
		(start 90.780108 -78.852776)
		(end 89.77884 -80.354424)
		(width 0.1397)
		(layer "In5.Cu")
		(net "PCIE_IOM_TO_COMP_20_DP")
	)
	(segment
		(start 92.477336 -46.063154)
		(end 94.90329 -58.192162)
		(width 0.1397)
		(layer "In5.Cu")
		(net "PCIE_IOM_TO_COMP_20_DP")
	)
	(segment
		(start 95.833438 -35.875214)
		(end 93.94825 -38.703504)
		(width 0.1397)
		(layer "In5.Cu")
		(net "PCIE_IOM_TO_COMP_20_DP")
	)
	(segment
		(start 94.88551 -58.280808)
		(end 90.780108 -78.852776)
		(width 0.1397)
		(layer "In5.Cu")
		(net "PCIE_IOM_TO_COMP_20_DP")
	)
	(segment
		(start 100.997258 -32.457644)
		(end 98.443034 -34.148268)
		(width 0.1397)
		(layer "In5.Cu")
		(net "PCIE_IOM_TO_COMP_20_DP")
	)
	(segment
		(start 111.76508 -30.307026)
		(end 110.479586 -29.021532)
		(width 0.1397)
		(layer "In5.Cu")
		(net "PCIE_IOM_TO_COMP_20_DP")
	)
	(segment
		(start 86.776306 -84.85886)
		(end 86.659212 -84.975954)
		(width 0.1397)
		(layer "In5.Cu")
		(net "PCIE_IOM_TO_COMP_20_DP")
	)
	(segment
		(start 94.90329 -58.192162)
		(end 94.88551 -58.280808)
		(width 0.1397)
		(layer "In5.Cu")
		(net "PCIE_IOM_TO_COMP_20_DP")
	)
	(segment
		(start 112.311942 -36.135056)
		(end 112.134142 -36.135056)
		(width 0.1397)
		(layer "In5.Cu")
		(net "PCIE_IOM_TO_COMP_20_DP")
	)
	(segment
		(start 111.76508 -35.765994)
		(end 111.76508 -30.307026)
		(width 0.1397)
		(layer "In5.Cu")
		(net "PCIE_IOM_TO_COMP_20_DP")
	)
	(arc
		(start 112.134142 -36.135056)
		(mid 111.873176 -36.02696)
		(end 111.76508 -35.765994)
		(width 0.1397)
		(layer "In5.Cu")
		(net "PCIE_IOM_TO_COMP_20_DP")
	)
	(arc
		(start 85.263228 -85.184234)
		(mid 85.065662 -85.1024)
		(end 84.983828 -84.904834)
		(width 0.1397)
		(layer "In5.Cu")
		(net "PCIE_IOM_TO_COMP_20_DP")
	)
	(arc
		(start 112.499902 -35.947096)
		(mid 112.44485 -36.080004)
		(end 112.311942 -36.135056)
		(width 0.1397)
		(layer "In5.Cu")
		(net "PCIE_IOM_TO_COMP_20_DP")
	)
	(arc
		(start 86.659212 -84.975954)
		(mid 86.428573 -85.130028)
		(end 86.156546 -85.184234)
		(width 0.1397)
		(layer "In5.Cu")
		(net "PCIE_IOM_TO_COMP_20_DP")
	)
	(segment
		(start 81.111344 -85.750146)
		(end 81.355946 -85.505544)
		(width 0.14605)
		(layer "F.Cu")
		(net "PCIE_IOM_TO_COMP_20_DN")
	)
	(segment
		(start 81.355946 -85.505544)
		(end 84.780628 -85.505544)
		(width 0.14605)
		(layer "F.Cu")
		(net "PCIE_IOM_TO_COMP_20_DN")
	)
	(segment
		(start 79.925164 -85.750146)
		(end 81.111344 -85.750146)
		(width 0.14605)
		(layer "F.Cu")
		(net "PCIE_IOM_TO_COMP_20_DN")
	)
	(segment
		(start 84.983828 -85.708744)
		(end 84.983828 -85.793834)
		(width 0.14605)
		(layer "F.Cu")
		(net "PCIE_IOM_TO_COMP_20_DN")
	)
	(arc
		(start 84.780628 -85.505544)
		(mid 84.924312 -85.56506)
		(end 84.983828 -85.708744)
		(width 0.14605)
		(layer "F.Cu")
		(net "PCIE_IOM_TO_COMP_20_DN")
	)
	(segment
		(start 96.071436 -36.113974)
		(end 101.17963 -32.73298)
		(width 0.1397)
		(layer "In5.Cu")
		(net "PCIE_IOM_TO_COMP_20_DN")
	)
	(segment
		(start 111.43488 -30.443932)
		(end 111.43488 -35.765994)
		(width 0.1397)
		(layer "In5.Cu")
		(net "PCIE_IOM_TO_COMP_20_DN")
	)
	(segment
		(start 94.2594 -38.832282)
		(end 96.071436 -36.113974)
		(width 0.1397)
		(layer "In5.Cu")
		(net "PCIE_IOM_TO_COMP_20_DN")
	)
	(segment
		(start 106.288332 -29.351732)
		(end 110.34268 -29.351732)
		(width 0.1397)
		(layer "In5.Cu")
		(net "PCIE_IOM_TO_COMP_20_DN")
	)
	(segment
		(start 85.263228 -85.514434)
		(end 86.156546 -85.514434)
		(width 0.1397)
		(layer "In5.Cu")
		(net "PCIE_IOM_TO_COMP_20_DN")
	)
	(segment
		(start 112.134142 -36.465256)
		(end 112.311942 -36.465256)
		(width 0.1397)
		(layer "In5.Cu")
		(net "PCIE_IOM_TO_COMP_20_DN")
	)
	(segment
		(start 92.81414 -46.063154)
		(end 94.2594 -38.832282)
		(width 0.1397)
		(layer "In5.Cu")
		(net "PCIE_IOM_TO_COMP_20_DN")
	)
	(segment
		(start 110.34268 -29.351732)
		(end 111.43488 -30.443932)
		(width 0.1397)
		(layer "In5.Cu")
		(net "PCIE_IOM_TO_COMP_20_DN")
	)
	(segment
		(start 89.052908 -82.038952)
		(end 91.091258 -78.981554)
		(width 0.1397)
		(layer "In5.Cu")
		(net "PCIE_IOM_TO_COMP_20_DN")
	)
	(segment
		(start 101.17963 -32.73298)
		(end 106.288332 -29.351732)
		(width 0.1397)
		(layer "In5.Cu")
		(net "PCIE_IOM_TO_COMP_20_DN")
	)
	(segment
		(start 86.892892 -85.209634)
		(end 87.0331 -85.069426)
		(width 0.1397)
		(layer "In5.Cu")
		(net "PCIE_IOM_TO_COMP_20_DN")
	)
	(segment
		(start 87.0331 -85.069426)
		(end 89.052908 -82.038952)
		(width 0.1397)
		(layer "In5.Cu")
		(net "PCIE_IOM_TO_COMP_20_DN")
	)
	(segment
		(start 95.20936 -58.345578)
		(end 95.240094 -58.192162)
		(width 0.1397)
		(layer "In5.Cu")
		(net "PCIE_IOM_TO_COMP_20_DN")
	)
	(segment
		(start 112.499902 -36.653216)
		(end 112.499902 -37.00018)
		(width 0.1397)
		(layer "In5.Cu")
		(net "PCIE_IOM_TO_COMP_20_DN")
	)
	(segment
		(start 91.091258 -78.981554)
		(end 95.20936 -58.345578)
		(width 0.1397)
		(layer "In5.Cu")
		(net "PCIE_IOM_TO_COMP_20_DN")
	)
	(segment
		(start 95.240094 -58.192162)
		(end 92.81414 -46.063154)
		(width 0.1397)
		(layer "In5.Cu")
		(net "PCIE_IOM_TO_COMP_20_DN")
	)
	(arc
		(start 84.983828 -85.793834)
		(mid 85.065662 -85.596268)
		(end 85.263228 -85.514434)
		(width 0.1397)
		(layer "In5.Cu")
		(net "PCIE_IOM_TO_COMP_20_DN")
	)
	(arc
		(start 112.311942 -36.465256)
		(mid 112.44485 -36.520308)
		(end 112.499902 -36.653216)
		(width 0.1397)
		(layer "In5.Cu")
		(net "PCIE_IOM_TO_COMP_20_DN")
	)
	(arc
		(start 111.43488 -35.765994)
		(mid 111.639689 -36.260447)
		(end 112.134142 -36.465256)
		(width 0.1397)
		(layer "In5.Cu")
		(net "PCIE_IOM_TO_COMP_20_DN")
	)
	(arc
		(start 86.156546 -85.514434)
		(mid 86.555018 -85.435227)
		(end 86.892892 -85.209634)
		(width 0.1397)
		(layer "In5.Cu")
		(net "PCIE_IOM_TO_COMP_20_DN")
	)
	(segment
		(start 79.925164 -81.7499)
		(end 81.111598 -81.7499)
		(width 0.14605)
		(layer "F.Cu")
		(net "PCIE_IOM_TO_COMP_19_DP")
	)
	(segment
		(start 81.355946 -81.994248)
		(end 83.104228 -81.994248)
		(width 0.14605)
		(layer "F.Cu")
		(net "PCIE_IOM_TO_COMP_19_DP")
	)
	(segment
		(start 81.111598 -81.7499)
		(end 81.355946 -81.994248)
		(width 0.14605)
		(layer "F.Cu")
		(net "PCIE_IOM_TO_COMP_19_DP")
	)
	(segment
		(start 83.358228 -81.740248)
		(end 83.358228 -81.705196)
		(width 0.14605)
		(layer "F.Cu")
		(net "PCIE_IOM_TO_COMP_19_DP")
	)
	(arc
		(start 83.104228 -81.994248)
		(mid 83.283833 -81.919853)
		(end 83.358228 -81.740248)
		(width 0.14605)
		(layer "F.Cu")
		(net "PCIE_IOM_TO_COMP_19_DP")
	)
	(segment
		(start 93.960188 -57.74563)
		(end 93.960188 -57.88152)
		(width 0.1397)
		(layer "In5.Cu")
		(net "PCIE_IOM_TO_COMP_19_DP")
	)
	(segment
		(start 113.565178 -29.887672)
		(end 111.901478 -28.223972)
		(width 0.1397)
		(layer "In5.Cu")
		(net "PCIE_IOM_TO_COMP_19_DP")
	)
	(segment
		(start 113.565178 -36.96589)
		(end 113.565178 -29.887672)
		(width 0.1397)
		(layer "In5.Cu")
		(net "PCIE_IOM_TO_COMP_19_DP")
	)
	(segment
		(start 93.960188 -57.88152)
		(end 90.22334 -76.56449)
		(width 0.1397)
		(layer "In5.Cu")
		(net "PCIE_IOM_TO_COMP_19_DP")
	)
	(segment
		(start 94.716346 -35.438842)
		(end 94.442026 -35.85337)
		(width 0.1397)
		(layer "In5.Cu")
		(net "PCIE_IOM_TO_COMP_19_DP")
	)
	(segment
		(start 93.144086 -37.816282)
		(end 91.559888 -45.74159)
		(width 0.1397)
		(layer "In5.Cu")
		(net "PCIE_IOM_TO_COMP_19_DP")
	)
	(segment
		(start 105.305606 -28.223972)
		(end 94.960186 -35.070034)
		(width 0.1397)
		(layer "In5.Cu")
		(net "PCIE_IOM_TO_COMP_19_DP")
	)
	(segment
		(start 111.901478 -28.223972)
		(end 105.305606 -28.223972)
		(width 0.1397)
		(layer "In5.Cu")
		(net "PCIE_IOM_TO_COMP_19_DP")
	)
	(segment
		(start 114.3 -36.800028)
		(end 114.3 -37.146992)
		(width 0.1397)
		(layer "In5.Cu")
		(net "PCIE_IOM_TO_COMP_19_DP")
	)
	(segment
		(start 91.559888 -45.74159)
		(end 93.960188 -57.74563)
		(width 0.1397)
		(layer "In5.Cu")
		(net "PCIE_IOM_TO_COMP_19_DP")
	)
	(segment
		(start 94.442026 -35.85337)
		(end 93.947996 -36.600384)
		(width 0.1397)
		(layer "In5.Cu")
		(net "PCIE_IOM_TO_COMP_19_DP")
	)
	(segment
		(start 93.947996 -36.600384)
		(end 93.144086 -37.816282)
		(width 0.1397)
		(layer "In5.Cu")
		(net "PCIE_IOM_TO_COMP_19_DP")
	)
	(segment
		(start 114.11204 -37.334952)
		(end 113.93424 -37.334952)
		(width 0.1397)
		(layer "In5.Cu")
		(net "PCIE_IOM_TO_COMP_19_DP")
	)
	(segment
		(start 94.960186 -35.070034)
		(end 94.716346 -35.438842)
		(width 0.1397)
		(layer "In5.Cu")
		(net "PCIE_IOM_TO_COMP_19_DP")
	)
	(segment
		(start 90.22334 -76.56449)
		(end 87.20836 -81.08696)
		(width 0.1397)
		(layer "In5.Cu")
		(net "PCIE_IOM_TO_COMP_19_DP")
	)
	(segment
		(start 85.989922 -81.984596)
		(end 83.637628 -81.984596)
		(width 0.1397)
		(layer "In5.Cu")
		(net "PCIE_IOM_TO_COMP_19_DP")
	)
	(segment
		(start 87.20836 -81.08696)
		(end 86.537546 -81.757774)
		(width 0.1397)
		(layer "In5.Cu")
		(net "PCIE_IOM_TO_COMP_19_DP")
	)
	(arc
		(start 114.3 -37.146992)
		(mid 114.244948 -37.2799)
		(end 114.11204 -37.334952)
		(width 0.1397)
		(layer "In5.Cu")
		(net "PCIE_IOM_TO_COMP_19_DP")
	)
	(arc
		(start 113.93424 -37.334952)
		(mid 113.673274 -37.226856)
		(end 113.565178 -36.96589)
		(width 0.1397)
		(layer "In5.Cu")
		(net "PCIE_IOM_TO_COMP_19_DP")
	)
	(arc
		(start 86.537546 -81.757774)
		(mid 86.28628 -81.925602)
		(end 85.989922 -81.984596)
		(width 0.1397)
		(layer "In5.Cu")
		(net "PCIE_IOM_TO_COMP_19_DP")
	)
	(arc
		(start 83.637628 -81.984596)
		(mid 83.440062 -81.902762)
		(end 83.358228 -81.705196)
		(width 0.1397)
		(layer "In5.Cu")
		(net "PCIE_IOM_TO_COMP_19_DP")
	)
	(segment
		(start 79.925164 -82.55)
		(end 81.111344 -82.55)
		(width 0.14605)
		(layer "F.Cu")
		(net "PCIE_IOM_TO_COMP_19_DN")
	)
	(segment
		(start 81.355946 -82.305398)
		(end 83.104228 -82.305398)
		(width 0.14605)
		(layer "F.Cu")
		(net "PCIE_IOM_TO_COMP_19_DN")
	)
	(segment
		(start 81.111344 -82.55)
		(end 81.355946 -82.305398)
		(width 0.14605)
		(layer "F.Cu")
		(net "PCIE_IOM_TO_COMP_19_DN")
	)
	(segment
		(start 83.358228 -82.559398)
		(end 83.358228 -82.594196)
		(width 0.14605)
		(layer "F.Cu")
		(net "PCIE_IOM_TO_COMP_19_DN")
	)
	(arc
		(start 83.104228 -82.305398)
		(mid 83.283833 -82.379793)
		(end 83.358228 -82.559398)
		(width 0.14605)
		(layer "F.Cu")
		(net "PCIE_IOM_TO_COMP_19_DN")
	)
	(segment
		(start 93.455236 -37.944552)
		(end 94.223586 -36.782756)
		(width 0.1397)
		(layer "In5.Cu")
		(net "PCIE_IOM_TO_COMP_19_DN")
	)
	(segment
		(start 114.3 -37.853112)
		(end 114.3 -38.200076)
		(width 0.1397)
		(layer "In5.Cu")
		(net "PCIE_IOM_TO_COMP_19_DN")
	)
	(segment
		(start 94.290388 -57.712864)
		(end 91.896692 -45.74159)
		(width 0.1397)
		(layer "In5.Cu")
		(net "PCIE_IOM_TO_COMP_19_DN")
	)
	(segment
		(start 113.93424 -37.665152)
		(end 114.11204 -37.665152)
		(width 0.1397)
		(layer "In5.Cu")
		(net "PCIE_IOM_TO_COMP_19_DN")
	)
	(segment
		(start 83.637628 -82.314796)
		(end 85.989922 -82.314796)
		(width 0.1397)
		(layer "In5.Cu")
		(net "PCIE_IOM_TO_COMP_19_DN")
	)
	(segment
		(start 91.896692 -45.74159)
		(end 93.455236 -37.944552)
		(width 0.1397)
		(layer "In5.Cu")
		(net "PCIE_IOM_TO_COMP_19_DN")
	)
	(segment
		(start 86.771226 -81.991454)
		(end 87.465154 -81.297526)
		(width 0.1397)
		(layer "In5.Cu")
		(net "PCIE_IOM_TO_COMP_19_DN")
	)
	(segment
		(start 94.290388 -57.914286)
		(end 94.290388 -57.712864)
		(width 0.1397)
		(layer "In5.Cu")
		(net "PCIE_IOM_TO_COMP_19_DN")
	)
	(segment
		(start 95.198692 -35.30854)
		(end 105.405174 -28.554172)
		(width 0.1397)
		(layer "In5.Cu")
		(net "PCIE_IOM_TO_COMP_19_DN")
	)
	(segment
		(start 113.234978 -30.024578)
		(end 113.234978 -36.96589)
		(width 0.1397)
		(layer "In5.Cu")
		(net "PCIE_IOM_TO_COMP_19_DN")
	)
	(segment
		(start 87.465154 -81.297526)
		(end 90.53449 -76.693522)
		(width 0.1397)
		(layer "In5.Cu")
		(net "PCIE_IOM_TO_COMP_19_DN")
	)
	(segment
		(start 94.223586 -36.782756)
		(end 95.198692 -35.30854)
		(width 0.1397)
		(layer "In5.Cu")
		(net "PCIE_IOM_TO_COMP_19_DN")
	)
	(segment
		(start 105.405174 -28.554172)
		(end 111.764572 -28.554172)
		(width 0.1397)
		(layer "In5.Cu")
		(net "PCIE_IOM_TO_COMP_19_DN")
	)
	(segment
		(start 90.53449 -76.693522)
		(end 94.290388 -57.914286)
		(width 0.1397)
		(layer "In5.Cu")
		(net "PCIE_IOM_TO_COMP_19_DN")
	)
	(segment
		(start 111.764572 -28.554172)
		(end 113.234978 -30.024578)
		(width 0.1397)
		(layer "In5.Cu")
		(net "PCIE_IOM_TO_COMP_19_DN")
	)
	(arc
		(start 114.11204 -37.665152)
		(mid 114.244948 -37.720204)
		(end 114.3 -37.853112)
		(width 0.1397)
		(layer "In5.Cu")
		(net "PCIE_IOM_TO_COMP_19_DN")
	)
	(arc
		(start 113.234978 -36.96589)
		(mid 113.439787 -37.460343)
		(end 113.93424 -37.665152)
		(width 0.1397)
		(layer "In5.Cu")
		(net "PCIE_IOM_TO_COMP_19_DN")
	)
	(arc
		(start 83.358228 -82.594196)
		(mid 83.440062 -82.39663)
		(end 83.637628 -82.314796)
		(width 0.1397)
		(layer "In5.Cu")
		(net "PCIE_IOM_TO_COMP_19_DN")
	)
	(arc
		(start 85.989922 -82.314796)
		(mid 86.41272 -82.230808)
		(end 86.771226 -81.991454)
		(width 0.1397)
		(layer "In5.Cu")
		(net "PCIE_IOM_TO_COMP_19_DN")
	)
	(segment
		(start 79.925164 -78.550008)
		(end 81.111598 -78.550008)
		(width 0.14605)
		(layer "F.Cu")
		(net "PCIE_IOM_TO_COMP_18_DP")
	)
	(segment
		(start 81.111598 -78.550008)
		(end 81.355946 -78.794356)
		(width 0.14605)
		(layer "F.Cu")
		(net "PCIE_IOM_TO_COMP_18_DP")
	)
	(segment
		(start 84.983828 -78.553056)
		(end 84.983828 -78.504796)
		(width 0.14605)
		(layer "F.Cu")
		(net "PCIE_IOM_TO_COMP_18_DP")
	)
	(segment
		(start 81.355946 -78.794356)
		(end 84.742528 -78.794356)
		(width 0.14605)
		(layer "F.Cu")
		(net "PCIE_IOM_TO_COMP_18_DP")
	)
	(arc
		(start 84.742528 -78.794356)
		(mid 84.913153 -78.723681)
		(end 84.983828 -78.553056)
		(width 0.14605)
		(layer "F.Cu")
		(net "PCIE_IOM_TO_COMP_18_DP")
	)
	(segment
		(start 86.227666 -78.784196)
		(end 85.263228 -78.784196)
		(width 0.1397)
		(layer "In5.Cu")
		(net "PCIE_IOM_TO_COMP_18_DP")
	)
	(segment
		(start 115.365022 -30.275022)
		(end 112.522254 -27.432254)
		(width 0.1397)
		(layer "In5.Cu")
		(net "PCIE_IOM_TO_COMP_18_DP")
	)
	(segment
		(start 89.530428 -74.517504)
		(end 89.091008 -75.176888)
		(width 0.1397)
		(layer "In5.Cu")
		(net "PCIE_IOM_TO_COMP_18_DP")
	)
	(segment
		(start 116.099844 -35.600132)
		(end 116.099844 -35.947096)
		(width 0.1397)
		(layer "In5.Cu")
		(net "PCIE_IOM_TO_COMP_18_DP")
	)
	(segment
		(start 102.992936 -28.552902)
		(end 94.326202 -34.289238)
		(width 0.1397)
		(layer "In5.Cu")
		(net "PCIE_IOM_TO_COMP_18_DP")
	)
	(segment
		(start 87.056468 -78.230222)
		(end 86.697058 -78.589632)
		(width 0.1397)
		(layer "In5.Cu")
		(net "PCIE_IOM_TO_COMP_18_DP")
	)
	(segment
		(start 115.365022 -35.765994)
		(end 115.365022 -30.275022)
		(width 0.1397)
		(layer "In5.Cu")
		(net "PCIE_IOM_TO_COMP_18_DP")
	)
	(segment
		(start 115.911884 -36.135056)
		(end 115.734084 -36.135056)
		(width 0.1397)
		(layer "In5.Cu")
		(net "PCIE_IOM_TO_COMP_18_DP")
	)
	(segment
		(start 87.734648 -77.212698)
		(end 87.056468 -78.230222)
		(width 0.1397)
		(layer "In5.Cu")
		(net "PCIE_IOM_TO_COMP_18_DP")
	)
	(segment
		(start 92.850208 -36.502594)
		(end 92.649802 -36.803584)
		(width 0.1397)
		(layer "In5.Cu")
		(net "PCIE_IOM_TO_COMP_18_DP")
	)
	(segment
		(start 92.379292 -37.209222)
		(end 90.710258 -45.558456)
		(width 0.1397)
		(layer "In5.Cu")
		(net "PCIE_IOM_TO_COMP_18_DP")
	)
	(segment
		(start 93.150944 -57.942734)
		(end 89.970102 -73.857612)
		(width 0.1397)
		(layer "In5.Cu")
		(net "PCIE_IOM_TO_COMP_18_DP")
	)
	(segment
		(start 89.091008 -75.176888)
		(end 87.734648 -77.212698)
		(width 0.1397)
		(layer "In5.Cu")
		(net "PCIE_IOM_TO_COMP_18_DP")
	)
	(segment
		(start 112.522254 -27.432254)
		(end 104.6861 -27.432254)
		(width 0.1397)
		(layer "In5.Cu")
		(net "PCIE_IOM_TO_COMP_18_DP")
	)
	(segment
		(start 94.326202 -34.289238)
		(end 93.352366 -35.749992)
		(width 0.1397)
		(layer "In5.Cu")
		(net "PCIE_IOM_TO_COMP_18_DP")
	)
	(segment
		(start 93.352366 -35.749992)
		(end 92.850208 -36.502594)
		(width 0.1397)
		(layer "In5.Cu")
		(net "PCIE_IOM_TO_COMP_18_DP")
	)
	(segment
		(start 91.97594 -51.887628)
		(end 93.150944 -57.763156)
		(width 0.1397)
		(layer "In5.Cu")
		(net "PCIE_IOM_TO_COMP_18_DP")
	)
	(segment
		(start 92.649802 -36.803584)
		(end 92.379292 -37.209222)
		(width 0.1397)
		(layer "In5.Cu")
		(net "PCIE_IOM_TO_COMP_18_DP")
	)
	(segment
		(start 90.710258 -45.558456)
		(end 91.97594 -51.887628)
		(width 0.1397)
		(layer "In5.Cu")
		(net "PCIE_IOM_TO_COMP_18_DP")
	)
	(segment
		(start 89.970102 -73.857612)
		(end 89.530428 -74.517504)
		(width 0.1397)
		(layer "In5.Cu")
		(net "PCIE_IOM_TO_COMP_18_DP")
	)
	(segment
		(start 93.150944 -57.763156)
		(end 93.150944 -57.942734)
		(width 0.1397)
		(layer "In5.Cu")
		(net "PCIE_IOM_TO_COMP_18_DP")
	)
	(segment
		(start 104.6861 -27.432254)
		(end 102.992936 -28.552902)
		(width 0.1397)
		(layer "In5.Cu")
		(net "PCIE_IOM_TO_COMP_18_DP")
	)
	(arc
		(start 115.734084 -36.135056)
		(mid 115.473118 -36.02696)
		(end 115.365022 -35.765994)
		(width 0.1397)
		(layer "In5.Cu")
		(net "PCIE_IOM_TO_COMP_18_DP")
	)
	(arc
		(start 85.263228 -78.784196)
		(mid 85.065662 -78.702362)
		(end 84.983828 -78.504796)
		(width 0.1397)
		(layer "In5.Cu")
		(net "PCIE_IOM_TO_COMP_18_DP")
	)
	(arc
		(start 86.697058 -78.589632)
		(mid 86.4817 -78.733559)
		(end 86.227666 -78.784196)
		(width 0.1397)
		(layer "In5.Cu")
		(net "PCIE_IOM_TO_COMP_18_DP")
	)
	(arc
		(start 116.099844 -35.947096)
		(mid 116.044792 -36.080004)
		(end 115.911884 -36.135056)
		(width 0.1397)
		(layer "In5.Cu")
		(net "PCIE_IOM_TO_COMP_18_DP")
	)
	(segment
		(start 84.983828 -79.346806)
		(end 84.983828 -79.393796)
		(width 0.14605)
		(layer "F.Cu")
		(net "PCIE_IOM_TO_COMP_18_DN")
	)
	(segment
		(start 81.111344 -79.350108)
		(end 81.355946 -79.105506)
		(width 0.14605)
		(layer "F.Cu")
		(net "PCIE_IOM_TO_COMP_18_DN")
	)
	(segment
		(start 79.925164 -79.350108)
		(end 81.111344 -79.350108)
		(width 0.14605)
		(layer "F.Cu")
		(net "PCIE_IOM_TO_COMP_18_DN")
	)
	(segment
		(start 81.355946 -79.105506)
		(end 84.742528 -79.105506)
		(width 0.14605)
		(layer "F.Cu")
		(net "PCIE_IOM_TO_COMP_18_DN")
	)
	(arc
		(start 84.742528 -79.105506)
		(mid 84.913153 -79.176181)
		(end 84.983828 -79.346806)
		(width 0.14605)
		(layer "F.Cu")
		(net "PCIE_IOM_TO_COMP_18_DN")
	)
	(segment
		(start 90.281252 -73.98639)
		(end 89.365836 -75.360022)
		(width 0.1397)
		(layer "In5.Cu")
		(net "PCIE_IOM_TO_COMP_18_DN")
	)
	(segment
		(start 115.034822 -35.765994)
		(end 115.034822 -30.411928)
		(width 0.1397)
		(layer "In5.Cu")
		(net "PCIE_IOM_TO_COMP_18_DN")
	)
	(segment
		(start 115.911884 -36.465256)
		(end 115.734084 -36.465256)
		(width 0.1397)
		(layer "In5.Cu")
		(net "PCIE_IOM_TO_COMP_18_DN")
	)
	(segment
		(start 93.481144 -57.73039)
		(end 93.481144 -57.9755)
		(width 0.1397)
		(layer "In5.Cu")
		(net "PCIE_IOM_TO_COMP_18_DN")
	)
	(segment
		(start 93.627194 -35.933126)
		(end 93.158564 -36.63569)
		(width 0.1397)
		(layer "In5.Cu")
		(net "PCIE_IOM_TO_COMP_18_DN")
	)
	(segment
		(start 116.099844 -37.00018)
		(end 116.099844 -36.653216)
		(width 0.1397)
		(layer "In5.Cu")
		(net "PCIE_IOM_TO_COMP_18_DN")
	)
	(segment
		(start 93.481144 -57.9755)
		(end 90.281252 -73.98639)
		(width 0.1397)
		(layer "In5.Cu")
		(net "PCIE_IOM_TO_COMP_18_DN")
	)
	(segment
		(start 94.5642 -34.527998)
		(end 93.627194 -35.933126)
		(width 0.1397)
		(layer "In5.Cu")
		(net "PCIE_IOM_TO_COMP_18_DN")
	)
	(segment
		(start 92.29979 -51.822858)
		(end 93.481144 -57.73039)
		(width 0.1397)
		(layer "In5.Cu")
		(net "PCIE_IOM_TO_COMP_18_DN")
	)
	(segment
		(start 91.047062 -45.558456)
		(end 92.29979 -51.822858)
		(width 0.1397)
		(layer "In5.Cu")
		(net "PCIE_IOM_TO_COMP_18_DN")
	)
	(segment
		(start 87.313008 -78.441042)
		(end 86.930738 -78.823312)
		(width 0.1397)
		(layer "In5.Cu")
		(net "PCIE_IOM_TO_COMP_18_DN")
	)
	(segment
		(start 104.785668 -27.762454)
		(end 94.5642 -34.527998)
		(width 0.1397)
		(layer "In5.Cu")
		(net "PCIE_IOM_TO_COMP_18_DN")
	)
	(segment
		(start 115.034822 -30.411928)
		(end 112.385348 -27.762454)
		(width 0.1397)
		(layer "In5.Cu")
		(net "PCIE_IOM_TO_COMP_18_DN")
	)
	(segment
		(start 89.365836 -75.360022)
		(end 87.313008 -78.441042)
		(width 0.1397)
		(layer "In5.Cu")
		(net "PCIE_IOM_TO_COMP_18_DN")
	)
	(segment
		(start 92.690442 -37.338)
		(end 91.047062 -45.558456)
		(width 0.1397)
		(layer "In5.Cu")
		(net "PCIE_IOM_TO_COMP_18_DN")
	)
	(segment
		(start 86.227666 -79.114396)
		(end 85.263228 -79.114396)
		(width 0.1397)
		(layer "In5.Cu")
		(net "PCIE_IOM_TO_COMP_18_DN")
	)
	(segment
		(start 112.385348 -27.762454)
		(end 104.785668 -27.762454)
		(width 0.1397)
		(layer "In5.Cu")
		(net "PCIE_IOM_TO_COMP_18_DN")
	)
	(segment
		(start 93.158564 -36.63569)
		(end 92.690442 -37.338)
		(width 0.1397)
		(layer "In5.Cu")
		(net "PCIE_IOM_TO_COMP_18_DN")
	)
	(arc
		(start 115.734084 -36.465256)
		(mid 115.239631 -36.260447)
		(end 115.034822 -35.765994)
		(width 0.1397)
		(layer "In5.Cu")
		(net "PCIE_IOM_TO_COMP_18_DN")
	)
	(arc
		(start 86.930738 -78.823312)
		(mid 86.608137 -79.03874)
		(end 86.227666 -79.114396)
		(width 0.1397)
		(layer "In5.Cu")
		(net "PCIE_IOM_TO_COMP_18_DN")
	)
	(arc
		(start 85.263228 -79.114396)
		(mid 85.065662 -79.19623)
		(end 84.983828 -79.393796)
		(width 0.1397)
		(layer "In5.Cu")
		(net "PCIE_IOM_TO_COMP_18_DN")
	)
	(arc
		(start 116.099844 -36.653216)
		(mid 116.044792 -36.520308)
		(end 115.911884 -36.465256)
		(width 0.1397)
		(layer "In5.Cu")
		(net "PCIE_IOM_TO_COMP_18_DN")
	)
	(segment
		(start 79.925164 -75.350116)
		(end 81.111344 -75.350116)
		(width 0.14605)
		(layer "F.Cu")
		(net "PCIE_IOM_TO_COMP_17_DP")
	)
	(segment
		(start 81.355946 -75.59421)
		(end 83.091528 -75.59421)
		(width 0.14605)
		(layer "F.Cu")
		(net "PCIE_IOM_TO_COMP_17_DP")
	)
	(segment
		(start 81.111344 -75.350116)
		(end 81.111598 -75.349862)
		(width 0.14605)
		(layer "F.Cu")
		(net "PCIE_IOM_TO_COMP_17_DP")
	)
	(segment
		(start 83.358228 -75.32751)
		(end 83.358228 -75.305158)
		(width 0.14605)
		(layer "F.Cu")
		(net "PCIE_IOM_TO_COMP_17_DP")
	)
	(segment
		(start 81.111598 -75.349862)
		(end 81.355946 -75.59421)
		(width 0.14605)
		(layer "F.Cu")
		(net "PCIE_IOM_TO_COMP_17_DP")
	)
	(arc
		(start 83.091528 -75.59421)
		(mid 83.280113 -75.516095)
		(end 83.358228 -75.32751)
		(width 0.14605)
		(layer "F.Cu")
		(net "PCIE_IOM_TO_COMP_17_DP")
	)
	(segment
		(start 91.02217 -62.723268)
		(end 88.956388 -73.061576)
		(width 0.1397)
		(layer "In5.Cu")
		(net "PCIE_IOM_TO_COMP_17_DP")
	)
	(segment
		(start 91.60764 -36.395406)
		(end 89.765886 -45.604176)
		(width 0.1397)
		(layer "In5.Cu")
		(net "PCIE_IOM_TO_COMP_17_DP")
	)
	(segment
		(start 88.19261 -74.205338)
		(end 87.07755 -75.320398)
		(width 0.1397)
		(layer "In5.Cu")
		(net "PCIE_IOM_TO_COMP_17_DP")
	)
	(segment
		(start 89.765886 -45.604176)
		(end 90.427302 -49.006506)
		(width 0.1397)
		(layer "In5.Cu")
		(net "PCIE_IOM_TO_COMP_17_DP")
	)
	(segment
		(start 117.899942 -36.800028)
		(end 117.899942 -37.146992)
		(width 0.1397)
		(layer "In5.Cu")
		(net "PCIE_IOM_TO_COMP_17_DP")
	)
	(segment
		(start 90.162888 -50.365914)
		(end 91.15933 -55.493158)
		(width 0.1397)
		(layer "In5.Cu")
		(net "PCIE_IOM_TO_COMP_17_DP")
	)
	(segment
		(start 117.711982 -37.334952)
		(end 117.534182 -37.334952)
		(width 0.1397)
		(layer "In5.Cu")
		(net "PCIE_IOM_TO_COMP_17_DP")
	)
	(segment
		(start 90.38209 -59.49315)
		(end 91.02217 -62.723268)
		(width 0.1397)
		(layer "In5.Cu")
		(net "PCIE_IOM_TO_COMP_17_DP")
	)
	(segment
		(start 113.373916 -26.62301)
		(end 104.194864 -26.62301)
		(width 0.1397)
		(layer "In5.Cu")
		(net "PCIE_IOM_TO_COMP_17_DP")
	)
	(segment
		(start 117.16512 -36.96589)
		(end 117.16512 -30.414214)
		(width 0.1397)
		(layer "In5.Cu")
		(net "PCIE_IOM_TO_COMP_17_DP")
	)
	(segment
		(start 117.16512 -30.414214)
		(end 113.373916 -26.62301)
		(width 0.1397)
		(layer "In5.Cu")
		(net "PCIE_IOM_TO_COMP_17_DP")
	)
	(segment
		(start 93.339158 -33.805622)
		(end 91.60764 -36.395406)
		(width 0.1397)
		(layer "In5.Cu")
		(net "PCIE_IOM_TO_COMP_17_DP")
	)
	(segment
		(start 104.194864 -26.62301)
		(end 93.339158 -33.805622)
		(width 0.1397)
		(layer "In5.Cu")
		(net "PCIE_IOM_TO_COMP_17_DP")
	)
	(segment
		(start 91.15933 -55.493158)
		(end 90.38209 -59.49315)
		(width 0.1397)
		(layer "In5.Cu")
		(net "PCIE_IOM_TO_COMP_17_DP")
	)
	(segment
		(start 86.44001 -75.584558)
		(end 83.637628 -75.584558)
		(width 0.1397)
		(layer "In5.Cu")
		(net "PCIE_IOM_TO_COMP_17_DP")
	)
	(segment
		(start 88.956388 -73.061576)
		(end 88.19261 -74.205338)
		(width 0.1397)
		(layer "In5.Cu")
		(net "PCIE_IOM_TO_COMP_17_DP")
	)
	(segment
		(start 90.427302 -49.006506)
		(end 90.162888 -50.365914)
		(width 0.1397)
		(layer "In5.Cu")
		(net "PCIE_IOM_TO_COMP_17_DP")
	)
	(arc
		(start 117.534182 -37.334952)
		(mid 117.273216 -37.226856)
		(end 117.16512 -36.96589)
		(width 0.1397)
		(layer "In5.Cu")
		(net "PCIE_IOM_TO_COMP_17_DP")
	)
	(arc
		(start 83.637628 -75.584558)
		(mid 83.440062 -75.502724)
		(end 83.358228 -75.305158)
		(width 0.1397)
		(layer "In5.Cu")
		(net "PCIE_IOM_TO_COMP_17_DP")
	)
	(arc
		(start 87.07755 -75.320398)
		(mid 86.785059 -75.515927)
		(end 86.44001 -75.584558)
		(width 0.1397)
		(layer "In5.Cu")
		(net "PCIE_IOM_TO_COMP_17_DP")
	)
	(arc
		(start 117.899942 -37.146992)
		(mid 117.84489 -37.2799)
		(end 117.711982 -37.334952)
		(width 0.1397)
		(layer "In5.Cu")
		(net "PCIE_IOM_TO_COMP_17_DP")
	)
	(segment
		(start 81.355946 -75.90536)
		(end 83.091528 -75.90536)
		(width 0.14605)
		(layer "F.Cu")
		(net "PCIE_IOM_TO_COMP_17_DN")
	)
	(segment
		(start 79.925164 -76.149962)
		(end 81.111344 -76.149962)
		(width 0.14605)
		(layer "F.Cu")
		(net "PCIE_IOM_TO_COMP_17_DN")
	)
	(segment
		(start 83.358228 -76.17206)
		(end 83.358228 -76.194158)
		(width 0.14605)
		(layer "F.Cu")
		(net "PCIE_IOM_TO_COMP_17_DN")
	)
	(segment
		(start 81.111344 -76.149962)
		(end 81.355946 -75.90536)
		(width 0.14605)
		(layer "F.Cu")
		(net "PCIE_IOM_TO_COMP_17_DN")
	)
	(arc
		(start 83.091528 -75.90536)
		(mid 83.280113 -75.983475)
		(end 83.358228 -76.17206)
		(width 0.14605)
		(layer "F.Cu")
		(net "PCIE_IOM_TO_COMP_17_DN")
	)
	(segment
		(start 90.499438 -50.365914)
		(end 91.49588 -55.493158)
		(width 0.1397)
		(layer "In5.Cu")
		(net "PCIE_IOM_TO_COMP_17_DN")
	)
	(segment
		(start 117.899942 -38.200076)
		(end 117.899942 -37.853112)
		(width 0.1397)
		(layer "In5.Cu")
		(net "PCIE_IOM_TO_COMP_17_DN")
	)
	(segment
		(start 90.763852 -49.006506)
		(end 90.499438 -50.365914)
		(width 0.1397)
		(layer "In5.Cu")
		(net "PCIE_IOM_TO_COMP_17_DN")
	)
	(segment
		(start 91.49588 -55.493158)
		(end 90.71864 -59.492642)
		(width 0.1397)
		(layer "In5.Cu")
		(net "PCIE_IOM_TO_COMP_17_DN")
	)
	(segment
		(start 93.576902 -34.044636)
		(end 91.91879 -36.524438)
		(width 0.1397)
		(layer "In5.Cu")
		(net "PCIE_IOM_TO_COMP_17_DN")
	)
	(segment
		(start 116.83492 -30.55112)
		(end 113.23701 -26.95321)
		(width 0.1397)
		(layer "In5.Cu")
		(net "PCIE_IOM_TO_COMP_17_DN")
	)
	(segment
		(start 91.358974 -62.723522)
		(end 89.267538 -73.190608)
		(width 0.1397)
		(layer "In5.Cu")
		(net "PCIE_IOM_TO_COMP_17_DN")
	)
	(segment
		(start 116.83492 -36.96589)
		(end 116.83492 -30.55112)
		(width 0.1397)
		(layer "In5.Cu")
		(net "PCIE_IOM_TO_COMP_17_DN")
	)
	(segment
		(start 91.91879 -36.524438)
		(end 90.10269 -45.605192)
		(width 0.1397)
		(layer "In5.Cu")
		(net "PCIE_IOM_TO_COMP_17_DN")
	)
	(segment
		(start 87.310976 -75.554078)
		(end 87.310976 -75.554332)
		(width 0.1397)
		(layer "In5.Cu")
		(net "PCIE_IOM_TO_COMP_17_DN")
	)
	(segment
		(start 113.23701 -26.95321)
		(end 104.294432 -26.95321)
		(width 0.1397)
		(layer "In5.Cu")
		(net "PCIE_IOM_TO_COMP_17_DN")
	)
	(segment
		(start 88.44915 -74.415904)
		(end 87.310976 -75.554078)
		(width 0.1397)
		(layer "In5.Cu")
		(net "PCIE_IOM_TO_COMP_17_DN")
	)
	(segment
		(start 117.711982 -37.665152)
		(end 117.534182 -37.665152)
		(width 0.1397)
		(layer "In5.Cu")
		(net "PCIE_IOM_TO_COMP_17_DN")
	)
	(segment
		(start 89.267538 -73.190608)
		(end 88.44915 -74.415904)
		(width 0.1397)
		(layer "In5.Cu")
		(net "PCIE_IOM_TO_COMP_17_DN")
	)
	(segment
		(start 90.71864 -59.492642)
		(end 91.358974 -62.723522)
		(width 0.1397)
		(layer "In5.Cu")
		(net "PCIE_IOM_TO_COMP_17_DN")
	)
	(segment
		(start 90.10269 -45.605192)
		(end 90.763852 -49.006506)
		(width 0.1397)
		(layer "In5.Cu")
		(net "PCIE_IOM_TO_COMP_17_DN")
	)
	(segment
		(start 104.294432 -26.95321)
		(end 93.576902 -34.044636)
		(width 0.1397)
		(layer "In5.Cu")
		(net "PCIE_IOM_TO_COMP_17_DN")
	)
	(segment
		(start 86.44001 -75.914758)
		(end 83.637628 -75.914758)
		(width 0.1397)
		(layer "In5.Cu")
		(net "PCIE_IOM_TO_COMP_17_DN")
	)
	(arc
		(start 83.637628 -75.914758)
		(mid 83.440062 -75.996592)
		(end 83.358228 -76.194158)
		(width 0.1397)
		(layer "In5.Cu")
		(net "PCIE_IOM_TO_COMP_17_DN")
	)
	(arc
		(start 117.899942 -37.853112)
		(mid 117.84489 -37.720204)
		(end 117.711982 -37.665152)
		(width 0.1397)
		(layer "In5.Cu")
		(net "PCIE_IOM_TO_COMP_17_DN")
	)
	(arc
		(start 117.534182 -37.665152)
		(mid 117.039729 -37.460343)
		(end 116.83492 -36.96589)
		(width 0.1397)
		(layer "In5.Cu")
		(net "PCIE_IOM_TO_COMP_17_DN")
	)
	(arc
		(start 87.310976 -75.554332)
		(mid 86.911316 -75.821094)
		(end 86.44001 -75.914758)
		(width 0.1397)
		(layer "In5.Cu")
		(net "PCIE_IOM_TO_COMP_17_DN")
	)
	(segment
		(start 79.925164 -72.14997)
		(end 81.11109 -72.14997)
		(width 0.14605)
		(layer "F.Cu")
		(net "PCIE_IOM_TO_COMP_16_DP")
	)
	(segment
		(start 84.983828 -72.115172)
		(end 84.983828 -72.081136)
		(width 0.14605)
		(layer "F.Cu")
		(net "PCIE_IOM_TO_COMP_16_DP")
	)
	(segment
		(start 81.11109 -72.14997)
		(end 81.355692 -72.394572)
		(width 0.14605)
		(layer "F.Cu")
		(net "PCIE_IOM_TO_COMP_16_DP")
	)
	(segment
		(start 81.355692 -72.394572)
		(end 84.704428 -72.394572)
		(width 0.14605)
		(layer "F.Cu")
		(net "PCIE_IOM_TO_COMP_16_DP")
	)
	(arc
		(start 84.704428 -72.394572)
		(mid 84.901994 -72.312738)
		(end 84.983828 -72.115172)
		(width 0.14605)
		(layer "F.Cu")
		(net "PCIE_IOM_TO_COMP_16_DP")
	)
	(segment
		(start 90.685874 -36.106354)
		(end 88.803988 -45.525944)
		(width 0.1397)
		(layer "In5.Cu")
		(net "PCIE_IOM_TO_COMP_16_DP")
	)
	(segment
		(start 89.014808 -50.70729)
		(end 90.014806 -55.856124)
		(width 0.1397)
		(layer "In5.Cu")
		(net "PCIE_IOM_TO_COMP_16_DP")
	)
	(segment
		(start 89.413334 -48.658272)
		(end 89.014808 -50.70729)
		(width 0.1397)
		(layer "In5.Cu")
		(net "PCIE_IOM_TO_COMP_16_DP")
	)
	(segment
		(start 91.783408 -34.466022)
		(end 90.685874 -36.106354)
		(width 0.1397)
		(layer "In5.Cu")
		(net "PCIE_IOM_TO_COMP_16_DP")
	)
	(segment
		(start 90.014806 -55.856124)
		(end 89.243662 -59.826144)
		(width 0.1397)
		(layer "In5.Cu")
		(net "PCIE_IOM_TO_COMP_16_DP")
	)
	(segment
		(start 119.51208 -36.135056)
		(end 119.33428 -36.135056)
		(width 0.1397)
		(layer "In5.Cu")
		(net "PCIE_IOM_TO_COMP_16_DP")
	)
	(segment
		(start 92.880942 -32.824928)
		(end 91.783408 -34.466022)
		(width 0.1397)
		(layer "In5.Cu")
		(net "PCIE_IOM_TO_COMP_16_DP")
	)
	(segment
		(start 88.397588 -71.217536)
		(end 88.062816 -71.719948)
		(width 0.1397)
		(layer "In5.Cu")
		(net "PCIE_IOM_TO_COMP_16_DP")
	)
	(segment
		(start 103.434642 -25.842722)
		(end 92.880942 -32.824928)
		(width 0.1397)
		(layer "In5.Cu")
		(net "PCIE_IOM_TO_COMP_16_DP")
	)
	(segment
		(start 113.761774 -25.842722)
		(end 103.434642 -25.842722)
		(width 0.1397)
		(layer "In5.Cu")
		(net "PCIE_IOM_TO_COMP_16_DP")
	)
	(segment
		(start 88.803988 -45.525944)
		(end 89.413334 -48.658272)
		(width 0.1397)
		(layer "In5.Cu")
		(net "PCIE_IOM_TO_COMP_16_DP")
	)
	(segment
		(start 88.062816 -71.719948)
		(end 87.615268 -72.167496)
		(width 0.1397)
		(layer "In5.Cu")
		(net "PCIE_IOM_TO_COMP_16_DP")
	)
	(segment
		(start 89.243662 -59.826144)
		(end 89.956386 -63.425324)
		(width 0.1397)
		(layer "In5.Cu")
		(net "PCIE_IOM_TO_COMP_16_DP")
	)
	(segment
		(start 119.70004 -35.600132)
		(end 119.70004 -35.947096)
		(width 0.1397)
		(layer "In5.Cu")
		(net "PCIE_IOM_TO_COMP_16_DP")
	)
	(segment
		(start 87.14994 -72.360536)
		(end 85.263228 -72.360536)
		(width 0.1397)
		(layer "In5.Cu")
		(net "PCIE_IOM_TO_COMP_16_DP")
	)
	(segment
		(start 118.965218 -31.046166)
		(end 113.761774 -25.842722)
		(width 0.1397)
		(layer "In5.Cu")
		(net "PCIE_IOM_TO_COMP_16_DP")
	)
	(segment
		(start 89.956386 -63.425324)
		(end 88.397588 -71.217536)
		(width 0.1397)
		(layer "In5.Cu")
		(net "PCIE_IOM_TO_COMP_16_DP")
	)
	(segment
		(start 118.965218 -35.765994)
		(end 118.965218 -31.046166)
		(width 0.1397)
		(layer "In5.Cu")
		(net "PCIE_IOM_TO_COMP_16_DP")
	)
	(arc
		(start 85.263228 -72.360536)
		(mid 85.065662 -72.278702)
		(end 84.983828 -72.081136)
		(width 0.1397)
		(layer "In5.Cu")
		(net "PCIE_IOM_TO_COMP_16_DP")
	)
	(arc
		(start 119.70004 -35.947096)
		(mid 119.644988 -36.080004)
		(end 119.51208 -36.135056)
		(width 0.1397)
		(layer "In5.Cu")
		(net "PCIE_IOM_TO_COMP_16_DP")
	)
	(arc
		(start 119.33428 -36.135056)
		(mid 119.073314 -36.02696)
		(end 118.965218 -35.765994)
		(width 0.1397)
		(layer "In5.Cu")
		(net "PCIE_IOM_TO_COMP_16_DP")
	)
	(arc
		(start 87.615268 -72.167496)
		(mid 87.401803 -72.310285)
		(end 87.14994 -72.360536)
		(width 0.1397)
		(layer "In5.Cu")
		(net "PCIE_IOM_TO_COMP_16_DP")
	)
	(segment
		(start 79.925164 -72.95007)
		(end 81.111344 -72.95007)
		(width 0.14605)
		(layer "F.Cu")
		(net "PCIE_IOM_TO_COMP_16_DN")
	)
	(segment
		(start 81.355692 -72.705722)
		(end 84.719414 -72.705722)
		(width 0.14605)
		(layer "F.Cu")
		(net "PCIE_IOM_TO_COMP_16_DN")
	)
	(segment
		(start 81.111344 -72.95007)
		(end 81.355692 -72.705722)
		(width 0.14605)
		(layer "F.Cu")
		(net "PCIE_IOM_TO_COMP_16_DN")
	)
	(arc
		(start 84.719414 -72.705722)
		(mid 84.906383 -72.783167)
		(end 84.983828 -72.970136)
		(width 0.14605)
		(layer "F.Cu")
		(net "PCIE_IOM_TO_COMP_16_DN")
	)
	(segment
		(start 89.580212 -59.825636)
		(end 90.29319 -63.425578)
		(width 0.1397)
		(layer "In5.Cu")
		(net "PCIE_IOM_TO_COMP_16_DN")
	)
	(segment
		(start 88.708738 -71.346314)
		(end 88.708992 -71.346568)
		(width 0.1397)
		(layer "In5.Cu")
		(net "PCIE_IOM_TO_COMP_16_DN")
	)
	(segment
		(start 88.31961 -71.930514)
		(end 87.848948 -72.401176)
		(width 0.1397)
		(layer "In5.Cu")
		(net "PCIE_IOM_TO_COMP_16_DN")
	)
	(segment
		(start 90.29319 -63.425578)
		(end 88.708738 -71.346314)
		(width 0.1397)
		(layer "In5.Cu")
		(net "PCIE_IOM_TO_COMP_16_DN")
	)
	(segment
		(start 119.70004 -37.00018)
		(end 119.70004 -36.653216)
		(width 0.1397)
		(layer "In5.Cu")
		(net "PCIE_IOM_TO_COMP_16_DN")
	)
	(segment
		(start 87.14994 -72.690736)
		(end 85.263228 -72.690736)
		(width 0.1397)
		(layer "In5.Cu")
		(net "PCIE_IOM_TO_COMP_16_DN")
	)
	(segment
		(start 118.635018 -35.765994)
		(end 118.635018 -31.183072)
		(width 0.1397)
		(layer "In5.Cu")
		(net "PCIE_IOM_TO_COMP_16_DN")
	)
	(segment
		(start 119.51208 -36.465256)
		(end 119.33428 -36.465256)
		(width 0.1397)
		(layer "In5.Cu")
		(net "PCIE_IOM_TO_COMP_16_DN")
	)
	(segment
		(start 103.53421 -26.172922)
		(end 93.118686 -33.063942)
		(width 0.1397)
		(layer "In5.Cu")
		(net "PCIE_IOM_TO_COMP_16_DN")
	)
	(segment
		(start 90.997024 -36.235386)
		(end 89.140792 -45.526706)
		(width 0.1397)
		(layer "In5.Cu")
		(net "PCIE_IOM_TO_COMP_16_DN")
	)
	(segment
		(start 89.140792 -45.526706)
		(end 89.749884 -48.658272)
		(width 0.1397)
		(layer "In5.Cu")
		(net "PCIE_IOM_TO_COMP_16_DN")
	)
	(segment
		(start 89.749884 -48.658272)
		(end 89.351358 -50.70729)
		(width 0.1397)
		(layer "In5.Cu")
		(net "PCIE_IOM_TO_COMP_16_DN")
	)
	(segment
		(start 88.708992 -71.346568)
		(end 88.31961 -71.930514)
		(width 0.1397)
		(layer "In5.Cu")
		(net "PCIE_IOM_TO_COMP_16_DN")
	)
	(segment
		(start 113.624868 -26.172922)
		(end 103.53421 -26.172922)
		(width 0.1397)
		(layer "In5.Cu")
		(net "PCIE_IOM_TO_COMP_16_DN")
	)
	(segment
		(start 118.635018 -31.183072)
		(end 113.624868 -26.172922)
		(width 0.1397)
		(layer "In5.Cu")
		(net "PCIE_IOM_TO_COMP_16_DN")
	)
	(segment
		(start 89.351358 -50.70729)
		(end 90.351356 -55.856124)
		(width 0.1397)
		(layer "In5.Cu")
		(net "PCIE_IOM_TO_COMP_16_DN")
	)
	(segment
		(start 90.351356 -55.856124)
		(end 89.580212 -59.825636)
		(width 0.1397)
		(layer "In5.Cu")
		(net "PCIE_IOM_TO_COMP_16_DN")
	)
	(segment
		(start 93.118686 -33.063942)
		(end 90.997024 -36.235386)
		(width 0.1397)
		(layer "In5.Cu")
		(net "PCIE_IOM_TO_COMP_16_DN")
	)
	(arc
		(start 119.33428 -36.465256)
		(mid 118.839827 -36.260447)
		(end 118.635018 -35.765994)
		(width 0.1397)
		(layer "In5.Cu")
		(net "PCIE_IOM_TO_COMP_16_DN")
	)
	(arc
		(start 85.263228 -72.690736)
		(mid 85.065662 -72.77257)
		(end 84.983828 -72.970136)
		(width 0.1397)
		(layer "In5.Cu")
		(net "PCIE_IOM_TO_COMP_16_DN")
	)
	(arc
		(start 87.848948 -72.401176)
		(mid 87.52824 -72.615466)
		(end 87.14994 -72.690736)
		(width 0.1397)
		(layer "In5.Cu")
		(net "PCIE_IOM_TO_COMP_16_DN")
	)
	(arc
		(start 119.70004 -36.653216)
		(mid 119.644988 -36.520308)
		(end 119.51208 -36.465256)
		(width 0.1397)
		(layer "In5.Cu")
		(net "PCIE_IOM_TO_COMP_16_DN")
	)
	(segment
		(start 191.600074 -74.299826)
		(end 191.99987 -74.699622)
		(width 0.09525)
		(layer "F.Cu")
		(net "PCIE_IOM_TO_COMP_15_DP_C")
	)
	(via
		(at 191.99987 -74.699622)
		(size 0.4572)
		(drill 0.2032)
		(layers "F.Cu" "B.Cu")
		(net "PCIE_IOM_TO_COMP_15_DP_C")
	)
	(segment
		(start 189.19317 -79.28483)
		(end 188.400436 -80.077564)
		(width 0.14605)
		(layer "B.Cu")
		(net "PCIE_IOM_TO_COMP_15_DP_C")
	)
	(segment
		(start 191.61379 -77.21981)
		(end 189.54877 -79.28483)
		(width 0.14605)
		(layer "B.Cu")
		(net "PCIE_IOM_TO_COMP_15_DP_C")
	)
	(segment
		(start 191.55029 -75.763628)
		(end 191.61379 -75.827128)
		(width 0.09525)
		(layer "B.Cu")
		(net "PCIE_IOM_TO_COMP_15_DP_C")
	)
	(segment
		(start 191.324738 -74.865738)
		(end 191.55029 -75.09129)
		(width 0.09525)
		(layer "B.Cu")
		(net "PCIE_IOM_TO_COMP_15_DP_C")
	)
	(segment
		(start 191.99987 -74.699622)
		(end 191.99987 -74.534268)
		(width 0.09525)
		(layer "B.Cu")
		(net "PCIE_IOM_TO_COMP_15_DP_C")
	)
	(segment
		(start 188.400436 -80.077564)
		(end 188.400436 -80.725518)
		(width 0.14605)
		(layer "B.Cu")
		(net "PCIE_IOM_TO_COMP_15_DP_C")
	)
	(segment
		(start 189.54877 -79.28483)
		(end 189.19317 -79.28483)
		(width 0.14605)
		(layer "B.Cu")
		(net "PCIE_IOM_TO_COMP_15_DP_C")
	)
	(segment
		(start 191.97193 -74.466704)
		(end 191.948308 -74.443336)
		(width 0.09525)
		(layer "B.Cu")
		(net "PCIE_IOM_TO_COMP_15_DP_C")
	)
	(segment
		(start 191.419226 -74.391774)
		(end 191.324738 -74.486262)
		(width 0.09525)
		(layer "B.Cu")
		(net "PCIE_IOM_TO_COMP_15_DP_C")
	)
	(segment
		(start 188.400436 -80.725518)
		(end 188.548518 -80.8736)
		(width 0.14605)
		(layer "B.Cu")
		(net "PCIE_IOM_TO_COMP_15_DP_C")
	)
	(segment
		(start 191.61379 -75.85075)
		(end 191.61379 -77.21981)
		(width 0.14605)
		(layer "B.Cu")
		(net "PCIE_IOM_TO_COMP_15_DP_C")
	)
	(segment
		(start 191.61379 -75.827128)
		(end 191.61379 -75.85075)
		(width 0.09525)
		(layer "B.Cu")
		(net "PCIE_IOM_TO_COMP_15_DP_C")
	)
	(segment
		(start 191.824356 -74.391774)
		(end 191.419226 -74.391774)
		(width 0.09525)
		(layer "B.Cu")
		(net "PCIE_IOM_TO_COMP_15_DP_C")
	)
	(segment
		(start 191.324738 -74.486262)
		(end 191.324738 -74.865738)
		(width 0.09525)
		(layer "B.Cu")
		(net "PCIE_IOM_TO_COMP_15_DP_C")
	)
	(segment
		(start 191.55029 -75.09129)
		(end 191.55029 -75.763628)
		(width 0.09525)
		(layer "B.Cu")
		(net "PCIE_IOM_TO_COMP_15_DP_C")
	)
	(arc
		(start 191.948308 -74.443336)
		(mid 191.891453 -74.405254)
		(end 191.824356 -74.391774)
		(width 0.09525)
		(layer "B.Cu")
		(net "PCIE_IOM_TO_COMP_15_DP_C")
	)
	(arc
		(start 191.99987 -74.534268)
		(mid 191.992668 -74.497681)
		(end 191.97193 -74.466704)
		(width 0.09525)
		(layer "B.Cu")
		(net "PCIE_IOM_TO_COMP_15_DP_C")
	)
	(segment
		(start 128.246124 -37.34435)
		(end 128.474216 -37.34435)
		(width 0.14605)
		(layer "B.Cu")
		(net "PCIE_IOM_TO_COMP_15_DP")
	)
	(segment
		(start 154.276806 -58.847736)
		(end 154.362404 -58.417968)
		(width 0.14605)
		(layer "B.Cu")
		(net "PCIE_IOM_TO_COMP_15_DP")
	)
	(segment
		(start 155.933394 -50.536602)
		(end 155.81376 -50.357278)
		(width 0.14605)
		(layer "B.Cu")
		(net "PCIE_IOM_TO_COMP_15_DP")
	)
	(segment
		(start 154.097482 -58.96737)
		(end 154.276806 -58.847736)
		(width 0.14605)
		(layer "B.Cu")
		(net "PCIE_IOM_TO_COMP_15_DP")
	)
	(segment
		(start 154.011884 -59.397138)
		(end 154.097482 -58.96737)
		(width 0.14605)
		(layer "B.Cu")
		(net "PCIE_IOM_TO_COMP_15_DP")
	)
	(segment
		(start 156.626052 -47.061628)
		(end 153.148538 -29.67609)
		(width 0.14605)
		(layer "B.Cu")
		(net "PCIE_IOM_TO_COMP_15_DP")
	)
	(segment
		(start 157.085538 -73.824592)
		(end 156.588968 -73.088754)
		(width 0.14605)
		(layer "B.Cu")
		(net "PCIE_IOM_TO_COMP_15_DP")
	)
	(segment
		(start 155.899358 -49.92751)
		(end 156.078682 -49.807876)
		(width 0.14605)
		(layer "B.Cu")
		(net "PCIE_IOM_TO_COMP_15_DP")
	)
	(segment
		(start 153.148538 -29.67609)
		(end 149.691344 -24.490172)
		(width 0.14605)
		(layer "B.Cu")
		(net "PCIE_IOM_TO_COMP_15_DP")
	)
	(segment
		(start 154.131518 -59.576208)
		(end 154.011884 -59.397138)
		(width 0.14605)
		(layer "B.Cu")
		(net "PCIE_IOM_TO_COMP_15_DP")
	)
	(segment
		(start 154.559254 -56.650636)
		(end 154.738578 -56.531002)
		(width 0.14605)
		(layer "B.Cu")
		(net "PCIE_IOM_TO_COMP_15_DP")
	)
	(segment
		(start 156.395166 -48.219868)
		(end 156.275532 -48.040798)
		(width 0.14605)
		(layer "B.Cu")
		(net "PCIE_IOM_TO_COMP_15_DP")
	)
	(segment
		(start 156.36113 -47.61103)
		(end 156.540454 -47.491396)
		(width 0.14605)
		(layer "B.Cu")
		(net "PCIE_IOM_TO_COMP_15_DP")
	)
	(segment
		(start 155.668472 -51.086004)
		(end 155.847796 -50.96637)
		(width 0.14605)
		(layer "B.Cu")
		(net "PCIE_IOM_TO_COMP_15_DP")
	)
	(segment
		(start 154.04592 -60.005976)
		(end 154.131518 -59.576208)
		(width 0.14605)
		(layer "B.Cu")
		(net "PCIE_IOM_TO_COMP_15_DP")
	)
	(segment
		(start 156.540454 -47.491396)
		(end 156.626052 -47.061628)
		(width 0.14605)
		(layer "B.Cu")
		(net "PCIE_IOM_TO_COMP_15_DP")
	)
	(segment
		(start 154.362404 -58.417968)
		(end 154.24277 -58.238644)
		(width 0.14605)
		(layer "B.Cu")
		(net "PCIE_IOM_TO_COMP_15_DP")
	)
	(segment
		(start 188.548518 -81.4324)
		(end 188.428122 -81.552796)
		(width 0.14605)
		(layer "B.Cu")
		(net "PCIE_IOM_TO_COMP_15_DP")
	)
	(segment
		(start 155.847796 -50.96637)
		(end 155.933394 -50.536602)
		(width 0.14605)
		(layer "B.Cu")
		(net "PCIE_IOM_TO_COMP_15_DP")
	)
	(segment
		(start 156.044646 -49.199038)
		(end 156.130244 -48.76927)
		(width 0.14605)
		(layer "B.Cu")
		(net "PCIE_IOM_TO_COMP_15_DP")
	)
	(segment
		(start 154.59329 -57.259474)
		(end 154.473656 -57.080404)
		(width 0.14605)
		(layer "B.Cu")
		(net "PCIE_IOM_TO_COMP_15_DP")
	)
	(segment
		(start 180.549042 -85.477604)
		(end 171.997878 -83.766914)
		(width 0.14605)
		(layer "B.Cu")
		(net "PCIE_IOM_TO_COMP_15_DP")
	)
	(segment
		(start 127.955548 -30.02534)
		(end 127.955548 -37.053774)
		(width 0.14605)
		(layer "B.Cu")
		(net "PCIE_IOM_TO_COMP_15_DP")
	)
	(segment
		(start 156.078682 -49.807876)
		(end 156.16428 -49.378362)
		(width 0.14605)
		(layer "B.Cu")
		(net "PCIE_IOM_TO_COMP_15_DP")
	)
	(segment
		(start 154.328368 -57.80913)
		(end 154.507692 -57.689242)
		(width 0.14605)
		(layer "B.Cu")
		(net "PCIE_IOM_TO_COMP_15_DP")
	)
	(segment
		(start 156.588968 -73.088754)
		(end 154.04592 -60.005976)
		(width 0.14605)
		(layer "B.Cu")
		(net "PCIE_IOM_TO_COMP_15_DP")
	)
	(segment
		(start 188.428122 -81.552796)
		(end 188.428122 -82.229452)
		(width 0.14605)
		(layer "B.Cu")
		(net "PCIE_IOM_TO_COMP_15_DP")
	)
	(segment
		(start 146.188684 -22.15515)
		(end 144.015968 -22.15515)
		(width 0.14605)
		(layer "B.Cu")
		(net "PCIE_IOM_TO_COMP_15_DP")
	)
	(segment
		(start 156.275532 -48.040798)
		(end 156.36113 -47.61103)
		(width 0.14605)
		(layer "B.Cu")
		(net "PCIE_IOM_TO_COMP_15_DP")
	)
	(segment
		(start 187.48756 -83.170014)
		(end 185.516012 -84.484464)
		(width 0.14605)
		(layer "B.Cu")
		(net "PCIE_IOM_TO_COMP_15_DP")
	)
	(segment
		(start 185.516012 -84.484464)
		(end 180.549042 -85.477604)
		(width 0.14605)
		(layer "B.Cu")
		(net "PCIE_IOM_TO_COMP_15_DP")
	)
	(segment
		(start 141.54531 -21.8694)
		(end 141.19352 -22.22119)
		(width 0.14605)
		(layer "B.Cu")
		(net "PCIE_IOM_TO_COMP_15_DP")
	)
	(segment
		(start 149.691344 -24.490172)
		(end 146.188684 -22.15515)
		(width 0.14605)
		(layer "B.Cu")
		(net "PCIE_IOM_TO_COMP_15_DP")
	)
	(segment
		(start 155.702508 -51.694842)
		(end 155.582874 -51.515518)
		(width 0.14605)
		(layer "B.Cu")
		(net "PCIE_IOM_TO_COMP_15_DP")
	)
	(segment
		(start 171.997878 -83.766914)
		(end 157.085538 -73.824592)
		(width 0.14605)
		(layer "B.Cu")
		(net "PCIE_IOM_TO_COMP_15_DP")
	)
	(segment
		(start 128.700022 -37.11829)
		(end 128.700022 -36.800028)
		(width 0.14605)
		(layer "B.Cu")
		(net "PCIE_IOM_TO_COMP_15_DP")
	)
	(segment
		(start 135.759698 -22.22119)
		(end 127.955548 -30.02534)
		(width 0.14605)
		(layer "B.Cu")
		(net "PCIE_IOM_TO_COMP_15_DP")
	)
	(segment
		(start 156.16428 -49.378362)
		(end 156.044646 -49.199038)
		(width 0.14605)
		(layer "B.Cu")
		(net "PCIE_IOM_TO_COMP_15_DP")
	)
	(segment
		(start 141.19352 -22.22119)
		(end 135.759698 -22.22119)
		(width 0.14605)
		(layer "B.Cu")
		(net "PCIE_IOM_TO_COMP_15_DP")
	)
	(segment
		(start 154.473656 -57.080404)
		(end 154.559254 -56.650636)
		(width 0.14605)
		(layer "B.Cu")
		(net "PCIE_IOM_TO_COMP_15_DP")
	)
	(segment
		(start 188.428122 -82.229452)
		(end 187.48756 -83.170014)
		(width 0.14605)
		(layer "B.Cu")
		(net "PCIE_IOM_TO_COMP_15_DP")
	)
	(segment
		(start 154.738578 -56.531002)
		(end 155.702508 -51.694842)
		(width 0.14605)
		(layer "B.Cu")
		(net "PCIE_IOM_TO_COMP_15_DP")
	)
	(segment
		(start 144.015968 -22.15515)
		(end 143.730218 -21.8694)
		(width 0.14605)
		(layer "B.Cu")
		(net "PCIE_IOM_TO_COMP_15_DP")
	)
	(segment
		(start 154.24277 -58.238644)
		(end 154.328368 -57.80913)
		(width 0.14605)
		(layer "B.Cu")
		(net "PCIE_IOM_TO_COMP_15_DP")
	)
	(segment
		(start 156.309568 -48.649636)
		(end 156.395166 -48.219868)
		(width 0.14605)
		(layer "B.Cu")
		(net "PCIE_IOM_TO_COMP_15_DP")
	)
	(segment
		(start 155.81376 -50.357278)
		(end 155.899358 -49.92751)
		(width 0.14605)
		(layer "B.Cu")
		(net "PCIE_IOM_TO_COMP_15_DP")
	)
	(segment
		(start 156.130244 -48.76927)
		(end 156.309568 -48.649636)
		(width 0.14605)
		(layer "B.Cu")
		(net "PCIE_IOM_TO_COMP_15_DP")
	)
	(segment
		(start 154.507692 -57.689242)
		(end 154.59329 -57.259474)
		(width 0.14605)
		(layer "B.Cu")
		(net "PCIE_IOM_TO_COMP_15_DP")
	)
	(segment
		(start 143.730218 -21.8694)
		(end 141.54531 -21.8694)
		(width 0.14605)
		(layer "B.Cu")
		(net "PCIE_IOM_TO_COMP_15_DP")
	)
	(segment
		(start 155.582874 -51.515518)
		(end 155.668472 -51.086004)
		(width 0.14605)
		(layer "B.Cu")
		(net "PCIE_IOM_TO_COMP_15_DP")
	)
	(arc
		(start 127.955548 -37.053774)
		(mid 128.040656 -37.259242)
		(end 128.246124 -37.34435)
		(width 0.14605)
		(layer "B.Cu")
		(net "PCIE_IOM_TO_COMP_15_DP")
	)
	(arc
		(start 128.633728 -37.27831)
		(mid 128.682784 -37.204892)
		(end 128.700022 -37.11829)
		(width 0.14605)
		(layer "B.Cu")
		(net "PCIE_IOM_TO_COMP_15_DP")
	)
	(arc
		(start 128.474216 -37.34435)
		(mid 128.560531 -37.327181)
		(end 128.633728 -37.27831)
		(width 0.14605)
		(layer "B.Cu")
		(net "PCIE_IOM_TO_COMP_15_DP")
	)
	(segment
		(start 191.600074 -73.49998)
		(end 191.99987 -73.899776)
		(width 0.09525)
		(layer "F.Cu")
		(net "PCIE_IOM_TO_COMP_15_DN_C")
	)
	(via
		(at 191.99987 -73.899776)
		(size 0.4572)
		(drill 0.2032)
		(layers "F.Cu" "B.Cu")
		(net "PCIE_IOM_TO_COMP_15_DN_C")
	)
	(segment
		(start 191.843406 -74.207624)
		(end 191.342772 -74.207624)
		(width 0.09525)
		(layer "B.Cu")
		(net "PCIE_IOM_TO_COMP_15_DN_C")
	)
	(segment
		(start 188.089286 -79.948532)
		(end 188.089286 -80.774032)
		(width 0.14605)
		(layer "B.Cu")
		(net "PCIE_IOM_TO_COMP_15_DN_C")
	)
	(segment
		(start 191.140588 -74.942192)
		(end 191.36614 -75.167744)
		(width 0.09525)
		(layer "B.Cu")
		(net "PCIE_IOM_TO_COMP_15_DN_C")
	)
	(segment
		(start 191.99987 -73.899776)
		(end 191.99987 -74.076306)
		(width 0.09525)
		(layer "B.Cu")
		(net "PCIE_IOM_TO_COMP_15_DN_C")
	)
	(segment
		(start 191.36614 -75.167744)
		(end 191.36614 -75.763628)
		(width 0.09525)
		(layer "B.Cu")
		(net "PCIE_IOM_TO_COMP_15_DN_C")
	)
	(segment
		(start 188.089286 -80.774032)
		(end 187.989718 -80.8736)
		(width 0.14605)
		(layer "B.Cu")
		(net "PCIE_IOM_TO_COMP_15_DN_C")
	)
	(segment
		(start 191.36614 -75.763628)
		(end 191.30264 -75.827128)
		(width 0.09525)
		(layer "B.Cu")
		(net "PCIE_IOM_TO_COMP_15_DN_C")
	)
	(segment
		(start 189.419738 -78.97368)
		(end 189.064138 -78.97368)
		(width 0.14605)
		(layer "B.Cu")
		(net "PCIE_IOM_TO_COMP_15_DN_C")
	)
	(segment
		(start 191.30264 -77.090778)
		(end 189.419738 -78.97368)
		(width 0.14605)
		(layer "B.Cu")
		(net "PCIE_IOM_TO_COMP_15_DN_C")
	)
	(segment
		(start 191.342772 -74.207624)
		(end 191.140588 -74.409808)
		(width 0.09525)
		(layer "B.Cu")
		(net "PCIE_IOM_TO_COMP_15_DN_C")
	)
	(segment
		(start 191.30264 -75.85075)
		(end 191.30264 -77.090778)
		(width 0.14605)
		(layer "B.Cu")
		(net "PCIE_IOM_TO_COMP_15_DN_C")
	)
	(segment
		(start 191.971676 -74.14387)
		(end 191.953896 -74.16165)
		(width 0.09525)
		(layer "B.Cu")
		(net "PCIE_IOM_TO_COMP_15_DN_C")
	)
	(segment
		(start 191.140588 -74.409808)
		(end 191.140588 -74.942192)
		(width 0.09525)
		(layer "B.Cu")
		(net "PCIE_IOM_TO_COMP_15_DN_C")
	)
	(segment
		(start 191.30264 -75.827128)
		(end 191.30264 -75.85075)
		(width 0.09525)
		(layer "B.Cu")
		(net "PCIE_IOM_TO_COMP_15_DN_C")
	)
	(segment
		(start 189.064138 -78.97368)
		(end 188.089286 -79.948532)
		(width 0.14605)
		(layer "B.Cu")
		(net "PCIE_IOM_TO_COMP_15_DN_C")
	)
	(arc
		(start 191.953896 -74.16165)
		(mid 191.903218 -74.195605)
		(end 191.843406 -74.207624)
		(width 0.09525)
		(layer "B.Cu")
		(net "PCIE_IOM_TO_COMP_15_DN_C")
	)
	(arc
		(start 191.99987 -74.076306)
		(mid 191.992535 -74.112908)
		(end 191.971676 -74.14387)
		(width 0.09525)
		(layer "B.Cu")
		(net "PCIE_IOM_TO_COMP_15_DN_C")
	)
	(segment
		(start 128.700022 -37.826696)
		(end 128.700022 -38.200076)
		(width 0.14605)
		(layer "B.Cu")
		(net "PCIE_IOM_TO_COMP_15_DN")
	)
	(segment
		(start 180.549042 -85.160104)
		(end 172.11929 -83.473798)
		(width 0.14605)
		(layer "B.Cu")
		(net "PCIE_IOM_TO_COMP_15_DN")
	)
	(segment
		(start 187.289186 -82.927952)
		(end 185.3946 -84.191348)
		(width 0.14605)
		(layer "B.Cu")
		(net "PCIE_IOM_TO_COMP_15_DN")
	)
	(segment
		(start 143.85925 -21.55825)
		(end 141.416278 -21.55825)
		(width 0.14605)
		(layer "B.Cu")
		(net "PCIE_IOM_TO_COMP_15_DN")
	)
	(segment
		(start 141.416278 -21.55825)
		(end 141.064488 -21.91004)
		(width 0.14605)
		(layer "B.Cu")
		(net "PCIE_IOM_TO_COMP_15_DN")
	)
	(segment
		(start 188.116972 -82.10042)
		(end 187.289186 -82.927952)
		(width 0.14605)
		(layer "B.Cu")
		(net "PCIE_IOM_TO_COMP_15_DN")
	)
	(segment
		(start 141.064488 -21.91004)
		(end 135.630666 -21.91004)
		(width 0.14605)
		(layer "B.Cu")
		(net "PCIE_IOM_TO_COMP_15_DN")
	)
	(segment
		(start 187.989718 -81.4324)
		(end 188.116972 -81.559654)
		(width 0.14605)
		(layer "B.Cu")
		(net "PCIE_IOM_TO_COMP_15_DN")
	)
	(segment
		(start 156.882592 -72.967088)
		(end 154.363166 -60.006738)
		(width 0.14605)
		(layer "B.Cu")
		(net "PCIE_IOM_TO_COMP_15_DN")
	)
	(segment
		(start 172.11929 -83.473798)
		(end 157.309312 -73.599802)
		(width 0.14605)
		(layer "B.Cu")
		(net "PCIE_IOM_TO_COMP_15_DN")
	)
	(segment
		(start 146.282918 -21.844)
		(end 144.145 -21.844)
		(width 0.14605)
		(layer "B.Cu")
		(net "PCIE_IOM_TO_COMP_15_DN")
	)
	(segment
		(start 188.116972 -81.559654)
		(end 188.116972 -82.10042)
		(width 0.14605)
		(layer "B.Cu")
		(net "PCIE_IOM_TO_COMP_15_DN")
	)
	(segment
		(start 144.145 -21.844)
		(end 143.85925 -21.55825)
		(width 0.14605)
		(layer "B.Cu")
		(net "PCIE_IOM_TO_COMP_15_DN")
	)
	(segment
		(start 153.441654 -29.554678)
		(end 149.91588 -24.265636)
		(width 0.14605)
		(layer "B.Cu")
		(net "PCIE_IOM_TO_COMP_15_DN")
	)
	(segment
		(start 154.363166 -60.006738)
		(end 156.943552 -47.061628)
		(width 0.14605)
		(layer "B.Cu")
		(net "PCIE_IOM_TO_COMP_15_DN")
	)
	(segment
		(start 157.309312 -73.599802)
		(end 156.882592 -72.967088)
		(width 0.14605)
		(layer "B.Cu")
		(net "PCIE_IOM_TO_COMP_15_DN")
	)
	(segment
		(start 185.3946 -84.191348)
		(end 180.549042 -85.160104)
		(width 0.14605)
		(layer "B.Cu")
		(net "PCIE_IOM_TO_COMP_15_DN")
	)
	(segment
		(start 135.630666 -21.91004)
		(end 127.644398 -29.896308)
		(width 0.14605)
		(layer "B.Cu")
		(net "PCIE_IOM_TO_COMP_15_DN")
	)
	(segment
		(start 127.644398 -29.896308)
		(end 127.644398 -37.053774)
		(width 0.14605)
		(layer "B.Cu")
		(net "PCIE_IOM_TO_COMP_15_DN")
	)
	(segment
		(start 156.943552 -47.061628)
		(end 153.441654 -29.554678)
		(width 0.14605)
		(layer "B.Cu")
		(net "PCIE_IOM_TO_COMP_15_DN")
	)
	(segment
		(start 149.91588 -24.265636)
		(end 146.282918 -21.844)
		(width 0.14605)
		(layer "B.Cu")
		(net "PCIE_IOM_TO_COMP_15_DN")
	)
	(segment
		(start 128.246124 -37.6555)
		(end 128.528572 -37.6555)
		(width 0.14605)
		(layer "B.Cu")
		(net "PCIE_IOM_TO_COMP_15_DN")
	)
	(arc
		(start 127.644398 -37.053774)
		(mid 127.820639 -37.479259)
		(end 128.246124 -37.6555)
		(width 0.14605)
		(layer "B.Cu")
		(net "PCIE_IOM_TO_COMP_15_DN")
	)
	(arc
		(start 128.649984 -37.705792)
		(mid 128.686995 -37.761277)
		(end 128.700022 -37.826696)
		(width 0.14605)
		(layer "B.Cu")
		(net "PCIE_IOM_TO_COMP_15_DN")
	)
	(arc
		(start 128.528572 -37.6555)
		(mid 128.59428 -37.66857)
		(end 128.649984 -37.705792)
		(width 0.14605)
		(layer "B.Cu")
		(net "PCIE_IOM_TO_COMP_15_DN")
	)
	(segment
		(start 192.39992 -74.299826)
		(end 192.79997 -74.699876)
		(width 0.09525)
		(layer "F.Cu")
		(net "PCIE_IOM_TO_COMP_14_DP_C")
	)
	(via
		(at 192.79997 -74.699876)
		(size 0.4572)
		(drill 0.2032)
		(layers "F.Cu" "B.Cu")
		(net "PCIE_IOM_TO_COMP_14_DP_C")
	)
	(segment
		(start 192.587118 -75.031092)
		(end 192.245488 -75.544426)
		(width 0.09525)
		(layer "B.Cu")
		(net "PCIE_IOM_TO_COMP_14_DP_C")
	)
	(segment
		(start 192.245488 -77.629512)
		(end 192.034414 -77.840586)
		(width 0.09525)
		(layer "B.Cu")
		(net "PCIE_IOM_TO_COMP_14_DP_C")
	)
	(segment
		(start 192.034414 -77.840586)
		(end 192.034414 -77.930502)
		(width 0.09525)
		(layer "B.Cu")
		(net "PCIE_IOM_TO_COMP_14_DP_C")
	)
	(segment
		(start 192.01765 -77.947266)
		(end 190.079122 -79.885794)
		(width 0.14605)
		(layer "B.Cu")
		(net "PCIE_IOM_TO_COMP_14_DP_C")
	)
	(segment
		(start 192.034414 -77.930502)
		(end 192.01765 -77.947266)
		(width 0.09525)
		(layer "B.Cu")
		(net "PCIE_IOM_TO_COMP_14_DP_C")
	)
	(segment
		(start 190.079122 -80.753204)
		(end 190.199518 -80.8736)
		(width 0.14605)
		(layer "B.Cu")
		(net "PCIE_IOM_TO_COMP_14_DP_C")
	)
	(segment
		(start 192.245488 -75.544426)
		(end 192.245488 -77.629512)
		(width 0.09525)
		(layer "B.Cu")
		(net "PCIE_IOM_TO_COMP_14_DP_C")
	)
	(segment
		(start 190.079122 -79.885794)
		(end 190.079122 -80.753204)
		(width 0.14605)
		(layer "B.Cu")
		(net "PCIE_IOM_TO_COMP_14_DP_C")
	)
	(segment
		(start 192.587118 -74.912728)
		(end 192.587118 -75.031092)
		(width 0.09525)
		(layer "B.Cu")
		(net "PCIE_IOM_TO_COMP_14_DP_C")
	)
	(segment
		(start 192.79997 -74.699876)
		(end 192.587118 -74.912728)
		(width 0.09525)
		(layer "B.Cu")
		(net "PCIE_IOM_TO_COMP_14_DP_C")
	)
	(segment
		(start 152.778206 -59.666886)
		(end 152.864058 -59.237118)
		(width 0.14605)
		(layer "B.Cu")
		(net "PCIE_IOM_TO_COMP_14_DP")
	)
	(segment
		(start 154.643328 -49.56175)
		(end 154.822652 -49.442116)
		(width 0.14605)
		(layer "B.Cu")
		(net "PCIE_IOM_TO_COMP_14_DP")
	)
	(segment
		(start 154.445208 -51.328828)
		(end 154.325828 -51.149504)
		(width 0.14605)
		(layer "B.Cu")
		(net "PCIE_IOM_TO_COMP_14_DP")
	)
	(segment
		(start 152.983184 -34.75482)
		(end 152.80386 -34.635186)
		(width 0.14605)
		(layer "B.Cu")
		(net "PCIE_IOM_TO_COMP_14_DP")
	)
	(segment
		(start 153.207466 -56.741314)
		(end 153.293572 -56.3118)
		(width 0.14605)
		(layer "B.Cu")
		(net "PCIE_IOM_TO_COMP_14_DP")
	)
	(segment
		(start 152.751536 -33.59658)
		(end 152.572212 -33.476946)
		(width 0.14605)
		(layer "B.Cu")
		(net "PCIE_IOM_TO_COMP_14_DP")
	)
	(segment
		(start 152.142444 -30.551882)
		(end 152.056592 -30.122114)
		(width 0.14605)
		(layer "B.Cu")
		(net "PCIE_IOM_TO_COMP_14_DP")
	)
	(segment
		(start 190.072772 -82.422492)
		(end 188.37656 -84.118704)
		(width 0.14605)
		(layer "B.Cu")
		(net "PCIE_IOM_TO_COMP_14_DP")
	)
	(segment
		(start 152.28824 -31.280354)
		(end 152.108916 -31.16072)
		(width 0.14605)
		(layer "B.Cu")
		(net "PCIE_IOM_TO_COMP_14_DP")
	)
	(segment
		(start 154.908504 -49.012602)
		(end 154.78887 -48.833278)
		(width 0.14605)
		(layer "B.Cu")
		(net "PCIE_IOM_TO_COMP_14_DP")
	)
	(segment
		(start 153.241248 -57.350406)
		(end 153.3271 -56.920638)
		(width 0.14605)
		(layer "B.Cu")
		(net "PCIE_IOM_TO_COMP_14_DP")
	)
	(segment
		(start 152.254712 -31.889192)
		(end 152.374092 -31.709868)
		(width 0.14605)
		(layer "B.Cu")
		(net "PCIE_IOM_TO_COMP_14_DP")
	)
	(segment
		(start 155.020518 -47.675038)
		(end 155.10637 -47.24527)
		(width 0.14605)
		(layer "B.Cu")
		(net "PCIE_IOM_TO_COMP_14_DP")
	)
	(segment
		(start 148.961094 -25.532334)
		(end 145.746724 -23.36419)
		(width 0.14605)
		(layer "B.Cu")
		(net "PCIE_IOM_TO_COMP_14_DP")
	)
	(segment
		(start 152.80386 -34.635186)
		(end 152.717754 -34.205672)
		(width 0.14605)
		(layer "B.Cu")
		(net "PCIE_IOM_TO_COMP_14_DP")
	)
	(segment
		(start 156.045916 -74.506074)
		(end 155.507436 -73.708006)
		(width 0.14605)
		(layer "B.Cu")
		(net "PCIE_IOM_TO_COMP_14_DP")
	)
	(segment
		(start 152.837388 -34.026348)
		(end 152.751536 -33.59658)
		(width 0.14605)
		(layer "B.Cu")
		(net "PCIE_IOM_TO_COMP_14_DP")
	)
	(segment
		(start 154.78887 -48.833278)
		(end 154.874722 -48.40351)
		(width 0.14605)
		(layer "B.Cu")
		(net "PCIE_IOM_TO_COMP_14_DP")
	)
	(segment
		(start 153.3271 -56.920638)
		(end 153.207466 -56.741314)
		(width 0.14605)
		(layer "B.Cu")
		(net "PCIE_IOM_TO_COMP_14_DP")
	)
	(segment
		(start 152.572212 -33.476946)
		(end 152.48636 -33.047432)
		(width 0.14605)
		(layer "B.Cu")
		(net "PCIE_IOM_TO_COMP_14_DP")
	)
	(segment
		(start 130.045968 -36.144454)
		(end 130.27406 -36.144454)
		(width 0.14605)
		(layer "B.Cu")
		(net "PCIE_IOM_TO_COMP_14_DP")
	)
	(segment
		(start 155.371546 -46.696122)
		(end 152.983184 -34.75482)
		(width 0.14605)
		(layer "B.Cu")
		(net "PCIE_IOM_TO_COMP_14_DP")
	)
	(segment
		(start 152.48636 -33.047432)
		(end 152.60574 -32.868108)
		(width 0.14605)
		(layer "B.Cu")
		(net "PCIE_IOM_TO_COMP_14_DP")
	)
	(segment
		(start 186.304428 -85.499956)
		(end 180.554122 -86.650068)
		(width 0.14605)
		(layer "B.Cu")
		(net "PCIE_IOM_TO_COMP_14_DP")
	)
	(segment
		(start 155.054046 -48.283876)
		(end 155.139898 -47.854362)
		(width 0.14605)
		(layer "B.Cu")
		(net "PCIE_IOM_TO_COMP_14_DP")
	)
	(segment
		(start 152.60574 -32.868108)
		(end 152.519888 -32.43834)
		(width 0.14605)
		(layer "B.Cu")
		(net "PCIE_IOM_TO_COMP_14_DP")
	)
	(segment
		(start 188.37656 -84.118704)
		(end 186.304428 -85.499956)
		(width 0.14605)
		(layer "B.Cu")
		(net "PCIE_IOM_TO_COMP_14_DP")
	)
	(segment
		(start 154.557222 -49.991264)
		(end 154.643328 -49.56175)
		(width 0.14605)
		(layer "B.Cu")
		(net "PCIE_IOM_TO_COMP_14_DP")
	)
	(segment
		(start 153.095706 -58.079132)
		(end 152.976072 -57.899808)
		(width 0.14605)
		(layer "B.Cu")
		(net "PCIE_IOM_TO_COMP_14_DP")
	)
	(segment
		(start 152.864058 -59.237118)
		(end 152.744424 -59.057794)
		(width 0.14605)
		(layer "B.Cu")
		(net "PCIE_IOM_TO_COMP_14_DP")
	)
	(segment
		(start 152.056592 -30.122114)
		(end 148.961094 -25.532334)
		(width 0.14605)
		(layer "B.Cu")
		(net "PCIE_IOM_TO_COMP_14_DP")
	)
	(segment
		(start 152.83053 -58.62828)
		(end 153.009854 -58.508646)
		(width 0.14605)
		(layer "B.Cu")
		(net "PCIE_IOM_TO_COMP_14_DP")
	)
	(segment
		(start 154.591004 -50.600356)
		(end 154.676856 -50.170588)
		(width 0.14605)
		(layer "B.Cu")
		(net "PCIE_IOM_TO_COMP_14_DP")
	)
	(segment
		(start 180.554122 -86.650068)
		(end 171.563538 -84.851494)
		(width 0.14605)
		(layer "B.Cu")
		(net "PCIE_IOM_TO_COMP_14_DP")
	)
	(segment
		(start 153.472896 -56.192166)
		(end 154.445208 -51.328828)
		(width 0.14605)
		(layer "B.Cu")
		(net "PCIE_IOM_TO_COMP_14_DP")
	)
	(segment
		(start 136.233408 -23.36419)
		(end 129.755392 -29.842206)
		(width 0.14605)
		(layer "B.Cu")
		(net "PCIE_IOM_TO_COMP_14_DP")
	)
	(segment
		(start 130.499866 -35.918394)
		(end 130.499866 -35.600132)
		(width 0.14605)
		(layer "B.Cu")
		(net "PCIE_IOM_TO_COMP_14_DP")
	)
	(segment
		(start 153.061924 -57.47004)
		(end 153.241248 -57.350406)
		(width 0.14605)
		(layer "B.Cu")
		(net "PCIE_IOM_TO_COMP_14_DP")
	)
	(segment
		(start 152.519888 -32.43834)
		(end 152.340564 -32.31896)
		(width 0.14605)
		(layer "B.Cu")
		(net "PCIE_IOM_TO_COMP_14_DP")
	)
	(segment
		(start 154.822652 -49.442116)
		(end 154.908504 -49.012602)
		(width 0.14605)
		(layer "B.Cu")
		(net "PCIE_IOM_TO_COMP_14_DP")
	)
	(segment
		(start 154.874722 -48.40351)
		(end 155.054046 -48.283876)
		(width 0.14605)
		(layer "B.Cu")
		(net "PCIE_IOM_TO_COMP_14_DP")
	)
	(segment
		(start 153.009854 -58.508646)
		(end 153.095706 -58.079132)
		(width 0.14605)
		(layer "B.Cu")
		(net "PCIE_IOM_TO_COMP_14_DP")
	)
	(segment
		(start 152.108916 -31.16072)
		(end 152.023064 -30.731206)
		(width 0.14605)
		(layer "B.Cu")
		(net "PCIE_IOM_TO_COMP_14_DP")
	)
	(segment
		(start 129.755392 -29.842206)
		(end 129.755392 -35.853878)
		(width 0.14605)
		(layer "B.Cu")
		(net "PCIE_IOM_TO_COMP_14_DP")
	)
	(segment
		(start 152.744424 -59.057794)
		(end 152.83053 -58.62828)
		(width 0.14605)
		(layer "B.Cu")
		(net "PCIE_IOM_TO_COMP_14_DP")
	)
	(segment
		(start 190.072772 -81.559146)
		(end 190.072772 -82.422492)
		(width 0.14605)
		(layer "B.Cu")
		(net "PCIE_IOM_TO_COMP_14_DP")
	)
	(segment
		(start 155.285694 -47.12589)
		(end 155.371546 -46.696122)
		(width 0.14605)
		(layer "B.Cu")
		(net "PCIE_IOM_TO_COMP_14_DP")
	)
	(segment
		(start 152.976072 -57.899808)
		(end 153.061924 -57.47004)
		(width 0.14605)
		(layer "B.Cu")
		(net "PCIE_IOM_TO_COMP_14_DP")
	)
	(segment
		(start 155.10637 -47.24527)
		(end 155.285694 -47.12589)
		(width 0.14605)
		(layer "B.Cu")
		(net "PCIE_IOM_TO_COMP_14_DP")
	)
	(segment
		(start 154.325828 -51.149504)
		(end 154.41168 -50.71999)
		(width 0.14605)
		(layer "B.Cu")
		(net "PCIE_IOM_TO_COMP_14_DP")
	)
	(segment
		(start 154.41168 -50.71999)
		(end 154.591004 -50.600356)
		(width 0.14605)
		(layer "B.Cu")
		(net "PCIE_IOM_TO_COMP_14_DP")
	)
	(segment
		(start 152.023064 -30.731206)
		(end 152.142444 -30.551882)
		(width 0.14605)
		(layer "B.Cu")
		(net "PCIE_IOM_TO_COMP_14_DP")
	)
	(segment
		(start 152.340564 -32.31896)
		(end 152.254712 -31.889192)
		(width 0.14605)
		(layer "B.Cu")
		(net "PCIE_IOM_TO_COMP_14_DP")
	)
	(segment
		(start 171.563538 -84.851494)
		(end 156.045916 -74.506074)
		(width 0.14605)
		(layer "B.Cu")
		(net "PCIE_IOM_TO_COMP_14_DP")
	)
	(segment
		(start 152.717754 -34.205672)
		(end 152.837388 -34.026348)
		(width 0.14605)
		(layer "B.Cu")
		(net "PCIE_IOM_TO_COMP_14_DP")
	)
	(segment
		(start 152.374092 -31.709868)
		(end 152.28824 -31.280354)
		(width 0.14605)
		(layer "B.Cu")
		(net "PCIE_IOM_TO_COMP_14_DP")
	)
	(segment
		(start 145.746724 -23.36419)
		(end 136.233408 -23.36419)
		(width 0.14605)
		(layer "B.Cu")
		(net "PCIE_IOM_TO_COMP_14_DP")
	)
	(segment
		(start 153.293572 -56.3118)
		(end 153.472896 -56.192166)
		(width 0.14605)
		(layer "B.Cu")
		(net "PCIE_IOM_TO_COMP_14_DP")
	)
	(segment
		(start 155.139898 -47.854362)
		(end 155.020518 -47.675038)
		(width 0.14605)
		(layer "B.Cu")
		(net "PCIE_IOM_TO_COMP_14_DP")
	)
	(segment
		(start 190.199518 -81.4324)
		(end 190.072772 -81.559146)
		(width 0.14605)
		(layer "B.Cu")
		(net "PCIE_IOM_TO_COMP_14_DP")
	)
	(segment
		(start 154.676856 -50.170588)
		(end 154.557222 -49.991264)
		(width 0.14605)
		(layer "B.Cu")
		(net "PCIE_IOM_TO_COMP_14_DP")
	)
	(segment
		(start 155.507436 -73.708006)
		(end 152.778206 -59.666886)
		(width 0.14605)
		(layer "B.Cu")
		(net "PCIE_IOM_TO_COMP_14_DP")
	)
	(arc
		(start 130.433572 -36.078414)
		(mid 130.482628 -36.004996)
		(end 130.499866 -35.918394)
		(width 0.14605)
		(layer "B.Cu")
		(net "PCIE_IOM_TO_COMP_14_DP")
	)
	(arc
		(start 130.27406 -36.144454)
		(mid 130.360375 -36.127285)
		(end 130.433572 -36.078414)
		(width 0.14605)
		(layer "B.Cu")
		(net "PCIE_IOM_TO_COMP_14_DP")
	)
	(arc
		(start 129.755392 -35.853878)
		(mid 129.8405 -36.059346)
		(end 130.045968 -36.144454)
		(width 0.14605)
		(layer "B.Cu")
		(net "PCIE_IOM_TO_COMP_14_DP")
	)
	(segment
		(start 192.39992 -73.49998)
		(end 192.799716 -73.899776)
		(width 0.09525)
		(layer "F.Cu")
		(net "PCIE_IOM_TO_COMP_14_DN_C")
	)
	(via
		(at 192.799716 -73.899776)
		(size 0.4572)
		(drill 0.2032)
		(layers "F.Cu" "B.Cu")
		(net "PCIE_IOM_TO_COMP_14_DN_C")
	)
	(segment
		(start 192.799716 -73.899776)
		(end 192.402968 -74.529188)
		(width 0.09525)
		(layer "B.Cu")
		(net "PCIE_IOM_TO_COMP_14_DN_C")
	)
	(segment
		(start 189.767972 -80.746346)
		(end 189.640718 -80.8736)
		(width 0.14605)
		(layer "B.Cu")
		(net "PCIE_IOM_TO_COMP_14_DN_C")
	)
	(segment
		(start 191.904112 -77.710284)
		(end 191.814196 -77.710284)
		(width 0.09525)
		(layer "B.Cu")
		(net "PCIE_IOM_TO_COMP_14_DN_C")
	)
	(segment
		(start 192.402968 -74.529188)
		(end 192.402968 -74.975212)
		(width 0.09525)
		(layer "B.Cu")
		(net "PCIE_IOM_TO_COMP_14_DN_C")
	)
	(segment
		(start 191.814196 -77.710284)
		(end 191.797432 -77.727048)
		(width 0.09525)
		(layer "B.Cu")
		(net "PCIE_IOM_TO_COMP_14_DN_C")
	)
	(segment
		(start 192.402968 -74.975212)
		(end 192.061338 -75.488546)
		(width 0.09525)
		(layer "B.Cu")
		(net "PCIE_IOM_TO_COMP_14_DN_C")
	)
	(segment
		(start 192.061338 -77.553058)
		(end 191.904112 -77.710284)
		(width 0.09525)
		(layer "B.Cu")
		(net "PCIE_IOM_TO_COMP_14_DN_C")
	)
	(segment
		(start 191.797432 -77.727048)
		(end 189.767972 -79.756508)
		(width 0.14605)
		(layer "B.Cu")
		(net "PCIE_IOM_TO_COMP_14_DN_C")
	)
	(segment
		(start 189.767972 -79.756508)
		(end 189.767972 -80.746346)
		(width 0.14605)
		(layer "B.Cu")
		(net "PCIE_IOM_TO_COMP_14_DN_C")
	)
	(segment
		(start 192.061338 -75.488546)
		(end 192.061338 -77.553058)
		(width 0.09525)
		(layer "B.Cu")
		(net "PCIE_IOM_TO_COMP_14_DN_C")
	)
	(segment
		(start 189.761622 -81.553304)
		(end 189.761622 -82.29346)
		(width 0.14605)
		(layer "B.Cu")
		(net "PCIE_IOM_TO_COMP_14_DN")
	)
	(segment
		(start 130.045968 -36.455604)
		(end 130.328416 -36.455604)
		(width 0.14605)
		(layer "B.Cu")
		(net "PCIE_IOM_TO_COMP_14_DN")
	)
	(segment
		(start 149.185376 -25.308052)
		(end 145.841974 -23.05304)
		(width 0.14605)
		(layer "B.Cu")
		(net "PCIE_IOM_TO_COMP_14_DN")
	)
	(segment
		(start 153.095452 -59.667648)
		(end 155.689046 -46.696122)
		(width 0.14605)
		(layer "B.Cu")
		(net "PCIE_IOM_TO_COMP_14_DN")
	)
	(segment
		(start 186.182762 -85.20684)
		(end 180.554122 -86.332568)
		(width 0.14605)
		(layer "B.Cu")
		(net "PCIE_IOM_TO_COMP_14_DN")
	)
	(segment
		(start 188.178186 -83.876642)
		(end 186.183016 -85.20684)
		(width 0.14605)
		(layer "B.Cu")
		(net "PCIE_IOM_TO_COMP_14_DN")
	)
	(segment
		(start 171.68495 -84.558378)
		(end 156.26969 -74.28103)
		(width 0.14605)
		(layer "B.Cu")
		(net "PCIE_IOM_TO_COMP_14_DN")
	)
	(segment
		(start 155.80106 -73.58634)
		(end 153.095452 -59.667648)
		(width 0.14605)
		(layer "B.Cu")
		(net "PCIE_IOM_TO_COMP_14_DN")
	)
	(segment
		(start 136.104376 -23.05304)
		(end 129.444242 -29.713174)
		(width 0.14605)
		(layer "B.Cu")
		(net "PCIE_IOM_TO_COMP_14_DN")
	)
	(segment
		(start 186.183016 -85.20684)
		(end 186.183016 -85.206586)
		(width 0.14605)
		(layer "B.Cu")
		(net "PCIE_IOM_TO_COMP_14_DN")
	)
	(segment
		(start 156.26969 -74.28103)
		(end 155.80106 -73.58634)
		(width 0.14605)
		(layer "B.Cu")
		(net "PCIE_IOM_TO_COMP_14_DN")
	)
	(segment
		(start 189.640718 -81.4324)
		(end 189.761622 -81.553304)
		(width 0.14605)
		(layer "B.Cu")
		(net "PCIE_IOM_TO_COMP_14_DN")
	)
	(segment
		(start 145.841974 -23.05304)
		(end 136.104376 -23.05304)
		(width 0.14605)
		(layer "B.Cu")
		(net "PCIE_IOM_TO_COMP_14_DN")
	)
	(segment
		(start 129.444242 -29.713174)
		(end 129.444242 -35.853878)
		(width 0.14605)
		(layer "B.Cu")
		(net "PCIE_IOM_TO_COMP_14_DN")
	)
	(segment
		(start 155.689046 -46.696122)
		(end 152.349708 -29.999686)
		(width 0.14605)
		(layer "B.Cu")
		(net "PCIE_IOM_TO_COMP_14_DN")
	)
	(segment
		(start 152.349708 -29.999686)
		(end 149.185376 -25.308052)
		(width 0.14605)
		(layer "B.Cu")
		(net "PCIE_IOM_TO_COMP_14_DN")
	)
	(segment
		(start 189.761622 -82.29346)
		(end 188.178186 -83.876642)
		(width 0.14605)
		(layer "B.Cu")
		(net "PCIE_IOM_TO_COMP_14_DN")
	)
	(segment
		(start 180.554122 -86.332568)
		(end 171.68495 -84.558378)
		(width 0.14605)
		(layer "B.Cu")
		(net "PCIE_IOM_TO_COMP_14_DN")
	)
	(segment
		(start 186.183016 -85.206586)
		(end 186.182762 -85.20684)
		(width 0.14605)
		(layer "B.Cu")
		(net "PCIE_IOM_TO_COMP_14_DN")
	)
	(segment
		(start 130.499866 -36.6268)
		(end 130.499866 -37.00018)
		(width 0.14605)
		(layer "B.Cu")
		(net "PCIE_IOM_TO_COMP_14_DN")
	)
	(arc
		(start 130.328416 -36.455604)
		(mid 130.394124 -36.468674)
		(end 130.449828 -36.505896)
		(width 0.14605)
		(layer "B.Cu")
		(net "PCIE_IOM_TO_COMP_14_DN")
	)
	(arc
		(start 130.449828 -36.505896)
		(mid 130.486839 -36.561381)
		(end 130.499866 -36.6268)
		(width 0.14605)
		(layer "B.Cu")
		(net "PCIE_IOM_TO_COMP_14_DN")
	)
	(arc
		(start 129.444242 -35.853878)
		(mid 129.620483 -36.279363)
		(end 130.045968 -36.455604)
		(width 0.14605)
		(layer "B.Cu")
		(net "PCIE_IOM_TO_COMP_14_DN")
	)
	(segment
		(start 193.999866 -74.299826)
		(end 193.999866 -74.309224)
		(width 0.09525)
		(layer "F.Cu")
		(net "PCIE_IOM_TO_COMP_13_DP_C")
	)
	(segment
		(start 193.999866 -74.309224)
		(end 194.39255 -74.701908)
		(width 0.09525)
		(layer "F.Cu")
		(net "PCIE_IOM_TO_COMP_13_DP_C")
	)
	(via
		(at 194.39255 -74.701908)
		(size 0.4572)
		(drill 0.2032)
		(layers "F.Cu" "B.Cu")
		(net "PCIE_IOM_TO_COMP_13_DP_C")
	)
	(segment
		(start 194.15379 -76.601828)
		(end 194.15379 -76.62545)
		(width 0.09525)
		(layer "B.Cu")
		(net "PCIE_IOM_TO_COMP_13_DP_C")
	)
	(segment
		(start 192.129664 -80.771746)
		(end 192.231518 -80.8736)
		(width 0.14605)
		(layer "B.Cu")
		(net "PCIE_IOM_TO_COMP_13_DP_C")
	)
	(segment
		(start 194.22745 -74.867008)
		(end 194.22745 -76.009754)
		(width 0.09525)
		(layer "B.Cu")
		(net "PCIE_IOM_TO_COMP_13_DP_C")
	)
	(segment
		(start 194.09029 -76.538328)
		(end 194.15379 -76.601828)
		(width 0.09525)
		(layer "B.Cu")
		(net "PCIE_IOM_TO_COMP_13_DP_C")
	)
	(segment
		(start 194.15379 -77.41031)
		(end 192.129664 -79.434436)
		(width 0.14605)
		(layer "B.Cu")
		(net "PCIE_IOM_TO_COMP_13_DP_C")
	)
	(segment
		(start 194.15379 -76.62545)
		(end 194.15379 -77.41031)
		(width 0.14605)
		(layer "B.Cu")
		(net "PCIE_IOM_TO_COMP_13_DP_C")
	)
	(segment
		(start 194.09029 -76.146914)
		(end 194.09029 -76.538328)
		(width 0.09525)
		(layer "B.Cu")
		(net "PCIE_IOM_TO_COMP_13_DP_C")
	)
	(segment
		(start 194.22745 -76.009754)
		(end 194.09029 -76.146914)
		(width 0.09525)
		(layer "B.Cu")
		(net "PCIE_IOM_TO_COMP_13_DP_C")
	)
	(segment
		(start 192.129664 -79.434436)
		(end 192.129664 -80.771746)
		(width 0.14605)
		(layer "B.Cu")
		(net "PCIE_IOM_TO_COMP_13_DP_C")
	)
	(segment
		(start 194.39255 -74.701908)
		(end 194.22745 -74.867008)
		(width 0.09525)
		(layer "B.Cu")
		(net "PCIE_IOM_TO_COMP_13_DP_C")
	)
	(segment
		(start 150.860252 -30.782768)
		(end 150.7744 -30.353)
		(width 0.14605)
		(layer "B.Cu")
		(net "PCIE_IOM_TO_COMP_13_DP")
	)
	(segment
		(start 150.7744 -30.353)
		(end 150.159212 -29.430218)
		(width 0.14605)
		(layer "B.Cu")
		(net "PCIE_IOM_TO_COMP_13_DP")
	)
	(segment
		(start 155.103068 -75.252072)
		(end 154.435556 -74.251312)
		(width 0.14605)
		(layer "B.Cu")
		(net "PCIE_IOM_TO_COMP_13_DP")
	)
	(segment
		(start 190.226188 -85.342476)
		(end 188.667644 -86.381336)
		(width 0.14605)
		(layer "B.Cu")
		(net "PCIE_IOM_TO_COMP_13_DP")
	)
	(segment
		(start 153.695146 -44.965112)
		(end 153.515822 -44.845478)
		(width 0.14605)
		(layer "B.Cu")
		(net "PCIE_IOM_TO_COMP_13_DP")
	)
	(segment
		(start 148.436584 -26.84653)
		(end 148.193506 -26.48204)
		(width 0.14605)
		(layer "B.Cu")
		(net "PCIE_IOM_TO_COMP_13_DP")
	)
	(segment
		(start 151.554688 -34.257234)
		(end 151.468836 -33.827466)
		(width 0.14605)
		(layer "B.Cu")
		(net "PCIE_IOM_TO_COMP_13_DP")
	)
	(segment
		(start 149.09165 -27.829256)
		(end 148.848826 -27.464766)
		(width 0.14605)
		(layer "B.Cu")
		(net "PCIE_IOM_TO_COMP_13_DP")
	)
	(segment
		(start 153.463498 -43.806872)
		(end 153.284174 -43.687238)
		(width 0.14605)
		(layer "B.Cu")
		(net "PCIE_IOM_TO_COMP_13_DP")
	)
	(segment
		(start 151.700484 -34.985706)
		(end 151.52116 -34.866072)
		(width 0.14605)
		(layer "B.Cu")
		(net "PCIE_IOM_TO_COMP_13_DP")
	)
	(segment
		(start 148.637244 -27.422602)
		(end 148.39442 -27.057858)
		(width 0.14605)
		(layer "B.Cu")
		(net "PCIE_IOM_TO_COMP_13_DP")
	)
	(segment
		(start 153.05278 -42.528998)
		(end 152.966928 -42.099484)
		(width 0.14605)
		(layer "B.Cu")
		(net "PCIE_IOM_TO_COMP_13_DP")
	)
	(segment
		(start 180.953664 -87.897716)
		(end 171.121832 -85.931248)
		(width 0.14605)
		(layer "B.Cu")
		(net "PCIE_IOM_TO_COMP_13_DP")
	)
	(segment
		(start 153.086308 -41.92016)
		(end 153.000456 -41.490392)
		(width 0.14605)
		(layer "B.Cu")
		(net "PCIE_IOM_TO_COMP_13_DP")
	)
	(segment
		(start 154.012392 -46.553374)
		(end 154.012392 -46.552866)
		(width 0.14605)
		(layer "B.Cu")
		(net "PCIE_IOM_TO_COMP_13_DP")
	)
	(segment
		(start 151.468836 -33.827466)
		(end 151.289512 -33.708086)
		(width 0.14605)
		(layer "B.Cu")
		(net "PCIE_IOM_TO_COMP_13_DP")
	)
	(segment
		(start 192.1002 -83.468464)
		(end 190.226188 -85.342476)
		(width 0.14605)
		(layer "B.Cu")
		(net "PCIE_IOM_TO_COMP_13_DP")
	)
	(segment
		(start 136.697466 -24.546306)
		(end 131.55549 -29.688282)
		(width 0.14605)
		(layer "B.Cu")
		(net "PCIE_IOM_TO_COMP_13_DP")
	)
	(segment
		(start 149.74697 -28.811982)
		(end 149.503892 -28.447492)
		(width 0.14605)
		(layer "B.Cu")
		(net "PCIE_IOM_TO_COMP_13_DP")
	)
	(segment
		(start 151.289512 -33.708086)
		(end 151.20366 -33.278318)
		(width 0.14605)
		(layer "B.Cu")
		(net "PCIE_IOM_TO_COMP_13_DP")
	)
	(segment
		(start 152.821132 -41.371012)
		(end 152.73528 -40.941244)
		(width 0.14605)
		(layer "B.Cu")
		(net "PCIE_IOM_TO_COMP_13_DP")
	)
	(segment
		(start 154.012392 -46.552866)
		(end 153.92654 -46.123098)
		(width 0.14605)
		(layer "B.Cu")
		(net "PCIE_IOM_TO_COMP_13_DP")
	)
	(segment
		(start 171.121832 -85.931248)
		(end 155.103068 -75.252072)
		(width 0.14605)
		(layer "B.Cu")
		(net "PCIE_IOM_TO_COMP_13_DP")
	)
	(segment
		(start 152.73528 -40.941244)
		(end 152.854914 -40.76192)
		(width 0.14605)
		(layer "B.Cu")
		(net "PCIE_IOM_TO_COMP_13_DP")
	)
	(segment
		(start 149.049486 -28.040584)
		(end 149.09165 -27.829256)
		(width 0.14605)
		(layer "B.Cu")
		(net "PCIE_IOM_TO_COMP_13_DP")
	)
	(segment
		(start 131.55549 -29.688282)
		(end 131.55549 -37.053774)
		(width 0.14605)
		(layer "B.Cu")
		(net "PCIE_IOM_TO_COMP_13_DP")
	)
	(segment
		(start 151.435054 -34.436558)
		(end 151.554688 -34.257234)
		(width 0.14605)
		(layer "B.Cu")
		(net "PCIE_IOM_TO_COMP_13_DP")
	)
	(segment
		(start 149.704806 -29.02331)
		(end 149.74697 -28.811982)
		(width 0.14605)
		(layer "B.Cu")
		(net "PCIE_IOM_TO_COMP_13_DP")
	)
	(segment
		(start 153.317956 -43.0784)
		(end 153.232104 -42.648632)
		(width 0.14605)
		(layer "B.Cu")
		(net "PCIE_IOM_TO_COMP_13_DP")
	)
	(segment
		(start 154.435556 -74.251312)
		(end 151.45639 -59.34202)
		(width 0.14605)
		(layer "B.Cu")
		(net "PCIE_IOM_TO_COMP_13_DP")
	)
	(segment
		(start 131.846066 -37.34435)
		(end 132.074158 -37.34435)
		(width 0.14605)
		(layer "B.Cu")
		(net "PCIE_IOM_TO_COMP_13_DP")
	)
	(segment
		(start 149.292564 -28.405074)
		(end 149.049486 -28.040584)
		(width 0.14605)
		(layer "B.Cu")
		(net "PCIE_IOM_TO_COMP_13_DP")
	)
	(segment
		(start 148.848826 -27.464766)
		(end 148.637244 -27.422602)
		(width 0.14605)
		(layer "B.Cu")
		(net "PCIE_IOM_TO_COMP_13_DP")
	)
	(segment
		(start 153.232104 -42.648632)
		(end 153.05278 -42.528998)
		(width 0.14605)
		(layer "B.Cu")
		(net "PCIE_IOM_TO_COMP_13_DP")
	)
	(segment
		(start 153.661364 -45.57395)
		(end 153.780998 -45.394626)
		(width 0.14605)
		(layer "B.Cu")
		(net "PCIE_IOM_TO_COMP_13_DP")
	)
	(segment
		(start 151.058118 -32.549846)
		(end 150.972266 -32.120078)
		(width 0.14605)
		(layer "B.Cu")
		(net "PCIE_IOM_TO_COMP_13_DP")
	)
	(segment
		(start 148.193506 -26.48204)
		(end 145.290032 -24.546306)
		(width 0.14605)
		(layer "B.Cu")
		(net "PCIE_IOM_TO_COMP_13_DP")
	)
	(segment
		(start 150.972266 -32.120078)
		(end 151.091646 -31.940754)
		(width 0.14605)
		(layer "B.Cu")
		(net "PCIE_IOM_TO_COMP_13_DP")
	)
	(segment
		(start 153.429716 -44.41571)
		(end 153.54935 -44.236386)
		(width 0.14605)
		(layer "B.Cu")
		(net "PCIE_IOM_TO_COMP_13_DP")
	)
	(segment
		(start 153.284174 -43.687238)
		(end 153.198322 -43.257724)
		(width 0.14605)
		(layer "B.Cu")
		(net "PCIE_IOM_TO_COMP_13_DP")
	)
	(segment
		(start 150.82647 -31.391606)
		(end 150.740618 -30.962092)
		(width 0.14605)
		(layer "B.Cu")
		(net "PCIE_IOM_TO_COMP_13_DP")
	)
	(segment
		(start 153.54935 -44.236386)
		(end 153.463498 -43.806872)
		(width 0.14605)
		(layer "B.Cu")
		(net "PCIE_IOM_TO_COMP_13_DP")
	)
	(segment
		(start 151.005794 -31.51124)
		(end 150.82647 -31.391606)
		(width 0.14605)
		(layer "B.Cu")
		(net "PCIE_IOM_TO_COMP_13_DP")
	)
	(segment
		(start 132.299964 -37.11829)
		(end 132.299964 -36.800028)
		(width 0.14605)
		(layer "B.Cu")
		(net "PCIE_IOM_TO_COMP_13_DP")
	)
	(segment
		(start 188.667644 -86.381336)
		(end 180.953664 -87.897716)
		(width 0.14605)
		(layer "B.Cu")
		(net "PCIE_IOM_TO_COMP_13_DP")
	)
	(segment
		(start 151.237442 -32.66948)
		(end 151.058118 -32.549846)
		(width 0.14605)
		(layer "B.Cu")
		(net "PCIE_IOM_TO_COMP_13_DP")
	)
	(segment
		(start 149.947884 -29.3878)
		(end 149.704806 -29.02331)
		(width 0.14605)
		(layer "B.Cu")
		(net "PCIE_IOM_TO_COMP_13_DP")
	)
	(segment
		(start 152.966928 -42.099484)
		(end 153.086308 -41.92016)
		(width 0.14605)
		(layer "B.Cu")
		(net "PCIE_IOM_TO_COMP_13_DP")
	)
	(segment
		(start 149.503892 -28.447492)
		(end 149.292564 -28.405074)
		(width 0.14605)
		(layer "B.Cu")
		(net "PCIE_IOM_TO_COMP_13_DP")
	)
	(segment
		(start 192.1002 -81.563718)
		(end 192.1002 -83.468464)
		(width 0.14605)
		(layer "B.Cu")
		(net "PCIE_IOM_TO_COMP_13_DP")
	)
	(segment
		(start 151.323294 -33.098994)
		(end 151.237442 -32.66948)
		(width 0.14605)
		(layer "B.Cu")
		(net "PCIE_IOM_TO_COMP_13_DP")
	)
	(segment
		(start 153.515822 -44.845478)
		(end 153.429716 -44.41571)
		(width 0.14605)
		(layer "B.Cu")
		(net "PCIE_IOM_TO_COMP_13_DP")
	)
	(segment
		(start 153.92654 -46.123098)
		(end 153.747216 -46.003718)
		(width 0.14605)
		(layer "B.Cu")
		(net "PCIE_IOM_TO_COMP_13_DP")
	)
	(segment
		(start 152.854914 -40.76192)
		(end 151.700484 -34.985706)
		(width 0.14605)
		(layer "B.Cu")
		(net "PCIE_IOM_TO_COMP_13_DP")
	)
	(segment
		(start 145.290032 -24.546306)
		(end 136.697466 -24.546306)
		(width 0.14605)
		(layer "B.Cu")
		(net "PCIE_IOM_TO_COMP_13_DP")
	)
	(segment
		(start 148.39442 -27.057858)
		(end 148.436584 -26.84653)
		(width 0.14605)
		(layer "B.Cu")
		(net "PCIE_IOM_TO_COMP_13_DP")
	)
	(segment
		(start 153.198322 -43.257724)
		(end 153.317956 -43.0784)
		(width 0.14605)
		(layer "B.Cu")
		(net "PCIE_IOM_TO_COMP_13_DP")
	)
	(segment
		(start 150.740618 -30.962092)
		(end 150.860252 -30.782768)
		(width 0.14605)
		(layer "B.Cu")
		(net "PCIE_IOM_TO_COMP_13_DP")
	)
	(segment
		(start 153.747216 -46.003718)
		(end 153.661364 -45.57395)
		(width 0.14605)
		(layer "B.Cu")
		(net "PCIE_IOM_TO_COMP_13_DP")
	)
	(segment
		(start 151.52116 -34.866072)
		(end 151.435054 -34.436558)
		(width 0.14605)
		(layer "B.Cu")
		(net "PCIE_IOM_TO_COMP_13_DP")
	)
	(segment
		(start 151.091646 -31.940754)
		(end 151.005794 -31.51124)
		(width 0.14605)
		(layer "B.Cu")
		(net "PCIE_IOM_TO_COMP_13_DP")
	)
	(segment
		(start 151.20366 -33.278318)
		(end 151.323294 -33.098994)
		(width 0.14605)
		(layer "B.Cu")
		(net "PCIE_IOM_TO_COMP_13_DP")
	)
	(segment
		(start 153.780998 -45.394626)
		(end 153.695146 -44.965112)
		(width 0.14605)
		(layer "B.Cu")
		(net "PCIE_IOM_TO_COMP_13_DP")
	)
	(segment
		(start 150.159212 -29.430218)
		(end 149.947884 -29.3878)
		(width 0.14605)
		(layer "B.Cu")
		(net "PCIE_IOM_TO_COMP_13_DP")
	)
	(segment
		(start 192.231518 -81.4324)
		(end 192.1002 -81.563718)
		(width 0.14605)
		(layer "B.Cu")
		(net "PCIE_IOM_TO_COMP_13_DP")
	)
	(segment
		(start 153.000456 -41.490392)
		(end 152.821132 -41.371012)
		(width 0.14605)
		(layer "B.Cu")
		(net "PCIE_IOM_TO_COMP_13_DP")
	)
	(segment
		(start 151.45639 -59.34202)
		(end 154.012392 -46.553374)
		(width 0.14605)
		(layer "B.Cu")
		(net "PCIE_IOM_TO_COMP_13_DP")
	)
	(arc
		(start 132.074158 -37.34435)
		(mid 132.160473 -37.327181)
		(end 132.23367 -37.27831)
		(width 0.14605)
		(layer "B.Cu")
		(net "PCIE_IOM_TO_COMP_13_DP")
	)
	(arc
		(start 131.55549 -37.053774)
		(mid 131.640598 -37.259242)
		(end 131.846066 -37.34435)
		(width 0.14605)
		(layer "B.Cu")
		(net "PCIE_IOM_TO_COMP_13_DP")
	)
	(arc
		(start 132.23367 -37.27831)
		(mid 132.282726 -37.204892)
		(end 132.299964 -37.11829)
		(width 0.14605)
		(layer "B.Cu")
		(net "PCIE_IOM_TO_COMP_13_DP")
	)
	(segment
		(start 193.999866 -73.49998)
		(end 194.399662 -73.899776)
		(width 0.09525)
		(layer "F.Cu")
		(net "PCIE_IOM_TO_COMP_13_DN_C")
	)
	(via
		(at 194.399662 -73.899776)
		(size 0.4572)
		(drill 0.2032)
		(layers "F.Cu" "B.Cu")
		(net "PCIE_IOM_TO_COMP_13_DN_C")
	)
	(segment
		(start 193.84264 -76.601828)
		(end 193.84264 -76.62545)
		(width 0.09525)
		(layer "B.Cu")
		(net "PCIE_IOM_TO_COMP_13_DN_C")
	)
	(segment
		(start 193.84264 -76.62545)
		(end 193.84264 -77.281278)
		(width 0.14605)
		(layer "B.Cu")
		(net "PCIE_IOM_TO_COMP_13_DN_C")
	)
	(segment
		(start 191.818514 -79.305404)
		(end 191.818514 -80.727804)
		(width 0.14605)
		(layer "B.Cu")
		(net "PCIE_IOM_TO_COMP_13_DN_C")
	)
	(segment
		(start 194.0433 -74.91857)
		(end 194.0433 -75.9333)
		(width 0.09525)
		(layer "B.Cu")
		(net "PCIE_IOM_TO_COMP_13_DN_C")
	)
	(segment
		(start 193.90614 -76.538328)
		(end 193.84264 -76.601828)
		(width 0.09525)
		(layer "B.Cu")
		(net "PCIE_IOM_TO_COMP_13_DN_C")
	)
	(segment
		(start 193.90614 -76.07046)
		(end 193.90614 -76.538328)
		(width 0.09525)
		(layer "B.Cu")
		(net "PCIE_IOM_TO_COMP_13_DN_C")
	)
	(segment
		(start 193.988944 -74.310494)
		(end 193.988944 -74.864214)
		(width 0.09525)
		(layer "B.Cu")
		(net "PCIE_IOM_TO_COMP_13_DN_C")
	)
	(segment
		(start 194.399662 -73.899776)
		(end 193.988944 -74.310494)
		(width 0.09525)
		(layer "B.Cu")
		(net "PCIE_IOM_TO_COMP_13_DN_C")
	)
	(segment
		(start 191.818514 -80.727804)
		(end 191.672718 -80.8736)
		(width 0.14605)
		(layer "B.Cu")
		(net "PCIE_IOM_TO_COMP_13_DN_C")
	)
	(segment
		(start 193.988944 -74.864214)
		(end 194.0433 -74.91857)
		(width 0.09525)
		(layer "B.Cu")
		(net "PCIE_IOM_TO_COMP_13_DN_C")
	)
	(segment
		(start 194.0433 -75.9333)
		(end 193.90614 -76.07046)
		(width 0.09525)
		(layer "B.Cu")
		(net "PCIE_IOM_TO_COMP_13_DN_C")
	)
	(segment
		(start 193.84264 -77.281278)
		(end 191.818514 -79.305404)
		(width 0.14605)
		(layer "B.Cu")
		(net "PCIE_IOM_TO_COMP_13_DN_C")
	)
	(segment
		(start 180.954172 -87.58047)
		(end 171.243244 -85.638132)
		(width 0.14605)
		(layer "B.Cu")
		(net "PCIE_IOM_TO_COMP_13_DN")
	)
	(segment
		(start 154.330146 -46.552358)
		(end 154.330146 -46.55185)
		(width 0.14605)
		(layer "B.Cu")
		(net "PCIE_IOM_TO_COMP_13_DN")
	)
	(segment
		(start 151.067516 -30.231588)
		(end 148.418042 -26.257504)
		(width 0.14605)
		(layer "B.Cu")
		(net "PCIE_IOM_TO_COMP_13_DN")
	)
	(segment
		(start 188.54674 -86.087966)
		(end 180.954172 -87.58047)
		(width 0.14605)
		(layer "B.Cu")
		(net "PCIE_IOM_TO_COMP_13_DN")
	)
	(segment
		(start 151.77389 -59.34202)
		(end 154.330146 -46.552358)
		(width 0.14605)
		(layer "B.Cu")
		(net "PCIE_IOM_TO_COMP_13_DN")
	)
	(segment
		(start 191.78905 -83.339432)
		(end 190.027814 -85.100414)
		(width 0.14605)
		(layer "B.Cu")
		(net "PCIE_IOM_TO_COMP_13_DN")
	)
	(segment
		(start 132.299964 -37.826696)
		(end 132.299964 -38.200076)
		(width 0.14605)
		(layer "B.Cu")
		(net "PCIE_IOM_TO_COMP_13_DN")
	)
	(segment
		(start 190.027814 -85.100414)
		(end 188.54674 -86.087966)
		(width 0.14605)
		(layer "B.Cu")
		(net "PCIE_IOM_TO_COMP_13_DN")
	)
	(segment
		(start 191.672718 -81.4324)
		(end 191.78905 -81.548732)
		(width 0.14605)
		(layer "B.Cu")
		(net "PCIE_IOM_TO_COMP_13_DN")
	)
	(segment
		(start 136.568434 -24.235156)
		(end 131.24434 -29.55925)
		(width 0.14605)
		(layer "B.Cu")
		(net "PCIE_IOM_TO_COMP_13_DN")
	)
	(segment
		(start 131.24434 -29.55925)
		(end 131.24434 -37.053774)
		(width 0.14605)
		(layer "B.Cu")
		(net "PCIE_IOM_TO_COMP_13_DN")
	)
	(segment
		(start 171.243244 -85.638132)
		(end 155.327604 -75.027536)
		(width 0.14605)
		(layer "B.Cu")
		(net "PCIE_IOM_TO_COMP_13_DN")
	)
	(segment
		(start 154.728672 -74.1299)
		(end 151.77389 -59.34202)
		(width 0.14605)
		(layer "B.Cu")
		(net "PCIE_IOM_TO_COMP_13_DN")
	)
	(segment
		(start 131.846066 -37.6555)
		(end 132.128514 -37.6555)
		(width 0.14605)
		(layer "B.Cu")
		(net "PCIE_IOM_TO_COMP_13_DN")
	)
	(segment
		(start 148.418042 -26.257504)
		(end 145.384266 -24.235156)
		(width 0.14605)
		(layer "B.Cu")
		(net "PCIE_IOM_TO_COMP_13_DN")
	)
	(segment
		(start 155.327604 -75.027536)
		(end 154.728672 -74.1299)
		(width 0.14605)
		(layer "B.Cu")
		(net "PCIE_IOM_TO_COMP_13_DN")
	)
	(segment
		(start 154.330146 -46.55185)
		(end 151.067516 -30.231588)
		(width 0.14605)
		(layer "B.Cu")
		(net "PCIE_IOM_TO_COMP_13_DN")
	)
	(segment
		(start 191.78905 -81.548732)
		(end 191.78905 -83.339432)
		(width 0.14605)
		(layer "B.Cu")
		(net "PCIE_IOM_TO_COMP_13_DN")
	)
	(segment
		(start 145.384266 -24.235156)
		(end 136.568434 -24.235156)
		(width 0.14605)
		(layer "B.Cu")
		(net "PCIE_IOM_TO_COMP_13_DN")
	)
	(arc
		(start 132.128514 -37.6555)
		(mid 132.194222 -37.66857)
		(end 132.249926 -37.705792)
		(width 0.14605)
		(layer "B.Cu")
		(net "PCIE_IOM_TO_COMP_13_DN")
	)
	(arc
		(start 132.249926 -37.705792)
		(mid 132.286937 -37.761277)
		(end 132.299964 -37.826696)
		(width 0.14605)
		(layer "B.Cu")
		(net "PCIE_IOM_TO_COMP_13_DN")
	)
	(arc
		(start 131.24434 -37.053774)
		(mid 131.420581 -37.479259)
		(end 131.846066 -37.6555)
		(width 0.14605)
		(layer "B.Cu")
		(net "PCIE_IOM_TO_COMP_13_DN")
	)
	(segment
		(start 194.799966 -74.30897)
		(end 195.198492 -74.707496)
		(width 0.09525)
		(layer "F.Cu")
		(net "PCIE_IOM_TO_COMP_12_DP_C")
	)
	(segment
		(start 194.799966 -74.299826)
		(end 194.799966 -74.30897)
		(width 0.09525)
		(layer "F.Cu")
		(net "PCIE_IOM_TO_COMP_12_DP_C")
	)
	(via
		(at 195.198492 -74.707496)
		(size 0.4572)
		(drill 0.2032)
		(layers "F.Cu" "B.Cu")
		(net "PCIE_IOM_TO_COMP_12_DP_C")
	)
	(segment
		(start 194.9577 -77.700378)
		(end 194.9577 -77.724)
		(width 0.09525)
		(layer "B.Cu")
		(net "PCIE_IOM_TO_COMP_12_DP_C")
	)
	(segment
		(start 194.9577 -78.4225)
		(end 193.37909 -80.00111)
		(width 0.14605)
		(layer "B.Cu")
		(net "PCIE_IOM_TO_COMP_12_DP_C")
	)
	(segment
		(start 194.8942 -77.636878)
		(end 194.9577 -77.700378)
		(width 0.09525)
		(layer "B.Cu")
		(net "PCIE_IOM_TO_COMP_12_DP_C")
	)
	(segment
		(start 193.37909 -80.751172)
		(end 193.501518 -80.8736)
		(width 0.14605)
		(layer "B.Cu")
		(net "PCIE_IOM_TO_COMP_12_DP_C")
	)
	(segment
		(start 194.9577 -77.724)
		(end 194.9577 -78.4225)
		(width 0.14605)
		(layer "B.Cu")
		(net "PCIE_IOM_TO_COMP_12_DP_C")
	)
	(segment
		(start 194.980052 -74.925936)
		(end 194.980052 -76.571348)
		(width 0.09525)
		(layer "B.Cu")
		(net "PCIE_IOM_TO_COMP_12_DP_C")
	)
	(segment
		(start 194.8942 -76.6572)
		(end 194.8942 -77.636878)
		(width 0.09525)
		(layer "B.Cu")
		(net "PCIE_IOM_TO_COMP_12_DP_C")
	)
	(segment
		(start 193.37909 -80.00111)
		(end 193.37909 -80.751172)
		(width 0.14605)
		(layer "B.Cu")
		(net "PCIE_IOM_TO_COMP_12_DP_C")
	)
	(segment
		(start 194.980052 -76.571348)
		(end 194.8942 -76.6572)
		(width 0.09525)
		(layer "B.Cu")
		(net "PCIE_IOM_TO_COMP_12_DP_C")
	)
	(segment
		(start 195.198492 -74.707496)
		(end 194.980052 -74.925936)
		(width 0.09525)
		(layer "B.Cu")
		(net "PCIE_IOM_TO_COMP_12_DP_C")
	)
	(segment
		(start 144.889474 -25.719786)
		(end 137.25271 -25.719786)
		(width 0.14605)
		(layer "B.Cu")
		(net "PCIE_IOM_TO_COMP_12_DP")
	)
	(segment
		(start 193.374772 -81.559146)
		(end 193.374772 -83.819492)
		(width 0.14605)
		(layer "B.Cu")
		(net "PCIE_IOM_TO_COMP_12_DP")
	)
	(segment
		(start 187.654184 -87.969344)
		(end 187.22467 -88.055196)
		(width 0.14605)
		(layer "B.Cu")
		(net "PCIE_IOM_TO_COMP_12_DP")
	)
	(segment
		(start 154.184096 -76.013564)
		(end 153.377392 -74.798428)
		(width 0.14605)
		(layer "B.Cu")
		(net "PCIE_IOM_TO_COMP_12_DP")
	)
	(segment
		(start 180.122068 -89.060528)
		(end 180.002434 -88.881204)
		(width 0.14605)
		(layer "B.Cu")
		(net "PCIE_IOM_TO_COMP_12_DP")
	)
	(segment
		(start 185.887106 -88.167464)
		(end 185.457592 -88.253316)
		(width 0.14605)
		(layer "B.Cu")
		(net "PCIE_IOM_TO_COMP_12_DP")
	)
	(segment
		(start 193.064892 -84.129372)
		(end 193.064892 -84.344764)
		(width 0.14605)
		(layer "B.Cu")
		(net "PCIE_IOM_TO_COMP_12_DP")
	)
	(segment
		(start 180.73116 -89.027)
		(end 180.551582 -89.14638)
		(width 0.14605)
		(layer "B.Cu")
		(net "PCIE_IOM_TO_COMP_12_DP")
	)
	(segment
		(start 187.773818 -87.79002)
		(end 187.654184 -87.969344)
		(width 0.14605)
		(layer "B.Cu")
		(net "PCIE_IOM_TO_COMP_12_DP")
	)
	(segment
		(start 193.064892 -84.344764)
		(end 192.755012 -84.654644)
		(width 0.14605)
		(layer "B.Cu")
		(net "PCIE_IOM_TO_COMP_12_DP")
	)
	(segment
		(start 176.647602 -88.36533)
		(end 176.527968 -88.186006)
		(width 0.14605)
		(layer "B.Cu")
		(net "PCIE_IOM_TO_COMP_12_DP")
	)
	(segment
		(start 184.90819 -88.518492)
		(end 184.728866 -88.399112)
		(width 0.14605)
		(layer "B.Cu")
		(net "PCIE_IOM_TO_COMP_12_DP")
	)
	(segment
		(start 179.57292 -88.795098)
		(end 179.393596 -88.914732)
		(width 0.14605)
		(layer "B.Cu")
		(net "PCIE_IOM_TO_COMP_12_DP")
	)
	(segment
		(start 180.002434 -88.881204)
		(end 179.57292 -88.795098)
		(width 0.14605)
		(layer "B.Cu")
		(net "PCIE_IOM_TO_COMP_12_DP")
	)
	(segment
		(start 150.244048 -59.128914)
		(end 152.719786 -46.749462)
		(width 0.14605)
		(layer "B.Cu")
		(net "PCIE_IOM_TO_COMP_12_DP")
	)
	(segment
		(start 176.098454 -88.100154)
		(end 175.918876 -88.219534)
		(width 0.14605)
		(layer "B.Cu")
		(net "PCIE_IOM_TO_COMP_12_DP")
	)
	(segment
		(start 193.501518 -81.4324)
		(end 193.374772 -81.559146)
		(width 0.14605)
		(layer "B.Cu")
		(net "PCIE_IOM_TO_COMP_12_DP")
	)
	(segment
		(start 176.527968 -88.186006)
		(end 176.098454 -88.100154)
		(width 0.14605)
		(layer "B.Cu")
		(net "PCIE_IOM_TO_COMP_12_DP")
	)
	(segment
		(start 134.100062 -35.918394)
		(end 134.100062 -35.600132)
		(width 0.14605)
		(layer "B.Cu")
		(net "PCIE_IOM_TO_COMP_12_DP")
	)
	(segment
		(start 179.393596 -88.914732)
		(end 178.963828 -88.82888)
		(width 0.14605)
		(layer "B.Cu")
		(net "PCIE_IOM_TO_COMP_12_DP")
	)
	(segment
		(start 178.235356 -88.683084)
		(end 177.805842 -88.596978)
		(width 0.14605)
		(layer "B.Cu")
		(net "PCIE_IOM_TO_COMP_12_DP")
	)
	(segment
		(start 175.369728 -87.954358)
		(end 170.690794 -87.018114)
		(width 0.14605)
		(layer "B.Cu")
		(net "PCIE_IOM_TO_COMP_12_DP")
	)
	(segment
		(start 152.719786 -46.749462)
		(end 149.556724 -30.930088)
		(width 0.14605)
		(layer "B.Cu")
		(net "PCIE_IOM_TO_COMP_12_DP")
	)
	(segment
		(start 153.377392 -74.798428)
		(end 150.244048 -59.128914)
		(width 0.14605)
		(layer "B.Cu")
		(net "PCIE_IOM_TO_COMP_12_DP")
	)
	(segment
		(start 185.457592 -88.253316)
		(end 185.337958 -88.43264)
		(width 0.14605)
		(layer "B.Cu")
		(net "PCIE_IOM_TO_COMP_12_DP")
	)
	(segment
		(start 190.803022 -86.391242)
		(end 189.361572 -87.472266)
		(width 0.14605)
		(layer "B.Cu")
		(net "PCIE_IOM_TO_COMP_12_DP")
	)
	(segment
		(start 177.805842 -88.596978)
		(end 177.686208 -88.417654)
		(width 0.14605)
		(layer "B.Cu")
		(net "PCIE_IOM_TO_COMP_12_DP")
	)
	(segment
		(start 188.932058 -87.558118)
		(end 188.812424 -87.737442)
		(width 0.14605)
		(layer "B.Cu")
		(net "PCIE_IOM_TO_COMP_12_DP")
	)
	(segment
		(start 177.256694 -88.331802)
		(end 177.07737 -88.451182)
		(width 0.14605)
		(layer "B.Cu")
		(net "PCIE_IOM_TO_COMP_12_DP")
	)
	(segment
		(start 177.686208 -88.417654)
		(end 177.256694 -88.331802)
		(width 0.14605)
		(layer "B.Cu")
		(net "PCIE_IOM_TO_COMP_12_DP")
	)
	(segment
		(start 193.374772 -83.819492)
		(end 193.064892 -84.129372)
		(width 0.14605)
		(layer "B.Cu")
		(net "PCIE_IOM_TO_COMP_12_DP")
	)
	(segment
		(start 133.646164 -36.144454)
		(end 133.874256 -36.144454)
		(width 0.14605)
		(layer "B.Cu")
		(net "PCIE_IOM_TO_COMP_12_DP")
	)
	(segment
		(start 178.844448 -88.649302)
		(end 178.41468 -88.56345)
		(width 0.14605)
		(layer "B.Cu")
		(net "PCIE_IOM_TO_COMP_12_DP")
	)
	(segment
		(start 181.160674 -89.112852)
		(end 180.73116 -89.027)
		(width 0.14605)
		(layer "B.Cu")
		(net "PCIE_IOM_TO_COMP_12_DP")
	)
	(segment
		(start 170.690794 -87.018114)
		(end 154.184096 -76.013564)
		(width 0.14605)
		(layer "B.Cu")
		(net "PCIE_IOM_TO_COMP_12_DP")
	)
	(segment
		(start 147.039584 -27.153616)
		(end 144.889474 -25.719786)
		(width 0.14605)
		(layer "B.Cu")
		(net "PCIE_IOM_TO_COMP_12_DP")
	)
	(segment
		(start 186.496198 -88.200992)
		(end 186.06643 -88.286844)
		(width 0.14605)
		(layer "B.Cu")
		(net "PCIE_IOM_TO_COMP_12_DP")
	)
	(segment
		(start 137.25271 -25.719786)
		(end 133.355588 -29.616908)
		(width 0.14605)
		(layer "B.Cu")
		(net "PCIE_IOM_TO_COMP_12_DP")
	)
	(segment
		(start 191.91986 -85.489796)
		(end 191.704468 -85.489796)
		(width 0.14605)
		(layer "B.Cu")
		(net "PCIE_IOM_TO_COMP_12_DP")
	)
	(segment
		(start 192.53962 -84.654644)
		(end 192.22974 -84.964524)
		(width 0.14605)
		(layer "B.Cu")
		(net "PCIE_IOM_TO_COMP_12_DP")
	)
	(segment
		(start 186.06643 -88.286844)
		(end 185.887106 -88.167464)
		(width 0.14605)
		(layer "B.Cu")
		(net "PCIE_IOM_TO_COMP_12_DP")
	)
	(segment
		(start 189.361572 -87.472266)
		(end 188.932058 -87.558118)
		(width 0.14605)
		(layer "B.Cu")
		(net "PCIE_IOM_TO_COMP_12_DP")
	)
	(segment
		(start 184.728866 -88.399112)
		(end 181.160674 -89.112852)
		(width 0.14605)
		(layer "B.Cu")
		(net "PCIE_IOM_TO_COMP_12_DP")
	)
	(segment
		(start 177.07737 -88.451182)
		(end 176.647602 -88.36533)
		(width 0.14605)
		(layer "B.Cu")
		(net "PCIE_IOM_TO_COMP_12_DP")
	)
	(segment
		(start 192.755012 -84.654644)
		(end 192.53962 -84.654644)
		(width 0.14605)
		(layer "B.Cu")
		(net "PCIE_IOM_TO_COMP_12_DP")
	)
	(segment
		(start 187.22467 -88.055196)
		(end 187.045346 -87.935562)
		(width 0.14605)
		(layer "B.Cu")
		(net "PCIE_IOM_TO_COMP_12_DP")
	)
	(segment
		(start 175.489362 -88.133682)
		(end 175.369728 -87.954358)
		(width 0.14605)
		(layer "B.Cu")
		(net "PCIE_IOM_TO_COMP_12_DP")
	)
	(segment
		(start 133.355588 -29.616908)
		(end 133.355588 -35.853878)
		(width 0.14605)
		(layer "B.Cu")
		(net "PCIE_IOM_TO_COMP_12_DP")
	)
	(segment
		(start 186.615578 -88.021668)
		(end 186.496198 -88.200992)
		(width 0.14605)
		(layer "B.Cu")
		(net "PCIE_IOM_TO_COMP_12_DP")
	)
	(segment
		(start 188.812424 -87.737442)
		(end 188.382656 -87.823548)
		(width 0.14605)
		(layer "B.Cu")
		(net "PCIE_IOM_TO_COMP_12_DP")
	)
	(segment
		(start 178.41468 -88.56345)
		(end 178.235356 -88.683084)
		(width 0.14605)
		(layer "B.Cu")
		(net "PCIE_IOM_TO_COMP_12_DP")
	)
	(segment
		(start 175.918876 -88.219534)
		(end 175.489362 -88.133682)
		(width 0.14605)
		(layer "B.Cu")
		(net "PCIE_IOM_TO_COMP_12_DP")
	)
	(segment
		(start 188.382656 -87.823548)
		(end 188.203332 -87.703914)
		(width 0.14605)
		(layer "B.Cu")
		(net "PCIE_IOM_TO_COMP_12_DP")
	)
	(segment
		(start 191.704468 -85.489796)
		(end 190.803022 -86.391242)
		(width 0.14605)
		(layer "B.Cu")
		(net "PCIE_IOM_TO_COMP_12_DP")
	)
	(segment
		(start 149.556724 -30.930088)
		(end 147.039584 -27.153616)
		(width 0.14605)
		(layer "B.Cu")
		(net "PCIE_IOM_TO_COMP_12_DP")
	)
	(segment
		(start 187.045346 -87.935562)
		(end 186.615578 -88.021668)
		(width 0.14605)
		(layer "B.Cu")
		(net "PCIE_IOM_TO_COMP_12_DP")
	)
	(segment
		(start 178.963828 -88.82888)
		(end 178.844448 -88.649302)
		(width 0.14605)
		(layer "B.Cu")
		(net "PCIE_IOM_TO_COMP_12_DP")
	)
	(segment
		(start 192.22974 -84.964524)
		(end 192.22974 -85.179916)
		(width 0.14605)
		(layer "B.Cu")
		(net "PCIE_IOM_TO_COMP_12_DP")
	)
	(segment
		(start 185.337958 -88.43264)
		(end 184.90819 -88.518492)
		(width 0.14605)
		(layer "B.Cu")
		(net "PCIE_IOM_TO_COMP_12_DP")
	)
	(segment
		(start 180.551582 -89.14638)
		(end 180.122068 -89.060528)
		(width 0.14605)
		(layer "B.Cu")
		(net "PCIE_IOM_TO_COMP_12_DP")
	)
	(segment
		(start 192.22974 -85.179916)
		(end 191.91986 -85.489796)
		(width 0.14605)
		(layer "B.Cu")
		(net "PCIE_IOM_TO_COMP_12_DP")
	)
	(segment
		(start 188.203332 -87.703914)
		(end 187.773818 -87.79002)
		(width 0.14605)
		(layer "B.Cu")
		(net "PCIE_IOM_TO_COMP_12_DP")
	)
	(arc
		(start 133.355588 -35.853878)
		(mid 133.440696 -36.059346)
		(end 133.646164 -36.144454)
		(width 0.14605)
		(layer "B.Cu")
		(net "PCIE_IOM_TO_COMP_12_DP")
	)
	(arc
		(start 133.874256 -36.144454)
		(mid 133.960571 -36.127285)
		(end 134.033768 -36.078414)
		(width 0.14605)
		(layer "B.Cu")
		(net "PCIE_IOM_TO_COMP_12_DP")
	)
	(arc
		(start 134.033768 -36.078414)
		(mid 134.082824 -36.004996)
		(end 134.100062 -35.918394)
		(width 0.14605)
		(layer "B.Cu")
		(net "PCIE_IOM_TO_COMP_12_DP")
	)
	(segment
		(start 194.799966 -73.49998)
		(end 195.199762 -73.899776)
		(width 0.09525)
		(layer "F.Cu")
		(net "PCIE_IOM_TO_COMP_12_DN_C")
	)
	(via
		(at 195.199762 -73.899776)
		(size 0.4572)
		(drill 0.2032)
		(layers "F.Cu" "B.Cu")
		(net "PCIE_IOM_TO_COMP_12_DN_C")
	)
	(segment
		(start 194.71005 -77.636878)
		(end 194.64655 -77.700378)
		(width 0.09525)
		(layer "B.Cu")
		(net "PCIE_IOM_TO_COMP_12_DN_C")
	)
	(segment
		(start 194.795902 -74.573892)
		(end 194.795902 -76.494894)
		(width 0.09525)
		(layer "B.Cu")
		(net "PCIE_IOM_TO_COMP_12_DN_C")
	)
	(segment
		(start 192.942972 -80.8736)
		(end 192.942718 -80.8736)
		(width 0.136652)
		(layer "B.Cu")
		(net "PCIE_IOM_TO_COMP_12_DN_C")
	)
	(segment
		(start 194.795902 -76.494894)
		(end 194.71005 -76.580746)
		(width 0.09525)
		(layer "B.Cu")
		(net "PCIE_IOM_TO_COMP_12_DN_C")
	)
	(segment
		(start 194.71005 -76.580746)
		(end 194.71005 -77.636878)
		(width 0.09525)
		(layer "B.Cu")
		(net "PCIE_IOM_TO_COMP_12_DN_C")
	)
	(segment
		(start 193.06794 -79.872078)
		(end 193.06794 -80.748632)
		(width 0.14605)
		(layer "B.Cu")
		(net "PCIE_IOM_TO_COMP_12_DN_C")
	)
	(segment
		(start 194.64655 -77.724)
		(end 194.64655 -78.293468)
		(width 0.14605)
		(layer "B.Cu")
		(net "PCIE_IOM_TO_COMP_12_DN_C")
	)
	(segment
		(start 194.64655 -77.700378)
		(end 194.64655 -77.724)
		(width 0.09525)
		(layer "B.Cu")
		(net "PCIE_IOM_TO_COMP_12_DN_C")
	)
	(segment
		(start 195.199762 -73.899776)
		(end 194.795902 -74.573892)
		(width 0.09525)
		(layer "B.Cu")
		(net "PCIE_IOM_TO_COMP_12_DN_C")
	)
	(segment
		(start 194.64655 -78.293468)
		(end 193.06794 -79.872078)
		(width 0.14605)
		(layer "B.Cu")
		(net "PCIE_IOM_TO_COMP_12_DN_C")
	)
	(segment
		(start 193.06794 -80.748632)
		(end 192.942972 -80.8736)
		(width 0.14605)
		(layer "B.Cu")
		(net "PCIE_IOM_TO_COMP_12_DN_C")
	)
	(segment
		(start 154.408886 -75.789282)
		(end 153.670508 -74.67727)
		(width 0.14605)
		(layer "B.Cu")
		(net "PCIE_IOM_TO_COMP_12_DN")
	)
	(segment
		(start 133.044438 -29.487876)
		(end 133.044438 -35.853878)
		(width 0.14605)
		(layer "B.Cu")
		(net "PCIE_IOM_TO_COMP_12_DN")
	)
	(segment
		(start 193.063622 -81.553304)
		(end 193.063622 -83.69046)
		(width 0.14605)
		(layer "B.Cu")
		(net "PCIE_IOM_TO_COMP_12_DN")
	)
	(segment
		(start 144.983708 -25.408636)
		(end 137.123678 -25.408636)
		(width 0.14605)
		(layer "B.Cu")
		(net "PCIE_IOM_TO_COMP_12_DN")
	)
	(segment
		(start 153.670508 -74.67727)
		(end 150.561548 -59.128914)
		(width 0.14605)
		(layer "B.Cu")
		(net "PCIE_IOM_TO_COMP_12_DN")
	)
	(segment
		(start 192.942718 -81.4324)
		(end 193.063622 -81.553304)
		(width 0.14605)
		(layer "B.Cu")
		(net "PCIE_IOM_TO_COMP_12_DN")
	)
	(segment
		(start 181.160674 -88.795352)
		(end 170.812206 -86.724998)
		(width 0.14605)
		(layer "B.Cu")
		(net "PCIE_IOM_TO_COMP_12_DN")
	)
	(segment
		(start 149.84984 -30.808676)
		(end 147.26412 -26.92908)
		(width 0.14605)
		(layer "B.Cu")
		(net "PCIE_IOM_TO_COMP_12_DN")
	)
	(segment
		(start 170.812206 -86.724998)
		(end 154.408886 -75.789282)
		(width 0.14605)
		(layer "B.Cu")
		(net "PCIE_IOM_TO_COMP_12_DN")
	)
	(segment
		(start 134.100062 -36.6268)
		(end 134.100062 -37.00018)
		(width 0.14605)
		(layer "B.Cu")
		(net "PCIE_IOM_TO_COMP_12_DN")
	)
	(segment
		(start 133.646164 -36.455604)
		(end 133.928612 -36.455604)
		(width 0.14605)
		(layer "B.Cu")
		(net "PCIE_IOM_TO_COMP_12_DN")
	)
	(segment
		(start 189.23127 -87.180928)
		(end 181.160674 -88.795352)
		(width 0.14605)
		(layer "B.Cu")
		(net "PCIE_IOM_TO_COMP_12_DN")
	)
	(segment
		(start 153.037286 -46.749462)
		(end 149.84984 -30.808676)
		(width 0.14605)
		(layer "B.Cu")
		(net "PCIE_IOM_TO_COMP_12_DN")
	)
	(segment
		(start 147.26412 -26.92908)
		(end 144.983708 -25.408636)
		(width 0.14605)
		(layer "B.Cu")
		(net "PCIE_IOM_TO_COMP_12_DN")
	)
	(segment
		(start 190.598552 -86.15553)
		(end 189.23127 -87.180928)
		(width 0.14605)
		(layer "B.Cu")
		(net "PCIE_IOM_TO_COMP_12_DN")
	)
	(segment
		(start 193.063622 -83.69046)
		(end 190.598552 -86.15553)
		(width 0.14605)
		(layer "B.Cu")
		(net "PCIE_IOM_TO_COMP_12_DN")
	)
	(segment
		(start 137.123678 -25.408636)
		(end 133.044438 -29.487876)
		(width 0.14605)
		(layer "B.Cu")
		(net "PCIE_IOM_TO_COMP_12_DN")
	)
	(segment
		(start 150.561548 -59.128914)
		(end 153.037286 -46.749462)
		(width 0.14605)
		(layer "B.Cu")
		(net "PCIE_IOM_TO_COMP_12_DN")
	)
	(arc
		(start 133.928612 -36.455604)
		(mid 133.99432 -36.468674)
		(end 134.050024 -36.505896)
		(width 0.14605)
		(layer "B.Cu")
		(net "PCIE_IOM_TO_COMP_12_DN")
	)
	(arc
		(start 133.044438 -35.853878)
		(mid 133.220679 -36.279363)
		(end 133.646164 -36.455604)
		(width 0.14605)
		(layer "B.Cu")
		(net "PCIE_IOM_TO_COMP_12_DN")
	)
	(arc
		(start 134.050024 -36.505896)
		(mid 134.087035 -36.561381)
		(end 134.100062 -36.6268)
		(width 0.14605)
		(layer "B.Cu")
		(net "PCIE_IOM_TO_COMP_12_DN")
	)
	(segment
		(start 196.409564 -74.299826)
		(end 196.80809 -74.698352)
		(width 0.09525)
		(layer "F.Cu")
		(net "PCIE_IOM_TO_COMP_11_DP_C")
	)
	(segment
		(start 196.399912 -74.299826)
		(end 196.409564 -74.299826)
		(width 0.09525)
		(layer "F.Cu")
		(net "PCIE_IOM_TO_COMP_11_DP_C")
	)
	(via
		(at 196.80809 -74.698352)
		(size 0.4572)
		(drill 0.2032)
		(layers "F.Cu" "B.Cu")
		(net "PCIE_IOM_TO_COMP_11_DP_C")
	)
	(segment
		(start 196.94779 -76.77785)
		(end 196.94779 -78.778608)
		(width 0.14605)
		(layer "B.Cu")
		(net "PCIE_IOM_TO_COMP_11_DP_C")
	)
	(segment
		(start 196.88429 -75.586844)
		(end 196.88429 -76.690728)
		(width 0.09525)
		(layer "B.Cu")
		(net "PCIE_IOM_TO_COMP_11_DP_C")
	)
	(segment
		(start 196.94779 -76.754228)
		(end 196.94779 -76.77785)
		(width 0.09525)
		(layer "B.Cu")
		(net "PCIE_IOM_TO_COMP_11_DP_C")
	)
	(segment
		(start 196.80809 -75.510644)
		(end 196.88429 -75.586844)
		(width 0.09525)
		(layer "B.Cu")
		(net "PCIE_IOM_TO_COMP_11_DP_C")
	)
	(segment
		(start 196.80809 -74.698352)
		(end 196.80809 -75.510644)
		(width 0.09525)
		(layer "B.Cu")
		(net "PCIE_IOM_TO_COMP_11_DP_C")
	)
	(segment
		(start 196.88429 -76.690728)
		(end 196.94779 -76.754228)
		(width 0.09525)
		(layer "B.Cu")
		(net "PCIE_IOM_TO_COMP_11_DP_C")
	)
	(segment
		(start 196.94779 -78.778608)
		(end 197.698614 -79.529432)
		(width 0.14605)
		(layer "B.Cu")
		(net "PCIE_IOM_TO_COMP_11_DP_C")
	)
	(segment
		(start 197.698614 -80.752696)
		(end 197.819518 -80.8736)
		(width 0.14605)
		(layer "B.Cu")
		(net "PCIE_IOM_TO_COMP_11_DP_C")
	)
	(segment
		(start 197.698614 -79.529432)
		(end 197.698614 -80.752696)
		(width 0.14605)
		(layer "B.Cu")
		(net "PCIE_IOM_TO_COMP_11_DP_C")
	)
	(segment
		(start 171.809664 -88.805512)
		(end 172.239432 -88.891618)
		(width 0.14605)
		(layer "B.Cu")
		(net "PCIE_IOM_TO_COMP_11_DP")
	)
	(segment
		(start 182.569358 -90.957146)
		(end 182.998872 -91.042998)
		(width 0.14605)
		(layer "B.Cu")
		(net "PCIE_IOM_TO_COMP_11_DP")
	)
	(segment
		(start 135.990584 -28.67152)
		(end 137.799318 -26.862786)
		(width 0.14605)
		(layer "B.Cu")
		(net "PCIE_IOM_TO_COMP_11_DP")
	)
	(segment
		(start 184.766204 -91.241118)
		(end 185.735722 -91.047316)
		(width 0.14605)
		(layer "B.Cu")
		(net "PCIE_IOM_TO_COMP_11_DP")
	)
	(segment
		(start 153.301192 -76.799186)
		(end 170.763692 -88.441022)
		(width 0.14605)
		(layer "B.Cu")
		(net "PCIE_IOM_TO_COMP_11_DP")
	)
	(segment
		(start 181.840632 -90.81135)
		(end 182.019956 -90.69197)
		(width 0.14605)
		(layer "B.Cu")
		(net "PCIE_IOM_TO_COMP_11_DP")
	)
	(segment
		(start 180.861716 -90.460322)
		(end 181.291484 -90.546174)
		(width 0.14605)
		(layer "B.Cu")
		(net "PCIE_IOM_TO_COMP_11_DP")
	)
	(segment
		(start 135.680704 -29.196792)
		(end 135.990584 -28.886912)
		(width 0.14605)
		(layer "B.Cu")
		(net "PCIE_IOM_TO_COMP_11_DP")
	)
	(segment
		(start 180.252878 -90.49385)
		(end 180.682392 -90.579702)
		(width 0.14605)
		(layer "B.Cu")
		(net "PCIE_IOM_TO_COMP_11_DP")
	)
	(segment
		(start 191.411352 -88.528144)
		(end 191.775842 -88.28532)
		(width 0.14605)
		(layer "B.Cu")
		(net "PCIE_IOM_TO_COMP_11_DP")
	)
	(segment
		(start 172.967904 -89.03716)
		(end 173.397672 -89.123266)
		(width 0.14605)
		(layer "B.Cu")
		(net "PCIE_IOM_TO_COMP_11_DP")
	)
	(segment
		(start 171.040044 -88.496394)
		(end 171.69003 -88.626188)
		(width 0.14605)
		(layer "B.Cu")
		(net "PCIE_IOM_TO_COMP_11_DP")
	)
	(segment
		(start 183.727598 -91.188794)
		(end 184.157112 -91.274646)
		(width 0.14605)
		(layer "B.Cu")
		(net "PCIE_IOM_TO_COMP_11_DP")
	)
	(segment
		(start 135.155432 -37.053774)
		(end 135.155432 -29.506672)
		(width 0.14605)
		(layer "B.Cu")
		(net "PCIE_IOM_TO_COMP_11_DP")
	)
	(segment
		(start 190.428626 -89.18321)
		(end 190.793116 -88.940386)
		(width 0.14605)
		(layer "B.Cu")
		(net "PCIE_IOM_TO_COMP_11_DP")
	)
	(segment
		(start 191.81826 -88.073992)
		(end 192.18275 -87.830914)
		(width 0.14605)
		(layer "B.Cu")
		(net "PCIE_IOM_TO_COMP_11_DP")
	)
	(segment
		(start 180.682392 -90.579702)
		(end 180.861716 -90.460322)
		(width 0.14605)
		(layer "B.Cu")
		(net "PCIE_IOM_TO_COMP_11_DP")
	)
	(segment
		(start 189.4459 -89.838276)
		(end 189.81039 -89.595452)
		(width 0.14605)
		(layer "B.Cu")
		(net "PCIE_IOM_TO_COMP_11_DP")
	)
	(segment
		(start 181.291484 -90.546174)
		(end 181.411118 -90.725498)
		(width 0.14605)
		(layer "B.Cu")
		(net "PCIE_IOM_TO_COMP_11_DP")
	)
	(segment
		(start 172.239432 -88.891618)
		(end 172.418756 -88.771984)
		(width 0.14605)
		(layer "B.Cu")
		(net "PCIE_IOM_TO_COMP_11_DP")
	)
	(segment
		(start 137.799318 -26.862786)
		(end 144.41932 -26.862786)
		(width 0.14605)
		(layer "B.Cu")
		(net "PCIE_IOM_TO_COMP_11_DP")
	)
	(segment
		(start 185.915046 -91.166696)
		(end 186.344814 -91.080844)
		(width 0.14605)
		(layer "B.Cu")
		(net "PCIE_IOM_TO_COMP_11_DP")
	)
	(segment
		(start 146.159728 -28.023058)
		(end 146.4945 -28.52547)
		(width 0.14605)
		(layer "B.Cu")
		(net "PCIE_IOM_TO_COMP_11_DP")
	)
	(segment
		(start 189.852808 -89.384124)
		(end 190.217298 -89.141046)
		(width 0.14605)
		(layer "B.Cu")
		(net "PCIE_IOM_TO_COMP_11_DP")
	)
	(segment
		(start 185.735722 -91.047316)
		(end 185.915046 -91.166696)
		(width 0.14605)
		(layer "B.Cu")
		(net "PCIE_IOM_TO_COMP_11_DP")
	)
	(segment
		(start 171.69003 -88.626188)
		(end 171.809664 -88.805512)
		(width 0.14605)
		(layer "B.Cu")
		(net "PCIE_IOM_TO_COMP_11_DP")
	)
	(segment
		(start 192.18275 -87.830914)
		(end 197.692772 -82.320638)
		(width 0.14605)
		(layer "B.Cu")
		(net "PCIE_IOM_TO_COMP_11_DP")
	)
	(segment
		(start 190.793116 -88.940386)
		(end 190.835534 -88.729058)
		(width 0.14605)
		(layer "B.Cu")
		(net "PCIE_IOM_TO_COMP_11_DP")
	)
	(segment
		(start 174.126144 -89.268808)
		(end 174.555912 -89.354914)
		(width 0.14605)
		(layer "B.Cu")
		(net "PCIE_IOM_TO_COMP_11_DP")
	)
	(segment
		(start 180.133244 -90.31478)
		(end 180.133244 -90.314526)
		(width 0.14605)
		(layer "B.Cu")
		(net "PCIE_IOM_TO_COMP_11_DP")
	)
	(segment
		(start 190.835534 -88.729058)
		(end 191.200024 -88.48598)
		(width 0.14605)
		(layer "B.Cu")
		(net "PCIE_IOM_TO_COMP_11_DP")
	)
	(segment
		(start 146.67611 -28.798012)
		(end 148.483574 -31.50997)
		(width 0.14605)
		(layer "B.Cu")
		(net "PCIE_IOM_TO_COMP_11_DP")
	)
	(segment
		(start 146.4945 -28.52547)
		(end 146.67611 -28.798012)
		(width 0.14605)
		(layer "B.Cu")
		(net "PCIE_IOM_TO_COMP_11_DP")
	)
	(segment
		(start 191.775842 -88.28532)
		(end 191.81826 -88.073992)
		(width 0.14605)
		(layer "B.Cu")
		(net "PCIE_IOM_TO_COMP_11_DP")
	)
	(segment
		(start 144.41932 -26.862786)
		(end 146.159728 -28.023058)
		(width 0.14605)
		(layer "B.Cu")
		(net "PCIE_IOM_TO_COMP_11_DP")
	)
	(segment
		(start 182.449724 -90.777822)
		(end 182.569358 -90.957146)
		(width 0.14605)
		(layer "B.Cu")
		(net "PCIE_IOM_TO_COMP_11_DP")
	)
	(segment
		(start 182.019956 -90.69197)
		(end 182.449724 -90.777822)
		(width 0.14605)
		(layer "B.Cu")
		(net "PCIE_IOM_TO_COMP_11_DP")
	)
	(segment
		(start 189.81039 -89.595452)
		(end 189.852808 -89.384124)
		(width 0.14605)
		(layer "B.Cu")
		(net "PCIE_IOM_TO_COMP_11_DP")
	)
	(segment
		(start 173.397672 -89.123266)
		(end 173.576996 -89.003632)
		(width 0.14605)
		(layer "B.Cu")
		(net "PCIE_IOM_TO_COMP_11_DP")
	)
	(segment
		(start 184.157112 -91.274646)
		(end 184.336436 -91.155266)
		(width 0.14605)
		(layer "B.Cu")
		(net "PCIE_IOM_TO_COMP_11_DP")
	)
	(segment
		(start 184.336436 -91.155266)
		(end 184.766204 -91.241118)
		(width 0.14605)
		(layer "B.Cu")
		(net "PCIE_IOM_TO_COMP_11_DP")
	)
	(segment
		(start 187.503054 -90.849196)
		(end 187.622434 -90.669872)
		(width 0.14605)
		(layer "B.Cu")
		(net "PCIE_IOM_TO_COMP_11_DP")
	)
	(segment
		(start 181.411118 -90.725498)
		(end 181.840632 -90.81135)
		(width 0.14605)
		(layer "B.Cu")
		(net "PCIE_IOM_TO_COMP_11_DP")
	)
	(segment
		(start 174.735236 -89.23528)
		(end 180.133244 -90.31478)
		(width 0.14605)
		(layer "B.Cu")
		(net "PCIE_IOM_TO_COMP_11_DP")
	)
	(segment
		(start 135.990584 -28.886912)
		(end 135.990584 -28.67152)
		(width 0.14605)
		(layer "B.Cu")
		(net "PCIE_IOM_TO_COMP_11_DP")
	)
	(segment
		(start 150.691088 -67.222116)
		(end 152.30983 -75.312524)
		(width 0.14605)
		(layer "B.Cu")
		(net "PCIE_IOM_TO_COMP_11_DP")
	)
	(segment
		(start 190.217298 -89.141046)
		(end 190.428626 -89.18321)
		(width 0.14605)
		(layer "B.Cu")
		(net "PCIE_IOM_TO_COMP_11_DP")
	)
	(segment
		(start 174.555912 -89.354914)
		(end 174.735236 -89.23528)
		(width 0.14605)
		(layer "B.Cu")
		(net "PCIE_IOM_TO_COMP_11_DP")
	)
	(segment
		(start 173.576996 -89.003632)
		(end 174.006764 -89.089484)
		(width 0.14605)
		(layer "B.Cu")
		(net "PCIE_IOM_TO_COMP_11_DP")
	)
	(segment
		(start 187.073286 -90.935048)
		(end 187.503054 -90.849196)
		(width 0.14605)
		(layer "B.Cu")
		(net "PCIE_IOM_TO_COMP_11_DP")
	)
	(segment
		(start 180.133244 -90.314526)
		(end 180.252878 -90.49385)
		(width 0.14605)
		(layer "B.Cu")
		(net "PCIE_IOM_TO_COMP_11_DP")
	)
	(segment
		(start 191.200024 -88.48598)
		(end 191.411352 -88.528144)
		(width 0.14605)
		(layer "B.Cu")
		(net "PCIE_IOM_TO_COMP_11_DP")
	)
	(segment
		(start 151.537924 -46.796706)
		(end 149.072092 -59.130946)
		(width 0.14605)
		(layer "B.Cu")
		(net "PCIE_IOM_TO_COMP_11_DP")
	)
	(segment
		(start 189.234572 -89.796112)
		(end 189.4459 -89.838276)
		(width 0.14605)
		(layer "B.Cu")
		(net "PCIE_IOM_TO_COMP_11_DP")
	)
	(segment
		(start 186.464194 -90.90152)
		(end 186.893962 -90.815668)
		(width 0.14605)
		(layer "B.Cu")
		(net "PCIE_IOM_TO_COMP_11_DP")
	)
	(segment
		(start 172.848524 -88.857836)
		(end 172.967904 -89.03716)
		(width 0.14605)
		(layer "B.Cu")
		(net "PCIE_IOM_TO_COMP_11_DP")
	)
	(segment
		(start 148.483574 -31.50997)
		(end 151.537924 -46.796706)
		(width 0.14605)
		(layer "B.Cu")
		(net "PCIE_IOM_TO_COMP_11_DP")
	)
	(segment
		(start 135.155432 -29.506672)
		(end 135.465312 -29.196792)
		(width 0.14605)
		(layer "B.Cu")
		(net "PCIE_IOM_TO_COMP_11_DP")
	)
	(segment
		(start 186.893962 -90.815668)
		(end 187.073286 -90.935048)
		(width 0.14605)
		(layer "B.Cu")
		(net "PCIE_IOM_TO_COMP_11_DP")
	)
	(segment
		(start 174.006764 -89.089484)
		(end 174.126144 -89.268808)
		(width 0.14605)
		(layer "B.Cu")
		(net "PCIE_IOM_TO_COMP_11_DP")
	)
	(segment
		(start 152.30983 -75.312524)
		(end 153.301192 -76.799186)
		(width 0.14605)
		(layer "B.Cu")
		(net "PCIE_IOM_TO_COMP_11_DP")
	)
	(segment
		(start 172.418756 -88.771984)
		(end 172.848524 -88.857836)
		(width 0.14605)
		(layer "B.Cu")
		(net "PCIE_IOM_TO_COMP_11_DP")
	)
	(segment
		(start 197.692772 -81.559146)
		(end 197.819518 -81.4324)
		(width 0.14605)
		(layer "B.Cu")
		(net "PCIE_IOM_TO_COMP_11_DP")
	)
	(segment
		(start 135.465312 -29.196792)
		(end 135.680704 -29.196792)
		(width 0.14605)
		(layer "B.Cu")
		(net "PCIE_IOM_TO_COMP_11_DP")
	)
	(segment
		(start 197.692772 -82.320638)
		(end 197.692772 -81.559146)
		(width 0.14605)
		(layer "B.Cu")
		(net "PCIE_IOM_TO_COMP_11_DP")
	)
	(segment
		(start 186.344814 -91.080844)
		(end 186.464194 -90.90152)
		(width 0.14605)
		(layer "B.Cu")
		(net "PCIE_IOM_TO_COMP_11_DP")
	)
	(segment
		(start 170.763692 -88.441022)
		(end 171.040044 -88.496394)
		(width 0.14605)
		(layer "B.Cu")
		(net "PCIE_IOM_TO_COMP_11_DP")
	)
	(segment
		(start 182.998872 -91.042998)
		(end 183.178196 -90.923618)
		(width 0.14605)
		(layer "B.Cu")
		(net "PCIE_IOM_TO_COMP_11_DP")
	)
	(segment
		(start 135.899906 -36.800028)
		(end 135.899906 -37.11829)
		(width 0.14605)
		(layer "B.Cu")
		(net "PCIE_IOM_TO_COMP_11_DP")
	)
	(segment
		(start 183.178196 -90.923618)
		(end 183.607964 -91.00947)
		(width 0.14605)
		(layer "B.Cu")
		(net "PCIE_IOM_TO_COMP_11_DP")
	)
	(segment
		(start 135.6741 -37.34435)
		(end 135.446008 -37.34435)
		(width 0.14605)
		(layer "B.Cu")
		(net "PCIE_IOM_TO_COMP_11_DP")
	)
	(segment
		(start 149.072092 -59.130946)
		(end 150.691088 -67.222116)
		(width 0.14605)
		(layer "B.Cu")
		(net "PCIE_IOM_TO_COMP_11_DP")
	)
	(segment
		(start 188.052202 -90.58402)
		(end 189.234572 -89.796112)
		(width 0.14605)
		(layer "B.Cu")
		(net "PCIE_IOM_TO_COMP_11_DP")
	)
	(segment
		(start 183.607964 -91.00947)
		(end 183.727598 -91.188794)
		(width 0.14605)
		(layer "B.Cu")
		(net "PCIE_IOM_TO_COMP_11_DP")
	)
	(segment
		(start 187.622434 -90.669872)
		(end 188.052202 -90.58402)
		(width 0.14605)
		(layer "B.Cu")
		(net "PCIE_IOM_TO_COMP_11_DP")
	)
	(arc
		(start 135.899906 -37.11829)
		(mid 135.882679 -37.204897)
		(end 135.833612 -37.27831)
		(width 0.14605)
		(layer "B.Cu")
		(net "PCIE_IOM_TO_COMP_11_DP")
	)
	(arc
		(start 135.446008 -37.34435)
		(mid 135.24054 -37.259242)
		(end 135.155432 -37.053774)
		(width 0.14605)
		(layer "B.Cu")
		(net "PCIE_IOM_TO_COMP_11_DP")
	)
	(arc
		(start 135.833612 -37.27831)
		(mid 135.760427 -37.32721)
		(end 135.6741 -37.34435)
		(width 0.14605)
		(layer "B.Cu")
		(net "PCIE_IOM_TO_COMP_11_DP")
	)
	(segment
		(start 196.399912 -73.49998)
		(end 196.799708 -73.899776)
		(width 0.09525)
		(layer "F.Cu")
		(net "PCIE_IOM_TO_COMP_11_DN_C")
	)
	(via
		(at 196.799708 -73.899776)
		(size 0.4572)
		(drill 0.2032)
		(layers "F.Cu" "B.Cu")
		(net "PCIE_IOM_TO_COMP_11_DN_C")
	)
	(segment
		(start 196.70014 -75.663298)
		(end 196.70014 -76.690728)
		(width 0.09525)
		(layer "B.Cu")
		(net "PCIE_IOM_TO_COMP_11_DN_C")
	)
	(segment
		(start 197.387464 -79.658464)
		(end 197.387464 -80.746854)
		(width 0.14605)
		(layer "B.Cu")
		(net "PCIE_IOM_TO_COMP_11_DN_C")
	)
	(segment
		(start 196.62394 -75.587098)
		(end 196.70014 -75.663298)
		(width 0.09525)
		(layer "B.Cu")
		(net "PCIE_IOM_TO_COMP_11_DN_C")
	)
	(segment
		(start 196.799708 -73.899776)
		(end 196.404738 -74.294746)
		(width 0.09525)
		(layer "B.Cu")
		(net "PCIE_IOM_TO_COMP_11_DN_C")
	)
	(segment
		(start 196.70014 -76.690728)
		(end 196.63664 -76.754228)
		(width 0.09525)
		(layer "B.Cu")
		(net "PCIE_IOM_TO_COMP_11_DN_C")
	)
	(segment
		(start 196.63664 -76.77785)
		(end 196.63664 -78.90764)
		(width 0.14605)
		(layer "B.Cu")
		(net "PCIE_IOM_TO_COMP_11_DN_C")
	)
	(segment
		(start 196.404738 -74.865484)
		(end 196.62394 -75.084686)
		(width 0.09525)
		(layer "B.Cu")
		(net "PCIE_IOM_TO_COMP_11_DN_C")
	)
	(segment
		(start 196.63664 -76.754228)
		(end 196.63664 -76.77785)
		(width 0.09525)
		(layer "B.Cu")
		(net "PCIE_IOM_TO_COMP_11_DN_C")
	)
	(segment
		(start 196.63664 -78.90764)
		(end 197.387464 -79.658464)
		(width 0.14605)
		(layer "B.Cu")
		(net "PCIE_IOM_TO_COMP_11_DN_C")
	)
	(segment
		(start 197.387464 -80.746854)
		(end 197.260718 -80.8736)
		(width 0.14605)
		(layer "B.Cu")
		(net "PCIE_IOM_TO_COMP_11_DN_C")
	)
	(segment
		(start 196.62394 -75.084686)
		(end 196.62394 -75.587098)
		(width 0.09525)
		(layer "B.Cu")
		(net "PCIE_IOM_TO_COMP_11_DN_C")
	)
	(segment
		(start 196.404738 -74.294746)
		(end 196.404738 -74.865484)
		(width 0.09525)
		(layer "B.Cu")
		(net "PCIE_IOM_TO_COMP_11_DN_C")
	)
	(segment
		(start 144.513554 -26.551636)
		(end 146.384264 -27.798522)
		(width 0.14605)
		(layer "B.Cu")
		(net "PCIE_IOM_TO_COMP_11_DN")
	)
	(segment
		(start 137.670286 -26.551636)
		(end 144.513554 -26.551636)
		(width 0.14605)
		(layer "B.Cu")
		(net "PCIE_IOM_TO_COMP_11_DN")
	)
	(segment
		(start 153.525728 -76.57465)
		(end 170.885104 -88.147906)
		(width 0.14605)
		(layer "B.Cu")
		(net "PCIE_IOM_TO_COMP_11_DN")
	)
	(segment
		(start 146.384264 -27.798522)
		(end 148.77669 -31.388558)
		(width 0.14605)
		(layer "B.Cu")
		(net "PCIE_IOM_TO_COMP_11_DN")
	)
	(segment
		(start 187.93079 -90.290904)
		(end 191.984376 -87.588852)
		(width 0.14605)
		(layer "B.Cu")
		(net "PCIE_IOM_TO_COMP_11_DN")
	)
	(segment
		(start 148.77669 -31.388558)
		(end 151.855424 -46.796706)
		(width 0.14605)
		(layer "B.Cu")
		(net "PCIE_IOM_TO_COMP_11_DN")
	)
	(segment
		(start 170.885104 -88.147906)
		(end 184.766204 -90.923618)
		(width 0.14605)
		(layer "B.Cu")
		(net "PCIE_IOM_TO_COMP_11_DN")
	)
	(segment
		(start 197.381622 -82.191606)
		(end 197.381622 -81.553304)
		(width 0.14605)
		(layer "B.Cu")
		(net "PCIE_IOM_TO_COMP_11_DN")
	)
	(segment
		(start 191.984376 -87.588852)
		(end 197.381622 -82.191606)
		(width 0.14605)
		(layer "B.Cu")
		(net "PCIE_IOM_TO_COMP_11_DN")
	)
	(segment
		(start 134.844282 -29.37764)
		(end 137.670286 -26.551636)
		(width 0.14605)
		(layer "B.Cu")
		(net "PCIE_IOM_TO_COMP_11_DN")
	)
	(segment
		(start 135.728456 -37.6555)
		(end 135.446008 -37.6555)
		(width 0.14605)
		(layer "B.Cu")
		(net "PCIE_IOM_TO_COMP_11_DN")
	)
	(segment
		(start 134.844282 -37.053774)
		(end 134.844282 -29.37764)
		(width 0.14605)
		(layer "B.Cu")
		(net "PCIE_IOM_TO_COMP_11_DN")
	)
	(segment
		(start 152.602946 -75.191112)
		(end 153.525728 -76.57465)
		(width 0.14605)
		(layer "B.Cu")
		(net "PCIE_IOM_TO_COMP_11_DN")
	)
	(segment
		(start 151.855424 -46.796706)
		(end 149.389592 -59.130946)
		(width 0.14605)
		(layer "B.Cu")
		(net "PCIE_IOM_TO_COMP_11_DN")
	)
	(segment
		(start 149.389592 -59.130946)
		(end 152.602946 -75.191112)
		(width 0.14605)
		(layer "B.Cu")
		(net "PCIE_IOM_TO_COMP_11_DN")
	)
	(segment
		(start 184.766204 -90.923618)
		(end 187.93079 -90.290904)
		(width 0.14605)
		(layer "B.Cu")
		(net "PCIE_IOM_TO_COMP_11_DN")
	)
	(segment
		(start 197.381622 -81.553304)
		(end 197.260718 -81.4324)
		(width 0.14605)
		(layer "B.Cu")
		(net "PCIE_IOM_TO_COMP_11_DN")
	)
	(segment
		(start 135.899906 -38.200076)
		(end 135.899906 -37.826696)
		(width 0.14605)
		(layer "B.Cu")
		(net "PCIE_IOM_TO_COMP_11_DN")
	)
	(arc
		(start 135.899906 -37.826696)
		(mid 135.886909 -37.761265)
		(end 135.849868 -37.705792)
		(width 0.14605)
		(layer "B.Cu")
		(net "PCIE_IOM_TO_COMP_11_DN")
	)
	(arc
		(start 135.446008 -37.6555)
		(mid 135.020523 -37.479259)
		(end 134.844282 -37.053774)
		(width 0.14605)
		(layer "B.Cu")
		(net "PCIE_IOM_TO_COMP_11_DN")
	)
	(arc
		(start 135.849868 -37.705792)
		(mid 135.794164 -37.668572)
		(end 135.728456 -37.6555)
		(width 0.14605)
		(layer "B.Cu")
		(net "PCIE_IOM_TO_COMP_11_DN")
	)
	(segment
		(start 197.200012 -74.299826)
		(end 197.20941 -74.299826)
		(width 0.09525)
		(layer "F.Cu")
		(net "PCIE_IOM_TO_COMP_10_DP_C")
	)
	(segment
		(start 197.20941 -74.299826)
		(end 197.609206 -74.699622)
		(width 0.09525)
		(layer "F.Cu")
		(net "PCIE_IOM_TO_COMP_10_DP_C")
	)
	(via
		(at 197.609206 -74.699622)
		(size 0.4572)
		(drill 0.2032)
		(layers "F.Cu" "B.Cu")
		(net "PCIE_IOM_TO_COMP_10_DP_C")
	)
	(segment
		(start 197.615556 -74.705972)
		(end 197.615556 -75.670156)
		(width 0.09525)
		(layer "B.Cu")
		(net "PCIE_IOM_TO_COMP_10_DP_C")
	)
	(segment
		(start 198.0692 -76.422504)
		(end 198.0692 -76.446126)
		(width 0.09525)
		(layer "B.Cu")
		(net "PCIE_IOM_TO_COMP_10_DP_C")
	)
	(segment
		(start 198.968614 -77.721714)
		(end 198.968614 -80.752696)
		(width 0.14605)
		(layer "B.Cu")
		(net "PCIE_IOM_TO_COMP_10_DP_C")
	)
	(segment
		(start 198.0692 -76.8223)
		(end 198.968614 -77.721714)
		(width 0.14605)
		(layer "B.Cu")
		(net "PCIE_IOM_TO_COMP_10_DP_C")
	)
	(segment
		(start 197.609206 -74.699622)
		(end 197.615556 -74.705972)
		(width 0.09525)
		(layer "B.Cu")
		(net "PCIE_IOM_TO_COMP_10_DP_C")
	)
	(segment
		(start 198.0057 -76.0603)
		(end 198.0057 -76.359004)
		(width 0.09525)
		(layer "B.Cu")
		(net "PCIE_IOM_TO_COMP_10_DP_C")
	)
	(segment
		(start 197.615556 -75.670156)
		(end 198.0057 -76.0603)
		(width 0.09525)
		(layer "B.Cu")
		(net "PCIE_IOM_TO_COMP_10_DP_C")
	)
	(segment
		(start 198.968614 -80.752696)
		(end 199.089518 -80.8736)
		(width 0.14605)
		(layer "B.Cu")
		(net "PCIE_IOM_TO_COMP_10_DP_C")
	)
	(segment
		(start 198.0057 -76.359004)
		(end 198.0692 -76.422504)
		(width 0.09525)
		(layer "B.Cu")
		(net "PCIE_IOM_TO_COMP_10_DP_C")
	)
	(segment
		(start 198.0692 -76.446126)
		(end 198.0692 -76.8223)
		(width 0.14605)
		(layer "B.Cu")
		(net "PCIE_IOM_TO_COMP_10_DP_C")
	)
	(segment
		(start 149.532848 -43.462448)
		(end 149.619716 -43.891708)
		(width 0.14605)
		(layer "B.Cu")
		(net "PCIE_IOM_TO_COMP_10_DP")
	)
	(segment
		(start 151.203406 -75.754484)
		(end 152.483058 -77.673454)
		(width 0.14605)
		(layer "B.Cu")
		(net "PCIE_IOM_TO_COMP_10_DP")
	)
	(segment
		(start 189.223396 -91.480132)
		(end 189.434724 -91.52255)
		(width 0.14605)
		(layer "B.Cu")
		(net "PCIE_IOM_TO_COMP_10_DP")
	)
	(segment
		(start 147.700746 -33.64484)
		(end 147.58162 -33.824418)
		(width 0.14605)
		(layer "B.Cu")
		(net "PCIE_IOM_TO_COMP_10_DP")
	)
	(segment
		(start 147.58162 -33.824418)
		(end 147.668488 -34.253932)
		(width 0.14605)
		(layer "B.Cu")
		(net "PCIE_IOM_TO_COMP_10_DP")
	)
	(segment
		(start 149.417532 -42.125138)
		(end 149.298406 -42.304716)
		(width 0.14605)
		(layer "B.Cu")
		(net "PCIE_IOM_TO_COMP_10_DP")
	)
	(segment
		(start 148.137372 -36.569396)
		(end 148.317204 -36.688522)
		(width 0.14605)
		(layer "B.Cu")
		(net "PCIE_IOM_TO_COMP_10_DP")
	)
	(segment
		(start 149.651974 -43.282616)
		(end 149.532848 -43.462448)
		(width 0.14605)
		(layer "B.Cu")
		(net "PCIE_IOM_TO_COMP_10_DP")
	)
	(segment
		(start 149.54123 -67.442334)
		(end 151.203406 -75.754484)
		(width 0.14605)
		(layer "B.Cu")
		(net "PCIE_IOM_TO_COMP_10_DP")
	)
	(segment
		(start 188.24067 -92.135452)
		(end 188.451998 -92.177616)
		(width 0.14605)
		(layer "B.Cu")
		(net "PCIE_IOM_TO_COMP_10_DP")
	)
	(segment
		(start 190.206122 -90.825066)
		(end 190.41745 -90.86723)
		(width 0.14605)
		(layer "B.Cu")
		(net "PCIE_IOM_TO_COMP_10_DP")
	)
	(segment
		(start 149.619716 -43.891708)
		(end 149.799294 -44.010834)
		(width 0.14605)
		(layer "B.Cu")
		(net "PCIE_IOM_TO_COMP_10_DP")
	)
	(segment
		(start 190.824358 -90.412824)
		(end 192.171574 -89.51468)
		(width 0.14605)
		(layer "B.Cu")
		(net "PCIE_IOM_TO_COMP_10_DP")
	)
	(segment
		(start 189.841632 -91.068144)
		(end 190.206122 -90.825066)
		(width 0.14605)
		(layer "B.Cu")
		(net "PCIE_IOM_TO_COMP_10_DP")
	)
	(segment
		(start 143.469868 -28.005786)
		(end 145.64614 -29.457904)
		(width 0.14605)
		(layer "B.Cu")
		(net "PCIE_IOM_TO_COMP_10_DP")
	)
	(segment
		(start 149.854158 -45.04944)
		(end 150.033736 -45.168566)
		(width 0.14605)
		(layer "B.Cu")
		(net "PCIE_IOM_TO_COMP_10_DP")
	)
	(segment
		(start 146.502374 -31.016448)
		(end 146.745452 -31.380938)
		(width 0.14605)
		(layer "B.Cu")
		(net "PCIE_IOM_TO_COMP_10_DP")
	)
	(segment
		(start 189.434724 -91.52255)
		(end 189.799214 -91.279472)
		(width 0.14605)
		(layer "B.Cu")
		(net "PCIE_IOM_TO_COMP_10_DP")
	)
	(segment
		(start 150.120604 -45.597826)
		(end 150.001478 -45.777658)
		(width 0.14605)
		(layer "B.Cu")
		(net "PCIE_IOM_TO_COMP_10_DP")
	)
	(segment
		(start 137.474198 -36.144454)
		(end 137.246106 -36.144454)
		(width 0.14605)
		(layer "B.Cu")
		(net "PCIE_IOM_TO_COMP_10_DP")
	)
	(segment
		(start 148.082762 -35.53079)
		(end 148.16963 -35.960304)
		(width 0.14605)
		(layer "B.Cu")
		(net "PCIE_IOM_TO_COMP_10_DP")
	)
	(segment
		(start 150.268178 -46.326044)
		(end 150.355046 -46.755558)
		(width 0.14605)
		(layer "B.Cu")
		(net "PCIE_IOM_TO_COMP_10_DP")
	)
	(segment
		(start 147.4343 -33.0962)
		(end 147.613878 -33.215326)
		(width 0.14605)
		(layer "B.Cu")
		(net "PCIE_IOM_TO_COMP_10_DP")
	)
	(segment
		(start 147.613878 -33.215326)
		(end 147.700746 -33.64484)
		(width 0.14605)
		(layer "B.Cu")
		(net "PCIE_IOM_TO_COMP_10_DP")
	)
	(segment
		(start 183.382158 -93.472)
		(end 187.458604 -92.656914)
		(width 0.14605)
		(layer "B.Cu")
		(net "PCIE_IOM_TO_COMP_10_DP")
	)
	(segment
		(start 136.95553 -30.363414)
		(end 139.313158 -28.005786)
		(width 0.14605)
		(layer "B.Cu")
		(net "PCIE_IOM_TO_COMP_10_DP")
	)
	(segment
		(start 146.30146 -30.44063)
		(end 146.544538 -30.80512)
		(width 0.14605)
		(layer "B.Cu")
		(net "PCIE_IOM_TO_COMP_10_DP")
	)
	(segment
		(start 147.84832 -34.373058)
		(end 147.935188 -34.802572)
		(width 0.14605)
		(layer "B.Cu")
		(net "PCIE_IOM_TO_COMP_10_DP")
	)
	(segment
		(start 148.31695 -36.688522)
		(end 149.417532 -42.125138)
		(width 0.14605)
		(layer "B.Cu")
		(net "PCIE_IOM_TO_COMP_10_DP")
	)
	(segment
		(start 187.458604 -92.656914)
		(end 188.24067 -92.135452)
		(width 0.14605)
		(layer "B.Cu")
		(net "PCIE_IOM_TO_COMP_10_DP")
	)
	(segment
		(start 145.847054 -30.033722)
		(end 146.090132 -30.398212)
		(width 0.14605)
		(layer "B.Cu")
		(net "PCIE_IOM_TO_COMP_10_DP")
	)
	(segment
		(start 188.816742 -91.934538)
		(end 188.858906 -91.72321)
		(width 0.14605)
		(layer "B.Cu")
		(net "PCIE_IOM_TO_COMP_10_DP")
	)
	(segment
		(start 145.889218 -29.822394)
		(end 145.847054 -30.033722)
		(width 0.14605)
		(layer "B.Cu")
		(net "PCIE_IOM_TO_COMP_10_DP")
	)
	(segment
		(start 149.799294 -44.010834)
		(end 149.886416 -44.440348)
		(width 0.14605)
		(layer "B.Cu")
		(net "PCIE_IOM_TO_COMP_10_DP")
	)
	(segment
		(start 149.298406 -42.304716)
		(end 149.385528 -42.73423)
		(width 0.14605)
		(layer "B.Cu")
		(net "PCIE_IOM_TO_COMP_10_DP")
	)
	(segment
		(start 173.195488 -91.434412)
		(end 183.382158 -93.472)
		(width 0.14605)
		(layer "B.Cu")
		(net "PCIE_IOM_TO_COMP_10_DP")
	)
	(segment
		(start 149.886416 -44.440348)
		(end 149.76729 -44.619926)
		(width 0.14605)
		(layer "B.Cu")
		(net "PCIE_IOM_TO_COMP_10_DP")
	)
	(segment
		(start 190.78194 -90.624152)
		(end 190.824358 -90.412824)
		(width 0.14605)
		(layer "B.Cu")
		(net "PCIE_IOM_TO_COMP_10_DP")
	)
	(segment
		(start 147.347178 -32.666686)
		(end 147.4343 -33.0962)
		(width 0.14605)
		(layer "B.Cu")
		(net "PCIE_IOM_TO_COMP_10_DP")
	)
	(segment
		(start 148.16963 -35.960304)
		(end 148.050504 -36.139882)
		(width 0.14605)
		(layer "B.Cu")
		(net "PCIE_IOM_TO_COMP_10_DP")
	)
	(segment
		(start 198.964804 -82.721196)
		(end 198.964804 -81.557114)
		(width 0.14605)
		(layer "B.Cu")
		(net "PCIE_IOM_TO_COMP_10_DP")
	)
	(segment
		(start 149.385528 -42.73423)
		(end 149.565106 -42.853356)
		(width 0.14605)
		(layer "B.Cu")
		(net "PCIE_IOM_TO_COMP_10_DP")
	)
	(segment
		(start 146.745452 -31.380938)
		(end 146.95678 -31.423356)
		(width 0.14605)
		(layer "B.Cu")
		(net "PCIE_IOM_TO_COMP_10_DP")
	)
	(segment
		(start 149.76729 -44.619926)
		(end 149.854158 -45.04944)
		(width 0.14605)
		(layer "B.Cu")
		(net "PCIE_IOM_TO_COMP_10_DP")
	)
	(segment
		(start 188.451998 -92.177616)
		(end 188.816742 -91.934538)
		(width 0.14605)
		(layer "B.Cu")
		(net "PCIE_IOM_TO_COMP_10_DP")
	)
	(segment
		(start 147.379436 -32.057594)
		(end 147.466304 -32.487108)
		(width 0.14605)
		(layer "B.Cu")
		(net "PCIE_IOM_TO_COMP_10_DP")
	)
	(segment
		(start 139.313158 -28.005786)
		(end 143.469868 -28.005786)
		(width 0.14605)
		(layer "B.Cu")
		(net "PCIE_IOM_TO_COMP_10_DP")
	)
	(segment
		(start 148.050504 -36.139882)
		(end 148.137372 -36.569396)
		(width 0.14605)
		(layer "B.Cu")
		(net "PCIE_IOM_TO_COMP_10_DP")
	)
	(segment
		(start 190.41745 -90.86723)
		(end 190.78194 -90.624152)
		(width 0.14605)
		(layer "B.Cu")
		(net "PCIE_IOM_TO_COMP_10_DP")
	)
	(segment
		(start 192.171574 -89.51468)
		(end 198.964804 -82.721196)
		(width 0.14605)
		(layer "B.Cu")
		(net "PCIE_IOM_TO_COMP_10_DP")
	)
	(segment
		(start 136.95553 -35.853878)
		(end 136.95553 -30.363414)
		(width 0.14605)
		(layer "B.Cu")
		(net "PCIE_IOM_TO_COMP_10_DP")
	)
	(segment
		(start 150.033736 -45.168566)
		(end 150.120604 -45.597826)
		(width 0.14605)
		(layer "B.Cu")
		(net "PCIE_IOM_TO_COMP_10_DP")
	)
	(segment
		(start 147.935188 -34.802572)
		(end 147.816062 -34.98215)
		(width 0.14605)
		(layer "B.Cu")
		(net "PCIE_IOM_TO_COMP_10_DP")
	)
	(segment
		(start 147.879308 -59.129676)
		(end 149.54123 -67.442334)
		(width 0.14605)
		(layer "B.Cu")
		(net "PCIE_IOM_TO_COMP_10_DP")
	)
	(segment
		(start 188.858906 -91.72321)
		(end 189.223396 -91.480132)
		(width 0.14605)
		(layer "B.Cu")
		(net "PCIE_IOM_TO_COMP_10_DP")
	)
	(segment
		(start 146.544538 -30.80512)
		(end 146.502374 -31.016448)
		(width 0.14605)
		(layer "B.Cu")
		(net "PCIE_IOM_TO_COMP_10_DP")
	)
	(segment
		(start 146.090132 -30.398212)
		(end 146.30146 -30.44063)
		(width 0.14605)
		(layer "B.Cu")
		(net "PCIE_IOM_TO_COMP_10_DP")
	)
	(segment
		(start 147.90293 -35.411664)
		(end 148.082762 -35.53079)
		(width 0.14605)
		(layer "B.Cu")
		(net "PCIE_IOM_TO_COMP_10_DP")
	)
	(segment
		(start 147.668488 -34.253932)
		(end 147.84832 -34.373058)
		(width 0.14605)
		(layer "B.Cu")
		(net "PCIE_IOM_TO_COMP_10_DP")
	)
	(segment
		(start 150.0886 -46.206918)
		(end 150.268178 -46.326044)
		(width 0.14605)
		(layer "B.Cu")
		(net "PCIE_IOM_TO_COMP_10_DP")
	)
	(segment
		(start 147.816062 -34.98215)
		(end 147.90293 -35.411664)
		(width 0.14605)
		(layer "B.Cu")
		(net "PCIE_IOM_TO_COMP_10_DP")
	)
	(segment
		(start 198.964804 -81.557114)
		(end 199.089518 -81.4324)
		(width 0.14605)
		(layer "B.Cu")
		(net "PCIE_IOM_TO_COMP_10_DP")
	)
	(segment
		(start 149.565106 -42.853356)
		(end 149.651974 -43.282616)
		(width 0.14605)
		(layer "B.Cu")
		(net "PCIE_IOM_TO_COMP_10_DP")
	)
	(segment
		(start 146.95678 -31.423356)
		(end 147.379436 -32.057594)
		(width 0.14605)
		(layer "B.Cu")
		(net "PCIE_IOM_TO_COMP_10_DP")
	)
	(segment
		(start 150.001478 -45.777658)
		(end 150.0886 -46.206918)
		(width 0.14605)
		(layer "B.Cu")
		(net "PCIE_IOM_TO_COMP_10_DP")
	)
	(segment
		(start 189.799214 -91.279472)
		(end 189.841632 -91.068144)
		(width 0.14605)
		(layer "B.Cu")
		(net "PCIE_IOM_TO_COMP_10_DP")
	)
	(segment
		(start 145.64614 -29.457904)
		(end 145.889218 -29.822394)
		(width 0.14605)
		(layer "B.Cu")
		(net "PCIE_IOM_TO_COMP_10_DP")
	)
	(segment
		(start 137.700004 -35.600132)
		(end 137.700004 -35.918394)
		(width 0.14605)
		(layer "B.Cu")
		(net "PCIE_IOM_TO_COMP_10_DP")
	)
	(segment
		(start 148.317204 -36.688522)
		(end 148.31695 -36.688522)
		(width 0.14605)
		(layer "B.Cu")
		(net "PCIE_IOM_TO_COMP_10_DP")
	)
	(segment
		(start 147.466304 -32.487108)
		(end 147.347178 -32.666686)
		(width 0.14605)
		(layer "B.Cu")
		(net "PCIE_IOM_TO_COMP_10_DP")
	)
	(segment
		(start 152.483058 -77.673454)
		(end 173.195488 -91.434412)
		(width 0.14605)
		(layer "B.Cu")
		(net "PCIE_IOM_TO_COMP_10_DP")
	)
	(segment
		(start 150.355046 -46.755558)
		(end 147.879308 -59.129676)
		(width 0.14605)
		(layer "B.Cu")
		(net "PCIE_IOM_TO_COMP_10_DP")
	)
	(arc
		(start 137.246106 -36.144454)
		(mid 137.040638 -36.059346)
		(end 136.95553 -35.853878)
		(width 0.14605)
		(layer "B.Cu")
		(net "PCIE_IOM_TO_COMP_10_DP")
	)
	(arc
		(start 137.63371 -36.078414)
		(mid 137.560525 -36.127314)
		(end 137.474198 -36.144454)
		(width 0.14605)
		(layer "B.Cu")
		(net "PCIE_IOM_TO_COMP_10_DP")
	)
	(arc
		(start 137.700004 -35.918394)
		(mid 137.682777 -36.005001)
		(end 137.63371 -36.078414)
		(width 0.14605)
		(layer "B.Cu")
		(net "PCIE_IOM_TO_COMP_10_DP")
	)
	(segment
		(start 197.200012 -73.49998)
		(end 197.599808 -73.899776)
		(width 0.09525)
		(layer "F.Cu")
		(net "PCIE_IOM_TO_COMP_10_DN_C")
	)
	(via
		(at 197.599808 -73.899776)
		(size 0.4572)
		(drill 0.2032)
		(layers "F.Cu" "B.Cu")
		(net "PCIE_IOM_TO_COMP_10_DN_C")
	)
	(segment
		(start 197.431406 -75.74661)
		(end 197.82155 -76.136754)
		(width 0.09525)
		(layer "B.Cu")
		(net "PCIE_IOM_TO_COMP_10_DN_C")
	)
	(segment
		(start 198.657464 -77.850746)
		(end 198.657464 -80.746854)
		(width 0.14605)
		(layer "B.Cu")
		(net "PCIE_IOM_TO_COMP_10_DN_C")
	)
	(segment
		(start 197.431406 -75.085956)
		(end 197.431406 -75.74661)
		(width 0.09525)
		(layer "B.Cu")
		(net "PCIE_IOM_TO_COMP_10_DN_C")
	)
	(segment
		(start 198.657464 -80.746854)
		(end 198.530718 -80.8736)
		(width 0.14605)
		(layer "B.Cu")
		(net "PCIE_IOM_TO_COMP_10_DN_C")
	)
	(segment
		(start 197.75805 -76.422504)
		(end 197.75805 -76.446126)
		(width 0.09525)
		(layer "B.Cu")
		(net "PCIE_IOM_TO_COMP_10_DN_C")
	)
	(segment
		(start 197.599808 -73.899776)
		(end 197.459854 -73.899776)
		(width 0.09525)
		(layer "B.Cu")
		(net "PCIE_IOM_TO_COMP_10_DN_C")
	)
	(segment
		(start 197.212204 -74.866754)
		(end 197.431406 -75.085956)
		(width 0.09525)
		(layer "B.Cu")
		(net "PCIE_IOM_TO_COMP_10_DN_C")
	)
	(segment
		(start 197.459854 -73.899776)
		(end 197.212204 -74.147426)
		(width 0.09525)
		(layer "B.Cu")
		(net "PCIE_IOM_TO_COMP_10_DN_C")
	)
	(segment
		(start 197.212204 -74.147426)
		(end 197.212204 -74.866754)
		(width 0.09525)
		(layer "B.Cu")
		(net "PCIE_IOM_TO_COMP_10_DN_C")
	)
	(segment
		(start 197.82155 -76.136754)
		(end 197.82155 -76.359004)
		(width 0.09525)
		(layer "B.Cu")
		(net "PCIE_IOM_TO_COMP_10_DN_C")
	)
	(segment
		(start 197.75805 -76.446126)
		(end 197.75805 -76.951332)
		(width 0.14605)
		(layer "B.Cu")
		(net "PCIE_IOM_TO_COMP_10_DN_C")
	)
	(segment
		(start 197.75805 -76.951332)
		(end 198.657464 -77.850746)
		(width 0.14605)
		(layer "B.Cu")
		(net "PCIE_IOM_TO_COMP_10_DN_C")
	)
	(segment
		(start 197.82155 -76.359004)
		(end 197.75805 -76.422504)
		(width 0.09525)
		(layer "B.Cu")
		(net "PCIE_IOM_TO_COMP_10_DN_C")
	)
	(segment
		(start 187.337192 -92.363798)
		(end 183.382158 -93.1545)
		(width 0.14605)
		(layer "B.Cu")
		(net "PCIE_IOM_TO_COMP_10_DN")
	)
	(segment
		(start 183.382158 -93.1545)
		(end 173.316646 -91.141296)
		(width 0.14605)
		(layer "B.Cu")
		(net "PCIE_IOM_TO_COMP_10_DN")
	)
	(segment
		(start 137.700004 -36.6268)
		(end 137.700004 -37.00018)
		(width 0.14605)
		(layer "B.Cu")
		(net "PCIE_IOM_TO_COMP_10_DN")
	)
	(segment
		(start 151.496522 -75.633072)
		(end 148.196808 -59.129676)
		(width 0.14605)
		(layer "B.Cu")
		(net "PCIE_IOM_TO_COMP_10_DN")
	)
	(segment
		(start 198.653654 -82.592164)
		(end 191.9732 -89.272618)
		(width 0.14605)
		(layer "B.Cu")
		(net "PCIE_IOM_TO_COMP_10_DN")
	)
	(segment
		(start 198.530972 -81.4324)
		(end 198.653654 -81.555082)
		(width 0.14605)
		(layer "B.Cu")
		(net "PCIE_IOM_TO_COMP_10_DN")
	)
	(segment
		(start 152.70734 -77.448664)
		(end 151.496522 -75.633072)
		(width 0.14605)
		(layer "B.Cu")
		(net "PCIE_IOM_TO_COMP_10_DN")
	)
	(segment
		(start 145.870676 -29.233368)
		(end 143.564356 -27.694636)
		(width 0.14605)
		(layer "B.Cu")
		(net "PCIE_IOM_TO_COMP_10_DN")
	)
	(segment
		(start 198.653654 -81.555082)
		(end 198.653654 -82.592164)
		(width 0.14605)
		(layer "B.Cu")
		(net "PCIE_IOM_TO_COMP_10_DN")
	)
	(segment
		(start 137.246106 -36.455604)
		(end 137.528554 -36.455604)
		(width 0.14605)
		(layer "B.Cu")
		(net "PCIE_IOM_TO_COMP_10_DN")
	)
	(segment
		(start 198.530718 -81.4324)
		(end 198.530972 -81.4324)
		(width 0.14605)
		(layer "B.Cu")
		(net "PCIE_IOM_TO_COMP_10_DN")
	)
	(segment
		(start 173.316646 -91.141296)
		(end 152.70734 -77.448664)
		(width 0.14605)
		(layer "B.Cu")
		(net "PCIE_IOM_TO_COMP_10_DN")
	)
	(segment
		(start 143.564356 -27.694636)
		(end 139.184126 -27.694636)
		(width 0.14605)
		(layer "B.Cu")
		(net "PCIE_IOM_TO_COMP_10_DN")
	)
	(segment
		(start 147.672552 -31.935674)
		(end 145.870676 -29.233368)
		(width 0.14605)
		(layer "B.Cu")
		(net "PCIE_IOM_TO_COMP_10_DN")
	)
	(segment
		(start 148.196808 -59.129676)
		(end 150.672546 -46.755304)
		(width 0.14605)
		(layer "B.Cu")
		(net "PCIE_IOM_TO_COMP_10_DN")
	)
	(segment
		(start 150.672546 -46.755304)
		(end 147.672552 -31.935674)
		(width 0.14605)
		(layer "B.Cu")
		(net "PCIE_IOM_TO_COMP_10_DN")
	)
	(segment
		(start 136.64438 -30.234382)
		(end 136.64438 -35.853878)
		(width 0.14605)
		(layer "B.Cu")
		(net "PCIE_IOM_TO_COMP_10_DN")
	)
	(segment
		(start 191.9732 -89.272618)
		(end 187.337192 -92.363798)
		(width 0.14605)
		(layer "B.Cu")
		(net "PCIE_IOM_TO_COMP_10_DN")
	)
	(segment
		(start 139.184126 -27.694636)
		(end 136.64438 -30.234382)
		(width 0.14605)
		(layer "B.Cu")
		(net "PCIE_IOM_TO_COMP_10_DN")
	)
	(arc
		(start 137.528554 -36.455604)
		(mid 137.594262 -36.468674)
		(end 137.649966 -36.505896)
		(width 0.14605)
		(layer "B.Cu")
		(net "PCIE_IOM_TO_COMP_10_DN")
	)
	(arc
		(start 137.649966 -36.505896)
		(mid 137.686977 -36.561381)
		(end 137.700004 -36.6268)
		(width 0.14605)
		(layer "B.Cu")
		(net "PCIE_IOM_TO_COMP_10_DN")
	)
	(arc
		(start 136.64438 -35.853878)
		(mid 136.820621 -36.279363)
		(end 137.246106 -36.455604)
		(width 0.14605)
		(layer "B.Cu")
		(net "PCIE_IOM_TO_COMP_10_DN")
	)
	(segment
		(start 86.076028 -63.163196)
		(end 86.076028 -64.712596)
		(width 0.127)
		(layer "F.Cu")
		(net "PCIE_COMP_TO_IOM_RST_4_R")
	)
	(segment
		(start 86.076028 -64.712596)
		(end 86.418928 -65.055496)
		(width 0.127)
		(layer "F.Cu")
		(net "PCIE_COMP_TO_IOM_RST_4_R")
	)
	(segment
		(start 86.418928 -65.055496)
		(end 86.418928 -65.144396)
		(width 0.127)
		(layer "F.Cu")
		(net "PCIE_COMP_TO_IOM_RST_4_R")
	)
	(segment
		(start 79.925164 -61.74994)
		(end 84.662772 -61.74994)
		(width 0.127)
		(layer "F.Cu")
		(net "PCIE_COMP_TO_IOM_RST_4_R")
	)
	(segment
		(start 84.662772 -61.74994)
		(end 86.076028 -63.163196)
		(width 0.127)
		(layer "F.Cu")
		(net "PCIE_COMP_TO_IOM_RST_4_R")
	)
	(via
		(at 86.076028 -63.163196)
		(size 0.6604)
		(drill 0.3302)
		(layers "F.Cu" "B.Cu")
		(net "PCIE_COMP_TO_IOM_RST_4_R")
	)
	(segment
		(start 96.136968 -96.05645)
		(end 96.136968 -95.730568)
		(width 0.127)
		(layer "F.Cu")
		(net "PCIE_COMP_TO_IOM_RST_4")
	)
	(segment
		(start 88.02751 -65.144396)
		(end 88.06561 -65.182496)
		(width 0.127)
		(layer "F.Cu")
		(net "PCIE_COMP_TO_IOM_RST_4")
	)
	(segment
		(start 88.06561 -65.182496)
		(end 88.679528 -65.182496)
		(width 0.127)
		(layer "F.Cu")
		(net "PCIE_COMP_TO_IOM_RST_4")
	)
	(segment
		(start 91.154758 -90.748358)
		(end 91.553284 -91.146884)
		(width 0.127)
		(layer "F.Cu")
		(net "PCIE_COMP_TO_IOM_RST_4")
	)
	(segment
		(start 87.307928 -65.144396)
		(end 88.02751 -65.144396)
		(width 0.127)
		(layer "F.Cu")
		(net "PCIE_COMP_TO_IOM_RST_4")
	)
	(segment
		(start 88.679528 -65.182496)
		(end 91.154758 -67.657726)
		(width 0.127)
		(layer "F.Cu")
		(net "PCIE_COMP_TO_IOM_RST_4")
	)
	(segment
		(start 91.154758 -67.657726)
		(end 91.154758 -90.748358)
		(width 0.127)
		(layer "F.Cu")
		(net "PCIE_COMP_TO_IOM_RST_4")
	)
	(segment
		(start 98.829114 -157.898084)
		(end 99.372674 -158.441644)
		(width 0.127)
		(layer "F.Cu")
		(net "PCIE_COMP_TO_IOM_RST_4")
	)
	(segment
		(start 96.136968 -95.730568)
		(end 91.553284 -91.146884)
		(width 0.127)
		(layer "F.Cu")
		(net "PCIE_COMP_TO_IOM_RST_4")
	)
	(segment
		(start 97.6122 -157.46095)
		(end 98.049334 -157.898084)
		(width 0.127)
		(layer "F.Cu")
		(net "PCIE_COMP_TO_IOM_RST_4")
	)
	(segment
		(start 98.049334 -157.898084)
		(end 98.829114 -157.898084)
		(width 0.127)
		(layer "F.Cu")
		(net "PCIE_COMP_TO_IOM_RST_4")
	)
	(via
		(at 96.136968 -96.05645)
		(size 0.508)
		(drill 0.254)
		(layers "F.Cu" "B.Cu")
		(net "PCIE_COMP_TO_IOM_RST_4")
	)
	(via
		(at 91.553284 -91.146884)
		(size 0.6604)
		(drill 0.3302)
		(layers "F.Cu" "B.Cu")
		(net "PCIE_COMP_TO_IOM_RST_4")
	)
	(via
		(at 97.106232 -168.915588)
		(size 0.508)
		(drill 0.254)
		(layers "F.Cu" "B.Cu")
		(net "PCIE_COMP_TO_IOM_RST_4")
	)
	(via
		(at 95.17761 -126.675388)
		(size 0.508)
		(drill 0.254)
		(layers "F.Cu" "B.Cu")
		(net "PCIE_COMP_TO_IOM_RST_4")
	)
	(via
		(at 49.567846 -130.492754)
		(size 0.508)
		(drill 0.254)
		(layers "F.Cu" "B.Cu")
		(net "PCIE_COMP_TO_IOM_RST_4")
	)
	(via
		(at 97.6122 -157.46095)
		(size 0.508)
		(drill 0.254)
		(layers "F.Cu" "B.Cu")
		(net "PCIE_COMP_TO_IOM_RST_4")
	)
	(segment
		(start 90.6907 -173.5836)
		(end 90.6907 -171.8183)
		(width 0.127)
		(layer "B.Cu")
		(net "PCIE_COMP_TO_IOM_RST_4")
	)
	(segment
		(start 47.272194 -131.249674)
		(end 48.810926 -131.249674)
		(width 0.127)
		(layer "B.Cu")
		(net "PCIE_COMP_TO_IOM_RST_4")
	)
	(segment
		(start 48.810926 -131.249674)
		(end 49.567846 -130.492754)
		(width 0.127)
		(layer "B.Cu")
		(net "PCIE_COMP_TO_IOM_RST_4")
	)
	(segment
		(start 97.106232 -169.771568)
		(end 97.106232 -168.915588)
		(width 0.127)
		(layer "B.Cu")
		(net "PCIE_COMP_TO_IOM_RST_4")
	)
	(segment
		(start 95.504 -171.3738)
		(end 97.106232 -169.771568)
		(width 0.127)
		(layer "B.Cu")
		(net "PCIE_COMP_TO_IOM_RST_4")
	)
	(segment
		(start 91.1352 -171.3738)
		(end 95.504 -171.3738)
		(width 0.127)
		(layer "B.Cu")
		(net "PCIE_COMP_TO_IOM_RST_4")
	)
	(segment
		(start 90.6907 -171.8183)
		(end 91.1352 -171.3738)
		(width 0.127)
		(layer "B.Cu")
		(net "PCIE_COMP_TO_IOM_RST_4")
	)
	(segment
		(start 97.6122 -157.899608)
		(end 97.921318 -158.208726)
		(width 0.127)
		(layer "In2.Cu")
		(net "PCIE_COMP_TO_IOM_RST_4")
	)
	(segment
		(start 95.054166 -122.54992)
		(end 94.64802 -122.956066)
		(width 0.127)
		(layer "In2.Cu")
		(net "PCIE_COMP_TO_IOM_RST_4")
	)
	(segment
		(start 97.830894 -150.67026)
		(end 97.830894 -152.744424)
		(width 0.127)
		(layer "In2.Cu")
		(net "PCIE_COMP_TO_IOM_RST_4")
	)
	(segment
		(start 96.1263 -162.5473)
		(end 96.436434 -162.5473)
		(width 0.127)
		(layer "In2.Cu")
		(net "PCIE_COMP_TO_IOM_RST_4")
	)
	(segment
		(start 119.233442 -27.617674)
		(end 116.593874 -24.978106)
		(width 0.127)
		(layer "In2.Cu")
		(net "PCIE_COMP_TO_IOM_RST_4")
	)
	(segment
		(start 95.816166 -127.313944)
		(end 95.816166 -130.300984)
		(width 0.127)
		(layer "In2.Cu")
		(net "PCIE_COMP_TO_IOM_RST_4")
	)
	(segment
		(start 97.830894 -152.744424)
		(end 97.82937 -152.745948)
		(width 0.127)
		(layer "In2.Cu")
		(net "PCIE_COMP_TO_IOM_RST_4")
	)
	(segment
		(start 95.054166 -120.612408)
		(end 95.054166 -122.54992)
		(width 0.127)
		(layer "In2.Cu")
		(net "PCIE_COMP_TO_IOM_RST_4")
	)
	(segment
		(start 96.296988 -141.75994)
		(end 96.175068 -141.88186)
		(width 0.127)
		(layer "In2.Cu")
		(net "PCIE_COMP_TO_IOM_RST_4")
	)
	(segment
		(start 96.447864 -134.847076)
		(end 97.3836 -135.782812)
		(width 0.127)
		(layer "In2.Cu")
		(net "PCIE_COMP_TO_IOM_RST_4")
	)
	(segment
		(start 96.175068 -141.88186)
		(end 96.175068 -149.014434)
		(width 0.127)
		(layer "In2.Cu")
		(net "PCIE_COMP_TO_IOM_RST_4")
	)
	(segment
		(start 97.847658 -42.601388)
		(end 97.453958 -42.995088)
		(width 0.127)
		(layer "In2.Cu")
		(net "PCIE_COMP_TO_IOM_RST_4")
	)
	(segment
		(start 104.238298 -24.978106)
		(end 97.847658 -31.368746)
		(width 0.127)
		(layer "In2.Cu")
		(net "PCIE_COMP_TO_IOM_RST_4")
	)
	(segment
		(start 96.437704 -162.54857)
		(end 96.81337 -162.54857)
		(width 0.127)
		(layer "In2.Cu")
		(net "PCIE_COMP_TO_IOM_RST_4")
	)
	(segment
		(start 95.25 -117.558566)
		(end 95.25 -120.416574)
		(width 0.127)
		(layer "In2.Cu")
		(net "PCIE_COMP_TO_IOM_RST_4")
	)
	(segment
		(start 97.453958 -53.578506)
		(end 96.416114 -54.61635)
		(width 0.127)
		(layer "In2.Cu")
		(net "PCIE_COMP_TO_IOM_RST_4")
	)
	(segment
		(start 94.64802 -124.96419)
		(end 95.17761 -125.49378)
		(width 0.127)
		(layer "In2.Cu")
		(net "PCIE_COMP_TO_IOM_RST_4")
	)
	(segment
		(start 95.726504 -96.466914)
		(end 95.726504 -117.082062)
		(width 0.127)
		(layer "In2.Cu")
		(net "PCIE_COMP_TO_IOM_RST_4")
	)
	(segment
		(start 95.9866 -161.040318)
		(end 95.9866 -162.4076)
		(width 0.127)
		(layer "In2.Cu")
		(net "PCIE_COMP_TO_IOM_RST_4")
	)
	(segment
		(start 97.82937 -152.748488)
		(end 97.830894 -152.750012)
		(width 0.127)
		(layer "In2.Cu")
		(net "PCIE_COMP_TO_IOM_RST_4")
	)
	(segment
		(start 119.70004 -39.200074)
		(end 120.27154 -38.628574)
		(width 0.127)
		(layer "In2.Cu")
		(net "PCIE_COMP_TO_IOM_RST_4")
	)
	(segment
		(start 96.436434 -162.5473)
		(end 96.437704 -162.54857)
		(width 0.127)
		(layer "In2.Cu")
		(net "PCIE_COMP_TO_IOM_RST_4")
	)
	(segment
		(start 96.136968 -96.05645)
		(end 95.726504 -96.466914)
		(width 0.127)
		(layer "In2.Cu")
		(net "PCIE_COMP_TO_IOM_RST_4")
	)
	(segment
		(start 96.175068 -149.014434)
		(end 97.830894 -150.67026)
		(width 0.127)
		(layer "In2.Cu")
		(net "PCIE_COMP_TO_IOM_RST_4")
	)
	(segment
		(start 120.27154 -38.628574)
		(end 120.27154 -29.218382)
		(width 0.127)
		(layer "In2.Cu")
		(net "PCIE_COMP_TO_IOM_RST_4")
	)
	(segment
		(start 95.816166 -130.300984)
		(end 96.447864 -130.932682)
		(width 0.127)
		(layer "In2.Cu")
		(net "PCIE_COMP_TO_IOM_RST_4")
	)
	(segment
		(start 97.6122 -157.46095)
		(end 97.6122 -157.899608)
		(width 0.127)
		(layer "In2.Cu")
		(net "PCIE_COMP_TO_IOM_RST_4")
	)
	(segment
		(start 97.6122 -155.06065)
		(end 97.6122 -157.46095)
		(width 0.127)
		(layer "In2.Cu")
		(net "PCIE_COMP_TO_IOM_RST_4")
	)
	(segment
		(start 95.17761 -125.49378)
		(end 95.17761 -126.675388)
		(width 0.127)
		(layer "In2.Cu")
		(net "PCIE_COMP_TO_IOM_RST_4")
	)
	(segment
		(start 95.17761 -126.675388)
		(end 95.816166 -127.313944)
		(width 0.127)
		(layer "In2.Cu")
		(net "PCIE_COMP_TO_IOM_RST_4")
	)
	(segment
		(start 97.106232 -162.841432)
		(end 97.106232 -168.915588)
		(width 0.127)
		(layer "In2.Cu")
		(net "PCIE_COMP_TO_IOM_RST_4")
	)
	(segment
		(start 95.726504 -117.082062)
		(end 95.25 -117.558566)
		(width 0.127)
		(layer "In2.Cu")
		(net "PCIE_COMP_TO_IOM_RST_4")
	)
	(segment
		(start 97.453958 -42.995088)
		(end 97.453958 -53.578506)
		(width 0.127)
		(layer "In2.Cu")
		(net "PCIE_COMP_TO_IOM_RST_4")
	)
	(segment
		(start 96.447864 -130.932682)
		(end 96.447864 -134.847076)
		(width 0.127)
		(layer "In2.Cu")
		(net "PCIE_COMP_TO_IOM_RST_4")
	)
	(segment
		(start 96.416114 -54.61635)
		(end 96.416114 -95.777304)
		(width 0.127)
		(layer "In2.Cu")
		(net "PCIE_COMP_TO_IOM_RST_4")
	)
	(segment
		(start 97.847658 -31.368746)
		(end 97.847658 -42.601388)
		(width 0.127)
		(layer "In2.Cu")
		(net "PCIE_COMP_TO_IOM_RST_4")
	)
	(segment
		(start 97.921318 -159.1056)
		(end 95.9866 -161.040318)
		(width 0.127)
		(layer "In2.Cu")
		(net "PCIE_COMP_TO_IOM_RST_4")
	)
	(segment
		(start 97.3836 -137.600436)
		(end 96.296988 -138.687048)
		(width 0.127)
		(layer "In2.Cu")
		(net "PCIE_COMP_TO_IOM_RST_4")
	)
	(segment
		(start 119.233442 -28.180284)
		(end 119.233442 -27.617674)
		(width 0.127)
		(layer "In2.Cu")
		(net "PCIE_COMP_TO_IOM_RST_4")
	)
	(segment
		(start 95.25 -120.416574)
		(end 95.054166 -120.612408)
		(width 0.127)
		(layer "In2.Cu")
		(net "PCIE_COMP_TO_IOM_RST_4")
	)
	(segment
		(start 97.921318 -158.208726)
		(end 97.921318 -159.1056)
		(width 0.127)
		(layer "In2.Cu")
		(net "PCIE_COMP_TO_IOM_RST_4")
	)
	(segment
		(start 116.593874 -24.978106)
		(end 104.238298 -24.978106)
		(width 0.127)
		(layer "In2.Cu")
		(net "PCIE_COMP_TO_IOM_RST_4")
	)
	(segment
		(start 97.3836 -135.782812)
		(end 97.3836 -137.600436)
		(width 0.127)
		(layer "In2.Cu")
		(net "PCIE_COMP_TO_IOM_RST_4")
	)
	(segment
		(start 120.27154 -29.218382)
		(end 119.233442 -28.180284)
		(width 0.127)
		(layer "In2.Cu")
		(net "PCIE_COMP_TO_IOM_RST_4")
	)
	(segment
		(start 95.9866 -162.4076)
		(end 96.1263 -162.5473)
		(width 0.127)
		(layer "In2.Cu")
		(net "PCIE_COMP_TO_IOM_RST_4")
	)
	(segment
		(start 96.296988 -138.687048)
		(end 96.296988 -141.75994)
		(width 0.127)
		(layer "In2.Cu")
		(net "PCIE_COMP_TO_IOM_RST_4")
	)
	(segment
		(start 97.830894 -154.841956)
		(end 97.6122 -155.06065)
		(width 0.127)
		(layer "In2.Cu")
		(net "PCIE_COMP_TO_IOM_RST_4")
	)
	(segment
		(start 97.830894 -152.750012)
		(end 97.830894 -154.841956)
		(width 0.127)
		(layer "In2.Cu")
		(net "PCIE_COMP_TO_IOM_RST_4")
	)
	(segment
		(start 96.81337 -162.54857)
		(end 97.106232 -162.841432)
		(width 0.127)
		(layer "In2.Cu")
		(net "PCIE_COMP_TO_IOM_RST_4")
	)
	(segment
		(start 97.82937 -152.745948)
		(end 97.82937 -152.748488)
		(width 0.127)
		(layer "In2.Cu")
		(net "PCIE_COMP_TO_IOM_RST_4")
	)
	(segment
		(start 94.64802 -122.956066)
		(end 94.64802 -124.96419)
		(width 0.127)
		(layer "In2.Cu")
		(net "PCIE_COMP_TO_IOM_RST_4")
	)
	(segment
		(start 96.416114 -95.777304)
		(end 96.136968 -96.05645)
		(width 0.127)
		(layer "In2.Cu")
		(net "PCIE_COMP_TO_IOM_RST_4")
	)
	(segment
		(start 89.1921 -126.5682)
		(end 86.741 -126.5682)
		(width 0.127)
		(layer "In5.Cu")
		(net "PCIE_COMP_TO_IOM_RST_4")
	)
	(segment
		(start 93.527626 -127.2159)
		(end 89.8398 -127.2159)
		(width 0.127)
		(layer "In5.Cu")
		(net "PCIE_COMP_TO_IOM_RST_4")
	)
	(segment
		(start 83.723988 -128.0668)
		(end 82.479388 -129.3114)
		(width 0.127)
		(layer "In5.Cu")
		(net "PCIE_COMP_TO_IOM_RST_4")
	)
	(segment
		(start 83.9978 -128.0668)
		(end 83.723988 -128.0668)
		(width 0.127)
		(layer "In5.Cu")
		(net "PCIE_COMP_TO_IOM_RST_4")
	)
	(segment
		(start 86.741 -126.5682)
		(end 85.8266 -127.4826)
		(width 0.127)
		(layer "In5.Cu")
		(net "PCIE_COMP_TO_IOM_RST_4")
	)
	(segment
		(start 85.8266 -127.4826)
		(end 84.582 -127.4826)
		(width 0.127)
		(layer "In5.Cu")
		(net "PCIE_COMP_TO_IOM_RST_4")
	)
	(segment
		(start 89.8398 -127.2159)
		(end 89.1921 -126.5682)
		(width 0.127)
		(layer "In5.Cu")
		(net "PCIE_COMP_TO_IOM_RST_4")
	)
	(segment
		(start 68.637404 -129.93497)
		(end 67.213734 -128.5113)
		(width 0.127)
		(layer "In5.Cu")
		(net "PCIE_COMP_TO_IOM_RST_4")
	)
	(segment
		(start 79.390494 -129.3114)
		(end 79.073248 -128.994154)
		(width 0.127)
		(layer "In5.Cu")
		(net "PCIE_COMP_TO_IOM_RST_4")
	)
	(segment
		(start 52.453794 -130.934206)
		(end 50.009298 -130.934206)
		(width 0.127)
		(layer "In5.Cu")
		(net "PCIE_COMP_TO_IOM_RST_4")
	)
	(segment
		(start 53.6321 -129.7559)
		(end 52.453794 -130.934206)
		(width 0.127)
		(layer "In5.Cu")
		(net "PCIE_COMP_TO_IOM_RST_4")
	)
	(segment
		(start 71.770748 -129.93497)
		(end 68.637404 -129.93497)
		(width 0.127)
		(layer "In5.Cu")
		(net "PCIE_COMP_TO_IOM_RST_4")
	)
	(segment
		(start 55.67553 -128.5113)
		(end 54.43093 -129.7559)
		(width 0.127)
		(layer "In5.Cu")
		(net "PCIE_COMP_TO_IOM_RST_4")
	)
	(segment
		(start 72.711564 -128.994154)
		(end 71.770748 -129.93497)
		(width 0.127)
		(layer "In5.Cu")
		(net "PCIE_COMP_TO_IOM_RST_4")
	)
	(segment
		(start 82.479388 -129.3114)
		(end 79.390494 -129.3114)
		(width 0.127)
		(layer "In5.Cu")
		(net "PCIE_COMP_TO_IOM_RST_4")
	)
	(segment
		(start 50.009298 -130.934206)
		(end 49.567846 -130.492754)
		(width 0.127)
		(layer "In5.Cu")
		(net "PCIE_COMP_TO_IOM_RST_4")
	)
	(segment
		(start 79.073248 -128.994154)
		(end 72.711564 -128.994154)
		(width 0.127)
		(layer "In5.Cu")
		(net "PCIE_COMP_TO_IOM_RST_4")
	)
	(segment
		(start 84.582 -127.4826)
		(end 83.9978 -128.0668)
		(width 0.127)
		(layer "In5.Cu")
		(net "PCIE_COMP_TO_IOM_RST_4")
	)
	(segment
		(start 54.43093 -129.7559)
		(end 53.6321 -129.7559)
		(width 0.127)
		(layer "In5.Cu")
		(net "PCIE_COMP_TO_IOM_RST_4")
	)
	(segment
		(start 67.213734 -128.5113)
		(end 55.67553 -128.5113)
		(width 0.127)
		(layer "In5.Cu")
		(net "PCIE_COMP_TO_IOM_RST_4")
	)
	(segment
		(start 95.17761 -126.675388)
		(end 94.068138 -126.675388)
		(width 0.127)
		(layer "In5.Cu")
		(net "PCIE_COMP_TO_IOM_RST_4")
	)
	(segment
		(start 94.068138 -126.675388)
		(end 93.527626 -127.2159)
		(width 0.127)
		(layer "In5.Cu")
		(net "PCIE_COMP_TO_IOM_RST_4")
	)
	(segment
		(start 134.8486 -38.451536)
		(end 134.8486 -28.06192)
		(width 0.127)
		(layer "F.Cu")
		(net "PCIE_COMP_TO_IOM_RST_3")
	)
	(segment
		(start 134.100062 -39.200074)
		(end 134.8486 -38.451536)
		(width 0.127)
		(layer "F.Cu")
		(net "PCIE_COMP_TO_IOM_RST_3")
	)
	(segment
		(start 134.8486 -28.06192)
		(end 135.40232 -27.5082)
		(width 0.127)
		(layer "F.Cu")
		(net "PCIE_COMP_TO_IOM_RST_3")
	)
	(segment
		(start 150.811992 -99.4537)
		(end 150.43785 -99.827842)
		(width 0.127)
		(layer "F.Cu")
		(net "PCIE_COMP_TO_IOM_RST_2")
	)
	(segment
		(start 150.43785 -99.827842)
		(end 148.88337 -99.827842)
		(width 0.127)
		(layer "F.Cu")
		(net "PCIE_COMP_TO_IOM_RST_2")
	)
	(segment
		(start 143.002 -45.15104)
		(end 143.002 -39.9034)
		(width 0.127)
		(layer "F.Cu")
		(net "PCIE_COMP_TO_IOM_RST_2")
	)
	(segment
		(start 142.78864 -45.3644)
		(end 143.002 -45.15104)
		(width 0.127)
		(layer "F.Cu")
		(net "PCIE_COMP_TO_IOM_RST_2")
	)
	(segment
		(start 150.811992 -98.288094)
		(end 150.811992 -99.4537)
		(width 0.127)
		(layer "F.Cu")
		(net "PCIE_COMP_TO_IOM_RST_2")
	)
	(segment
		(start 142.298674 -39.200074)
		(end 141.299946 -39.200074)
		(width 0.127)
		(layer "F.Cu")
		(net "PCIE_COMP_TO_IOM_RST_2")
	)
	(segment
		(start 143.002 -39.9034)
		(end 142.298674 -39.200074)
		(width 0.127)
		(layer "F.Cu")
		(net "PCIE_COMP_TO_IOM_RST_2")
	)
	(via
		(at 148.88337 -99.827842)
		(size 0.508)
		(drill 0.254)
		(layers "F.Cu" "B.Cu")
		(net "PCIE_COMP_TO_IOM_RST_2")
	)
	(via
		(at 142.78864 -45.3644)
		(size 0.508)
		(drill 0.254)
		(layers "F.Cu" "B.Cu")
		(net "PCIE_COMP_TO_IOM_RST_2")
	)
	(segment
		(start 148.341588 -96.83242)
		(end 148.341588 -88.25992)
		(width 0.127)
		(layer "In2.Cu")
		(net "PCIE_COMP_TO_IOM_RST_2")
	)
	(segment
		(start 147.599654 -47.936404)
		(end 145.02765 -45.3644)
		(width 0.127)
		(layer "In2.Cu")
		(net "PCIE_COMP_TO_IOM_RST_2")
	)
	(segment
		(start 145.02765 -45.3644)
		(end 142.78864 -45.3644)
		(width 0.127)
		(layer "In2.Cu")
		(net "PCIE_COMP_TO_IOM_RST_2")
	)
	(segment
		(start 147.599654 -87.517986)
		(end 147.599654 -47.936404)
		(width 0.127)
		(layer "In2.Cu")
		(net "PCIE_COMP_TO_IOM_RST_2")
	)
	(segment
		(start 148.88337 -99.827842)
		(end 148.88337 -97.374202)
		(width 0.127)
		(layer "In2.Cu")
		(net "PCIE_COMP_TO_IOM_RST_2")
	)
	(segment
		(start 148.341588 -88.25992)
		(end 147.599654 -87.517986)
		(width 0.127)
		(layer "In2.Cu")
		(net "PCIE_COMP_TO_IOM_RST_2")
	)
	(segment
		(start 148.88337 -97.374202)
		(end 148.341588 -96.83242)
		(width 0.127)
		(layer "In2.Cu")
		(net "PCIE_COMP_TO_IOM_RST_2")
	)
	(segment
		(start 76.801472 -67.60464)
		(end 77.059028 -67.60464)
		(width 0.14605)
		(layer "F.Cu")
		(net "PCIE_COMP_TO_IOM_CLK_4_DP")
	)
	(segment
		(start 77.274674 -67.388994)
		(end 77.274674 -67.322192)
		(width 0.14605)
		(layer "F.Cu")
		(net "PCIE_COMP_TO_IOM_CLK_4_DP")
	)
	(segment
		(start 75.475084 -67.350132)
		(end 76.546964 -67.350132)
		(width 0.14605)
		(layer "F.Cu")
		(net "PCIE_COMP_TO_IOM_CLK_4_DP")
	)
	(segment
		(start 76.546964 -67.350132)
		(end 76.801472 -67.60464)
		(width 0.14605)
		(layer "F.Cu")
		(net "PCIE_COMP_TO_IOM_CLK_4_DP")
	)
	(arc
		(start 77.059028 -67.60464)
		(mid 77.211513 -67.541479)
		(end 77.274674 -67.388994)
		(width 0.14605)
		(layer "F.Cu")
		(net "PCIE_COMP_TO_IOM_CLK_4_DP")
	)
	(segment
		(start 79.391002 -66.815716)
		(end 79.543402 -66.663316)
		(width 0.14605)
		(layer "B.Cu")
		(net "PCIE_COMP_TO_IOM_CLK_4_DP")
	)
	(segment
		(start 101.571806 -22.445218)
		(end 102.367842 -22.445218)
		(width 0.14605)
		(layer "B.Cu")
		(net "PCIE_COMP_TO_IOM_CLK_4_DP")
	)
	(segment
		(start 86.674198 -60.764674)
		(end 86.553548 -60.586112)
		(width 0.14605)
		(layer "B.Cu")
		(net "PCIE_COMP_TO_IOM_CLK_4_DP")
	)
	(segment
		(start 77.033628 -65.753996)
		(end 77.452982 -65.753996)
		(width 0.14605)
		(layer "B.Cu")
		(net "PCIE_COMP_TO_IOM_CLK_4_DP")
	)
	(segment
		(start 86.411816 -61.315346)
		(end 86.590632 -61.19495)
		(width 0.14605)
		(layer "B.Cu")
		(net "PCIE_COMP_TO_IOM_CLK_4_DP")
	)
	(segment
		(start 105.911142 -22.445218)
		(end 106.063542 -22.597618)
		(width 0.14605)
		(layer "B.Cu")
		(net "PCIE_COMP_TO_IOM_CLK_4_DP")
	)
	(segment
		(start 105.320592 -22.597618)
		(end 105.472992 -22.445218)
		(width 0.14605)
		(layer "B.Cu")
		(net "PCIE_COMP_TO_IOM_CLK_4_DP")
	)
	(segment
		(start 78.362302 -66.663316)
		(end 78.800452 -66.663316)
		(width 0.14605)
		(layer "B.Cu")
		(net "PCIE_COMP_TO_IOM_CLK_4_DP")
	)
	(segment
		(start 105.472992 -22.445218)
		(end 105.911142 -22.445218)
		(width 0.14605)
		(layer "B.Cu")
		(net "PCIE_COMP_TO_IOM_CLK_4_DP")
	)
	(segment
		(start 86.329266 -66.361818)
		(end 86.482428 -65.575688)
		(width 0.14605)
		(layer "B.Cu")
		(net "PCIE_COMP_TO_IOM_CLK_4_DP")
	)
	(segment
		(start 87.004398 -58.267346)
		(end 88.079072 -52.73802)
		(width 0.14605)
		(layer "B.Cu")
		(net "PCIE_COMP_TO_IOM_CLK_4_DP")
	)
	(segment
		(start 106.654092 -22.445218)
		(end 114.824002 -22.445218)
		(width 0.14605)
		(layer "B.Cu")
		(net "PCIE_COMP_TO_IOM_CLK_4_DP")
	)
	(segment
		(start 102.520242 -22.597618)
		(end 102.958392 -22.597618)
		(width 0.14605)
		(layer "B.Cu")
		(net "PCIE_COMP_TO_IOM_CLK_4_DP")
	)
	(segment
		(start 120.83542 -28.456636)
		(end 120.83542 -42.66311)
		(width 0.14605)
		(layer "B.Cu")
		(net "PCIE_COMP_TO_IOM_CLK_4_DP")
	)
	(segment
		(start 80.133952 -66.815716)
		(end 80.572102 -66.815716)
		(width 0.14605)
		(layer "B.Cu")
		(net "PCIE_COMP_TO_IOM_CLK_4_DP")
	)
	(segment
		(start 118.896384 -26.733246)
		(end 119.11203 -26.733246)
		(width 0.14605)
		(layer "B.Cu")
		(net "PCIE_COMP_TO_IOM_CLK_4_DP")
	)
	(segment
		(start 86.899496 -59.605418)
		(end 86.7791 -59.426602)
		(width 0.14605)
		(layer "B.Cu")
		(net "PCIE_COMP_TO_IOM_CLK_4_DP")
	)
	(segment
		(start 117.22608 -25.062942)
		(end 117.441726 -25.062942)
		(width 0.14605)
		(layer "B.Cu")
		(net "PCIE_COMP_TO_IOM_CLK_4_DP")
	)
	(segment
		(start 118.586504 -26.423366)
		(end 118.896384 -26.733246)
		(width 0.14605)
		(layer "B.Cu")
		(net "PCIE_COMP_TO_IOM_CLK_4_DP")
	)
	(segment
		(start 76.693776 -66.093848)
		(end 77.033628 -65.753996)
		(width 0.14605)
		(layer "B.Cu")
		(net "PCIE_COMP_TO_IOM_CLK_4_DP")
	)
	(segment
		(start 86.553548 -60.586112)
		(end 86.637114 -60.15609)
		(width 0.14605)
		(layer "B.Cu")
		(net "PCIE_COMP_TO_IOM_CLK_4_DP")
	)
	(segment
		(start 90.384122 -29.905198)
		(end 101.571806 -22.445218)
		(width 0.14605)
		(layer "B.Cu")
		(net "PCIE_COMP_TO_IOM_CLK_4_DP")
	)
	(segment
		(start 86.186518 -62.474856)
		(end 86.365334 -62.354206)
		(width 0.14605)
		(layer "B.Cu")
		(net "PCIE_COMP_TO_IOM_CLK_4_DP")
	)
	(segment
		(start 87.385144 -49.191418)
		(end 87.073994 -47.60214)
		(width 0.14605)
		(layer "B.Cu")
		(net "PCIE_COMP_TO_IOM_CLK_4_DP")
	)
	(segment
		(start 87.790782 -50.470816)
		(end 87.611966 -50.350674)
		(width 0.14605)
		(layer "B.Cu")
		(net "PCIE_COMP_TO_IOM_CLK_4_DP")
	)
	(segment
		(start 89.84615 -33.338008)
		(end 89.67089 -32.436308)
		(width 0.14605)
		(layer "B.Cu")
		(net "PCIE_COMP_TO_IOM_CLK_4_DP")
	)
	(segment
		(start 86.81593 -60.03544)
		(end 86.899496 -59.605418)
		(width 0.14605)
		(layer "B.Cu")
		(net "PCIE_COMP_TO_IOM_CLK_4_DP")
	)
	(segment
		(start 76.693776 -67.46494)
		(end 76.693776 -66.093848)
		(width 0.14605)
		(layer "B.Cu")
		(net "PCIE_COMP_TO_IOM_CLK_4_DP")
	)
	(segment
		(start 117.751352 -25.372568)
		(end 117.751352 -25.588214)
		(width 0.14605)
		(layer "B.Cu")
		(net "PCIE_COMP_TO_IOM_CLK_4_DP")
	)
	(segment
		(start 117.441726 -25.062942)
		(end 117.751352 -25.372568)
		(width 0.14605)
		(layer "B.Cu")
		(net "PCIE_COMP_TO_IOM_CLK_4_DP")
	)
	(segment
		(start 116.390928 -24.22779)
		(end 116.606574 -24.22779)
		(width 0.14605)
		(layer "B.Cu")
		(net "PCIE_COMP_TO_IOM_CLK_4_DP")
	)
	(segment
		(start 89.67089 -32.436308)
		(end 90.384122 -29.905198)
		(width 0.14605)
		(layer "B.Cu")
		(net "PCIE_COMP_TO_IOM_CLK_4_DP")
	)
	(segment
		(start 78.952852 -66.815716)
		(end 79.391002 -66.815716)
		(width 0.14605)
		(layer "B.Cu")
		(net "PCIE_COMP_TO_IOM_CLK_4_DP")
	)
	(segment
		(start 102.958392 -22.597618)
		(end 103.110792 -22.445218)
		(width 0.14605)
		(layer "B.Cu")
		(net "PCIE_COMP_TO_IOM_CLK_4_DP")
	)
	(segment
		(start 80.572102 -66.815716)
		(end 80.724502 -66.663316)
		(width 0.14605)
		(layer "B.Cu")
		(net "PCIE_COMP_TO_IOM_CLK_4_DP")
	)
	(segment
		(start 77.452982 -65.753996)
		(end 78.362302 -66.663316)
		(width 0.14605)
		(layer "B.Cu")
		(net "PCIE_COMP_TO_IOM_CLK_4_DP")
	)
	(segment
		(start 86.32825 -61.745368)
		(end 86.411816 -61.315346)
		(width 0.14605)
		(layer "B.Cu")
		(net "PCIE_COMP_TO_IOM_CLK_4_DP")
	)
	(segment
		(start 87.611966 -50.350674)
		(end 87.527892 -49.920652)
		(width 0.14605)
		(layer "B.Cu")
		(net "PCIE_COMP_TO_IOM_CLK_4_DP")
	)
	(segment
		(start 103.701342 -22.597618)
		(end 104.139492 -22.597618)
		(width 0.14605)
		(layer "B.Cu")
		(net "PCIE_COMP_TO_IOM_CLK_4_DP")
	)
	(segment
		(start 86.365334 -62.354206)
		(end 86.4489 -61.924184)
		(width 0.14605)
		(layer "B.Cu")
		(net "PCIE_COMP_TO_IOM_CLK_4_DP")
	)
	(segment
		(start 119.11203 -26.733246)
		(end 120.83542 -28.456636)
		(width 0.14605)
		(layer "B.Cu")
		(net "PCIE_COMP_TO_IOM_CLK_4_DP")
	)
	(segment
		(start 88.079072 -52.73802)
		(end 87.754714 -51.079654)
		(width 0.14605)
		(layer "B.Cu")
		(net "PCIE_COMP_TO_IOM_CLK_4_DP")
	)
	(segment
		(start 87.56396 -49.311814)
		(end 87.385144 -49.191418)
		(width 0.14605)
		(layer "B.Cu")
		(net "PCIE_COMP_TO_IOM_CLK_4_DP")
	)
	(segment
		(start 119.70004 -43.173396)
		(end 119.70004 -42.800016)
		(width 0.14605)
		(layer "B.Cu")
		(net "PCIE_COMP_TO_IOM_CLK_4_DP")
	)
	(segment
		(start 102.367842 -22.445218)
		(end 102.520242 -22.597618)
		(width 0.14605)
		(layer "B.Cu")
		(net "PCIE_COMP_TO_IOM_CLK_4_DP")
	)
	(segment
		(start 84.393278 -67.785996)
		(end 85.44433 -67.785996)
		(width 0.14605)
		(layer "B.Cu")
		(net "PCIE_COMP_TO_IOM_CLK_4_DP")
	)
	(segment
		(start 86.4489 -61.924184)
		(end 86.32825 -61.745368)
		(width 0.14605)
		(layer "B.Cu")
		(net "PCIE_COMP_TO_IOM_CLK_4_DP")
	)
	(segment
		(start 80.724502 -66.663316)
		(end 83.270598 -66.663316)
		(width 0.14605)
		(layer "B.Cu")
		(net "PCIE_COMP_TO_IOM_CLK_4_DP")
	)
	(segment
		(start 78.800452 -66.663316)
		(end 78.952852 -66.815716)
		(width 0.14605)
		(layer "B.Cu")
		(net "PCIE_COMP_TO_IOM_CLK_4_DP")
	)
	(segment
		(start 87.527892 -49.920652)
		(end 87.648034 -49.741836)
		(width 0.14605)
		(layer "B.Cu")
		(net "PCIE_COMP_TO_IOM_CLK_4_DP")
	)
	(segment
		(start 86.198964 -67.031616)
		(end 86.329266 -66.361818)
		(width 0.14605)
		(layer "B.Cu")
		(net "PCIE_COMP_TO_IOM_CLK_4_DP")
	)
	(segment
		(start 87.073994 -47.60214)
		(end 89.84615 -33.338008)
		(width 0.14605)
		(layer "B.Cu")
		(net "PCIE_COMP_TO_IOM_CLK_4_DP")
	)
	(segment
		(start 106.501692 -22.597618)
		(end 106.654092 -22.445218)
		(width 0.14605)
		(layer "B.Cu")
		(net "PCIE_COMP_TO_IOM_CLK_4_DP")
	)
	(segment
		(start 104.139492 -22.597618)
		(end 104.291892 -22.445218)
		(width 0.14605)
		(layer "B.Cu")
		(net "PCIE_COMP_TO_IOM_CLK_4_DP")
	)
	(segment
		(start 86.637114 -60.15609)
		(end 86.81593 -60.03544)
		(width 0.14605)
		(layer "B.Cu")
		(net "PCIE_COMP_TO_IOM_CLK_4_DP")
	)
	(segment
		(start 76.839826 -67.61099)
		(end 76.693776 -67.46494)
		(width 0.14605)
		(layer "B.Cu")
		(net "PCIE_COMP_TO_IOM_CLK_4_DP")
	)
	(segment
		(start 106.063542 -22.597618)
		(end 106.501692 -22.597618)
		(width 0.14605)
		(layer "B.Cu")
		(net "PCIE_COMP_TO_IOM_CLK_4_DP")
	)
	(segment
		(start 116.081048 -23.702264)
		(end 116.081048 -23.91791)
		(width 0.14605)
		(layer "B.Cu")
		(net "PCIE_COMP_TO_IOM_CLK_4_DP")
	)
	(segment
		(start 86.033102 -63.264034)
		(end 86.186518 -62.474856)
		(width 0.14605)
		(layer "B.Cu")
		(net "PCIE_COMP_TO_IOM_CLK_4_DP")
	)
	(segment
		(start 116.9162 -24.537416)
		(end 116.9162 -24.753062)
		(width 0.14605)
		(layer "B.Cu")
		(net "PCIE_COMP_TO_IOM_CLK_4_DP")
	)
	(segment
		(start 86.7791 -59.426602)
		(end 86.862666 -58.99658)
		(width 0.14605)
		(layer "B.Cu")
		(net "PCIE_COMP_TO_IOM_CLK_4_DP")
	)
	(segment
		(start 87.124794 -58.445908)
		(end 87.004398 -58.267346)
		(width 0.14605)
		(layer "B.Cu")
		(net "PCIE_COMP_TO_IOM_CLK_4_DP")
	)
	(segment
		(start 118.276878 -25.898094)
		(end 118.586504 -26.20772)
		(width 0.14605)
		(layer "B.Cu")
		(net "PCIE_COMP_TO_IOM_CLK_4_DP")
	)
	(segment
		(start 87.874856 -50.900838)
		(end 87.790782 -50.470816)
		(width 0.14605)
		(layer "B.Cu")
		(net "PCIE_COMP_TO_IOM_CLK_4_DP")
	)
	(segment
		(start 103.548942 -22.445218)
		(end 103.701342 -22.597618)
		(width 0.14605)
		(layer "B.Cu")
		(net "PCIE_COMP_TO_IOM_CLK_4_DP")
	)
	(segment
		(start 86.482428 -65.575688)
		(end 86.033102 -63.264034)
		(width 0.14605)
		(layer "B.Cu")
		(net "PCIE_COMP_TO_IOM_CLK_4_DP")
	)
	(segment
		(start 118.586504 -26.20772)
		(end 118.586504 -26.423366)
		(width 0.14605)
		(layer "B.Cu")
		(net "PCIE_COMP_TO_IOM_CLK_4_DP")
	)
	(segment
		(start 117.751352 -25.588214)
		(end 118.061232 -25.898094)
		(width 0.14605)
		(layer "B.Cu")
		(net "PCIE_COMP_TO_IOM_CLK_4_DP")
	)
	(segment
		(start 103.110792 -22.445218)
		(end 103.548942 -22.445218)
		(width 0.14605)
		(layer "B.Cu")
		(net "PCIE_COMP_TO_IOM_CLK_4_DP")
	)
	(segment
		(start 86.862666 -58.99658)
		(end 87.041228 -58.87593)
		(width 0.14605)
		(layer "B.Cu")
		(net "PCIE_COMP_TO_IOM_CLK_4_DP")
	)
	(segment
		(start 76.985876 -67.61099)
		(end 76.839826 -67.61099)
		(width 0.14605)
		(layer "B.Cu")
		(net "PCIE_COMP_TO_IOM_CLK_4_DP")
	)
	(segment
		(start 87.041228 -58.87593)
		(end 87.124794 -58.445908)
		(width 0.14605)
		(layer "B.Cu")
		(net "PCIE_COMP_TO_IOM_CLK_4_DP")
	)
	(segment
		(start 116.081048 -23.91791)
		(end 116.390928 -24.22779)
		(width 0.14605)
		(layer "B.Cu")
		(net "PCIE_COMP_TO_IOM_CLK_4_DP")
	)
	(segment
		(start 87.754714 -51.079654)
		(end 87.874856 -50.900838)
		(width 0.14605)
		(layer "B.Cu")
		(net "PCIE_COMP_TO_IOM_CLK_4_DP")
	)
	(segment
		(start 104.291892 -22.445218)
		(end 104.730042 -22.445218)
		(width 0.14605)
		(layer "B.Cu")
		(net "PCIE_COMP_TO_IOM_CLK_4_DP")
	)
	(segment
		(start 79.543402 -66.663316)
		(end 79.981552 -66.663316)
		(width 0.14605)
		(layer "B.Cu")
		(net "PCIE_COMP_TO_IOM_CLK_4_DP")
	)
	(segment
		(start 116.606574 -24.22779)
		(end 116.9162 -24.537416)
		(width 0.14605)
		(layer "B.Cu")
		(net "PCIE_COMP_TO_IOM_CLK_4_DP")
	)
	(segment
		(start 114.824002 -22.445218)
		(end 116.081048 -23.702264)
		(width 0.14605)
		(layer "B.Cu")
		(net "PCIE_COMP_TO_IOM_CLK_4_DP")
	)
	(segment
		(start 104.882442 -22.597618)
		(end 105.320592 -22.597618)
		(width 0.14605)
		(layer "B.Cu")
		(net "PCIE_COMP_TO_IOM_CLK_4_DP")
	)
	(segment
		(start 79.981552 -66.663316)
		(end 80.133952 -66.815716)
		(width 0.14605)
		(layer "B.Cu")
		(net "PCIE_COMP_TO_IOM_CLK_4_DP")
	)
	(segment
		(start 104.730042 -22.445218)
		(end 104.882442 -22.597618)
		(width 0.14605)
		(layer "B.Cu")
		(net "PCIE_COMP_TO_IOM_CLK_4_DP")
	)
	(segment
		(start 86.590632 -61.19495)
		(end 86.674198 -60.764674)
		(width 0.14605)
		(layer "B.Cu")
		(net "PCIE_COMP_TO_IOM_CLK_4_DP")
	)
	(segment
		(start 85.44433 -67.785996)
		(end 86.198964 -67.031616)
		(width 0.14605)
		(layer "B.Cu")
		(net "PCIE_COMP_TO_IOM_CLK_4_DP")
	)
	(segment
		(start 83.270598 -66.663316)
		(end 84.393278 -67.785996)
		(width 0.14605)
		(layer "B.Cu")
		(net "PCIE_COMP_TO_IOM_CLK_4_DP")
	)
	(segment
		(start 118.061232 -25.898094)
		(end 118.276878 -25.898094)
		(width 0.14605)
		(layer "B.Cu")
		(net "PCIE_COMP_TO_IOM_CLK_4_DP")
	)
	(segment
		(start 87.648034 -49.741836)
		(end 87.56396 -49.311814)
		(width 0.14605)
		(layer "B.Cu")
		(net "PCIE_COMP_TO_IOM_CLK_4_DP")
	)
	(segment
		(start 120.153938 -43.344592)
		(end 119.87149 -43.344592)
		(width 0.14605)
		(layer "B.Cu")
		(net "PCIE_COMP_TO_IOM_CLK_4_DP")
	)
	(segment
		(start 116.9162 -24.753062)
		(end 117.22608 -25.062942)
		(width 0.14605)
		(layer "B.Cu")
		(net "PCIE_COMP_TO_IOM_CLK_4_DP")
	)
	(arc
		(start 120.83542 -42.66311)
		(mid 120.635819 -43.144991)
		(end 120.153938 -43.344592)
		(width 0.14605)
		(layer "B.Cu")
		(net "PCIE_COMP_TO_IOM_CLK_4_DP")
	)
	(arc
		(start 119.750078 -43.2943)
		(mid 119.713067 -43.238815)
		(end 119.70004 -43.173396)
		(width 0.14605)
		(layer "B.Cu")
		(net "PCIE_COMP_TO_IOM_CLK_4_DP")
	)
	(arc
		(start 119.87149 -43.344592)
		(mid 119.805782 -43.331522)
		(end 119.750078 -43.2943)
		(width 0.14605)
		(layer "B.Cu")
		(net "PCIE_COMP_TO_IOM_CLK_4_DP")
	)
	(arc
		(start 77.274674 -67.322192)
		(mid 77.190087 -67.526403)
		(end 76.985876 -67.61099)
		(width 0.14605)
		(layer "B.Cu")
		(net "PCIE_COMP_TO_IOM_CLK_4_DP")
	)
	(segment
		(start 76.78674 -67.91579)
		(end 77.059028 -67.91579)
		(width 0.14605)
		(layer "F.Cu")
		(net "PCIE_COMP_TO_IOM_CLK_4_DN")
	)
	(segment
		(start 75.475084 -68.149978)
		(end 76.552552 -68.149978)
		(width 0.14605)
		(layer "F.Cu")
		(net "PCIE_COMP_TO_IOM_CLK_4_DN")
	)
	(segment
		(start 76.552552 -68.149978)
		(end 76.78674 -67.91579)
		(width 0.14605)
		(layer "F.Cu")
		(net "PCIE_COMP_TO_IOM_CLK_4_DN")
	)
	(segment
		(start 77.274674 -68.131436)
		(end 77.274674 -68.211192)
		(width 0.14605)
		(layer "F.Cu")
		(net "PCIE_COMP_TO_IOM_CLK_4_DN")
	)
	(arc
		(start 77.059028 -67.91579)
		(mid 77.211513 -67.978951)
		(end 77.274674 -68.131436)
		(width 0.14605)
		(layer "F.Cu")
		(net "PCIE_COMP_TO_IOM_CLK_4_DN")
	)
	(segment
		(start 78.491334 -66.352166)
		(end 77.582014 -65.442846)
		(width 0.14605)
		(layer "B.Cu")
		(net "PCIE_COMP_TO_IOM_CLK_4_DN")
	)
	(segment
		(start 85.911436 -66.878708)
		(end 85.315298 -67.474846)
		(width 0.14605)
		(layer "B.Cu")
		(net "PCIE_COMP_TO_IOM_CLK_4_DN")
	)
	(segment
		(start 86.757002 -47.602902)
		(end 87.761826 -52.738274)
		(width 0.14605)
		(layer "B.Cu")
		(net "PCIE_COMP_TO_IOM_CLK_4_DN")
	)
	(segment
		(start 101.477572 -22.134068)
		(end 90.115644 -29.709872)
		(width 0.14605)
		(layer "B.Cu")
		(net "PCIE_COMP_TO_IOM_CLK_4_DN")
	)
	(segment
		(start 87.761826 -52.738274)
		(end 85.71611 -63.264288)
		(width 0.14605)
		(layer "B.Cu")
		(net "PCIE_COMP_TO_IOM_CLK_4_DN")
	)
	(segment
		(start 76.382626 -65.964816)
		(end 76.382626 -67.593972)
		(width 0.14605)
		(layer "B.Cu")
		(net "PCIE_COMP_TO_IOM_CLK_4_DN")
	)
	(segment
		(start 83.39963 -66.352166)
		(end 78.491334 -66.352166)
		(width 0.14605)
		(layer "B.Cu")
		(net "PCIE_COMP_TO_IOM_CLK_4_DN")
	)
	(segment
		(start 89.351104 -32.4231)
		(end 89.529158 -33.338008)
		(width 0.14605)
		(layer "B.Cu")
		(net "PCIE_COMP_TO_IOM_CLK_4_DN")
	)
	(segment
		(start 119.70004 -44.200064)
		(end 119.70004 -43.881802)
		(width 0.14605)
		(layer "B.Cu")
		(net "PCIE_COMP_TO_IOM_CLK_4_DN")
	)
	(segment
		(start 86.756748 -47.602394)
		(end 86.756748 -47.602902)
		(width 0.14605)
		(layer "B.Cu")
		(net "PCIE_COMP_TO_IOM_CLK_4_DN")
	)
	(segment
		(start 114.953034 -22.134068)
		(end 101.477572 -22.134068)
		(width 0.14605)
		(layer "B.Cu")
		(net "PCIE_COMP_TO_IOM_CLK_4_DN")
	)
	(segment
		(start 76.710794 -67.92214)
		(end 76.985622 -67.92214)
		(width 0.14605)
		(layer "B.Cu")
		(net "PCIE_COMP_TO_IOM_CLK_4_DN")
	)
	(segment
		(start 121.14657 -28.327604)
		(end 114.953034 -22.134068)
		(width 0.14605)
		(layer "B.Cu")
		(net "PCIE_COMP_TO_IOM_CLK_4_DN")
	)
	(segment
		(start 85.71611 -63.264288)
		(end 86.165182 -65.575688)
		(width 0.14605)
		(layer "B.Cu")
		(net "PCIE_COMP_TO_IOM_CLK_4_DN")
	)
	(segment
		(start 119.925846 -43.655742)
		(end 120.153938 -43.655742)
		(width 0.14605)
		(layer "B.Cu")
		(net "PCIE_COMP_TO_IOM_CLK_4_DN")
	)
	(segment
		(start 86.165182 -65.575688)
		(end 85.911436 -66.878708)
		(width 0.14605)
		(layer "B.Cu")
		(net "PCIE_COMP_TO_IOM_CLK_4_DN")
	)
	(segment
		(start 76.904596 -65.442846)
		(end 76.382626 -65.964816)
		(width 0.14605)
		(layer "B.Cu")
		(net "PCIE_COMP_TO_IOM_CLK_4_DN")
	)
	(segment
		(start 121.14657 -42.66311)
		(end 121.14657 -28.327604)
		(width 0.14605)
		(layer "B.Cu")
		(net "PCIE_COMP_TO_IOM_CLK_4_DN")
	)
	(segment
		(start 85.315298 -67.474846)
		(end 84.52231 -67.474846)
		(width 0.14605)
		(layer "B.Cu")
		(net "PCIE_COMP_TO_IOM_CLK_4_DN")
	)
	(segment
		(start 89.529158 -33.338008)
		(end 86.756748 -47.602394)
		(width 0.14605)
		(layer "B.Cu")
		(net "PCIE_COMP_TO_IOM_CLK_4_DN")
	)
	(segment
		(start 77.582014 -65.442846)
		(end 76.904596 -65.442846)
		(width 0.14605)
		(layer "B.Cu")
		(net "PCIE_COMP_TO_IOM_CLK_4_DN")
	)
	(segment
		(start 86.756748 -47.602902)
		(end 86.757002 -47.602902)
		(width 0.14605)
		(layer "B.Cu")
		(net "PCIE_COMP_TO_IOM_CLK_4_DN")
	)
	(segment
		(start 76.382626 -67.593972)
		(end 76.710794 -67.92214)
		(width 0.14605)
		(layer "B.Cu")
		(net "PCIE_COMP_TO_IOM_CLK_4_DN")
	)
	(segment
		(start 90.115644 -29.709872)
		(end 89.351104 -32.4231)
		(width 0.14605)
		(layer "B.Cu")
		(net "PCIE_COMP_TO_IOM_CLK_4_DN")
	)
	(segment
		(start 84.52231 -67.474846)
		(end 83.39963 -66.352166)
		(width 0.14605)
		(layer "B.Cu")
		(net "PCIE_COMP_TO_IOM_CLK_4_DN")
	)
	(arc
		(start 119.766334 -43.721782)
		(mid 119.839519 -43.672882)
		(end 119.925846 -43.655742)
		(width 0.14605)
		(layer "B.Cu")
		(net "PCIE_COMP_TO_IOM_CLK_4_DN")
	)
	(arc
		(start 119.70004 -43.881802)
		(mid 119.717267 -43.795195)
		(end 119.766334 -43.721782)
		(width 0.14605)
		(layer "B.Cu")
		(net "PCIE_COMP_TO_IOM_CLK_4_DN")
	)
	(arc
		(start 76.985622 -67.92214)
		(mid 77.190013 -68.006801)
		(end 77.274674 -68.211192)
		(width 0.14605)
		(layer "B.Cu")
		(net "PCIE_COMP_TO_IOM_CLK_4_DN")
	)
	(arc
		(start 120.153938 -43.655742)
		(mid 120.855835 -43.365007)
		(end 121.14657 -42.66311)
		(width 0.14605)
		(layer "B.Cu")
		(net "PCIE_COMP_TO_IOM_CLK_4_DN")
	)
	(segment
		(start 134.100062 -42.800016)
		(end 134.100062 -43.039538)
		(width 0.14605)
		(layer "F.Cu")
		(net "PCIE_COMP_TO_IOM_CLK_3_DP")
	)
	(segment
		(start 133.370066 -43.218608)
		(end 133.370066 -27.27833)
		(width 0.14605)
		(layer "F.Cu")
		(net "PCIE_COMP_TO_IOM_CLK_3_DP")
	)
	(segment
		(start 132.234178 -26.79065)
		(end 132.0546 -26.611072)
		(width 0.14605)
		(layer "F.Cu")
		(net "PCIE_COMP_TO_IOM_CLK_3_DP")
	)
	(segment
		(start 133.370066 -27.27833)
		(end 132.882386 -26.79065)
		(width 0.14605)
		(layer "F.Cu")
		(net "PCIE_COMP_TO_IOM_CLK_3_DP")
	)
	(segment
		(start 132.882386 -26.79065)
		(end 132.234178 -26.79065)
		(width 0.14605)
		(layer "F.Cu")
		(net "PCIE_COMP_TO_IOM_CLK_3_DP")
	)
	(segment
		(start 132.0546 -26.611072)
		(end 132.0546 -26.2001)
		(width 0.14605)
		(layer "F.Cu")
		(net "PCIE_COMP_TO_IOM_CLK_3_DP")
	)
	(segment
		(start 134.100062 -43.039538)
		(end 133.798056 -43.341544)
		(width 0.14605)
		(layer "F.Cu")
		(net "PCIE_COMP_TO_IOM_CLK_3_DP")
	)
	(segment
		(start 133.493002 -43.341544)
		(end 133.370066 -43.218608)
		(width 0.14605)
		(layer "F.Cu")
		(net "PCIE_COMP_TO_IOM_CLK_3_DP")
	)
	(segment
		(start 133.798056 -43.341544)
		(end 133.493002 -43.341544)
		(width 0.14605)
		(layer "F.Cu")
		(net "PCIE_COMP_TO_IOM_CLK_3_DP")
	)
	(segment
		(start 134.100062 -43.955462)
		(end 133.797294 -43.652694)
		(width 0.14605)
		(layer "F.Cu")
		(net "PCIE_COMP_TO_IOM_CLK_3_DN")
	)
	(segment
		(start 134.100062 -44.200064)
		(end 134.100062 -43.955462)
		(width 0.14605)
		(layer "F.Cu")
		(net "PCIE_COMP_TO_IOM_CLK_3_DN")
	)
	(segment
		(start 133.36397 -43.652694)
		(end 133.058916 -43.34764)
		(width 0.14605)
		(layer "F.Cu")
		(net "PCIE_COMP_TO_IOM_CLK_3_DN")
	)
	(segment
		(start 133.797294 -43.652694)
		(end 133.36397 -43.652694)
		(width 0.14605)
		(layer "F.Cu")
		(net "PCIE_COMP_TO_IOM_CLK_3_DN")
	)
	(segment
		(start 132.753354 -27.1018)
		(end 132.3086 -27.1018)
		(width 0.14605)
		(layer "F.Cu")
		(net "PCIE_COMP_TO_IOM_CLK_3_DN")
	)
	(segment
		(start 133.058916 -43.34764)
		(end 133.058916 -27.407362)
		(width 0.14605)
		(layer "F.Cu")
		(net "PCIE_COMP_TO_IOM_CLK_3_DN")
	)
	(segment
		(start 132.08 -27.3304)
		(end 132.08 -27.6098)
		(width 0.14605)
		(layer "F.Cu")
		(net "PCIE_COMP_TO_IOM_CLK_3_DN")
	)
	(segment
		(start 133.058916 -27.407362)
		(end 132.753354 -27.1018)
		(width 0.14605)
		(layer "F.Cu")
		(net "PCIE_COMP_TO_IOM_CLK_3_DN")
	)
	(segment
		(start 132.3086 -27.1018)
		(end 132.08 -27.3304)
		(width 0.14605)
		(layer "F.Cu")
		(net "PCIE_COMP_TO_IOM_CLK_3_DN")
	)
	(segment
		(start 208.298796 -83.791044)
		(end 207.769714 -83.261708)
		(width 0.14605)
		(layer "F.Cu")
		(net "PCIE_COMP_TO_IOM_CLK_2_DP")
	)
	(segment
		(start 207.769714 -82.361532)
		(end 208.2165 -81.915)
		(width 0.14605)
		(layer "F.Cu")
		(net "PCIE_COMP_TO_IOM_CLK_2_DP")
	)
	(segment
		(start 201.758804 -77.664564)
		(end 201.758804 -76.940918)
		(width 0.14605)
		(layer "F.Cu")
		(net "PCIE_COMP_TO_IOM_CLK_2_DP")
	)
	(segment
		(start 207.769714 -83.261708)
		(end 207.769714 -82.361532)
		(width 0.14605)
		(layer "F.Cu")
		(net "PCIE_COMP_TO_IOM_CLK_2_DP")
	)
	(segment
		(start 201.758804 -76.940918)
		(end 201.99985 -76.699872)
		(width 0.14605)
		(layer "F.Cu")
		(net "PCIE_COMP_TO_IOM_CLK_2_DP")
	)
	(segment
		(start 208.58734 -84.079588)
		(end 208.298796 -83.791044)
		(width 0.14605)
		(layer "F.Cu")
		(net "PCIE_COMP_TO_IOM_CLK_2_DP")
	)
	(segment
		(start 206.751936 -79.802228)
		(end 203.896468 -79.802228)
		(width 0.14605)
		(layer "F.Cu")
		(net "PCIE_COMP_TO_IOM_CLK_2_DP")
	)
	(segment
		(start 208.2165 -81.915)
		(end 207.8482 -81.5467)
		(width 0.14605)
		(layer "F.Cu")
		(net "PCIE_COMP_TO_IOM_CLK_2_DP")
	)
	(segment
		(start 207.8482 -81.5467)
		(end 207.8482 -80.898492)
		(width 0.14605)
		(layer "F.Cu")
		(net "PCIE_COMP_TO_IOM_CLK_2_DP")
	)
	(segment
		(start 203.896468 -79.802228)
		(end 201.758804 -77.664564)
		(width 0.14605)
		(layer "F.Cu")
		(net "PCIE_COMP_TO_IOM_CLK_2_DP")
	)
	(segment
		(start 207.8482 -80.898492)
		(end 206.751936 -79.802228)
		(width 0.14605)
		(layer "F.Cu")
		(net "PCIE_COMP_TO_IOM_CLK_2_DP")
	)
	(arc
		(start 208.995518 -84.079588)
		(mid 208.791466 -84.164072)
		(end 208.58734 -84.079588)
		(width 0.14605)
		(layer "F.Cu")
		(net "PCIE_COMP_TO_IOM_CLK_2_DP")
	)
	(segment
		(start 185.263028 -96.669606)
		(end 202.830176 -93.346016)
		(width 0.1397)
		(layer "In5.Cu")
		(net "PCIE_COMP_TO_IOM_CLK_2_DP")
	)
	(segment
		(start 148.850858 -69.75983)
		(end 150.088854 -76.159868)
		(width 0.1397)
		(layer "In5.Cu")
		(net "PCIE_COMP_TO_IOM_CLK_2_DP")
	)
	(segment
		(start 202.830176 -93.346016)
		(end 203.816712 -92.706952)
		(width 0.1397)
		(layer "In5.Cu")
		(net "PCIE_COMP_TO_IOM_CLK_2_DP")
	)
	(segment
		(start 148.850604 -69.75983)
		(end 148.850858 -69.75983)
		(width 0.1397)
		(layer "In5.Cu")
		(net "PCIE_COMP_TO_IOM_CLK_2_DP")
	)
	(segment
		(start 143.06804 -43.332146)
		(end 145.039334 -44.944284)
		(width 0.1397)
		(layer "In5.Cu")
		(net "PCIE_COMP_TO_IOM_CLK_2_DP")
	)
	(segment
		(start 206.6544 -83.4898)
		(end 208.011268 -83.4898)
		(width 0.1397)
		(layer "In5.Cu")
		(net "PCIE_COMP_TO_IOM_CLK_2_DP")
	)
	(segment
		(start 208.011268 -83.4898)
		(end 208.36128 -83.839812)
		(width 0.1397)
		(layer "In5.Cu")
		(net "PCIE_COMP_TO_IOM_CLK_2_DP")
	)
	(segment
		(start 141.299946 -42.800016)
		(end 141.299946 -43.116246)
		(width 0.1397)
		(layer "In5.Cu")
		(net "PCIE_COMP_TO_IOM_CLK_2_DP")
	)
	(segment
		(start 206.168752 -86.459822)
		(end 205.756256 -85.152992)
		(width 0.1397)
		(layer "In5.Cu")
		(net "PCIE_COMP_TO_IOM_CLK_2_DP")
	)
	(segment
		(start 172.641768 -94.26575)
		(end 185.263028 -96.669606)
		(width 0.1397)
		(layer "In5.Cu")
		(net "PCIE_COMP_TO_IOM_CLK_2_DP")
	)
	(segment
		(start 150.088854 -76.159868)
		(end 154.18435 -81.84261)
		(width 0.1397)
		(layer "In5.Cu")
		(net "PCIE_COMP_TO_IOM_CLK_2_DP")
	)
	(segment
		(start 159.504888 -86.7664)
		(end 161.664396 -88.072722)
		(width 0.1397)
		(layer "In5.Cu")
		(net "PCIE_COMP_TO_IOM_CLK_2_DP")
	)
	(segment
		(start 147.6121 -63.358776)
		(end 148.850604 -69.75983)
		(width 0.1397)
		(layer "In5.Cu")
		(net "PCIE_COMP_TO_IOM_CLK_2_DP")
	)
	(segment
		(start 154.18435 -81.84261)
		(end 158.384494 -84.488274)
		(width 0.1397)
		(layer "In5.Cu")
		(net "PCIE_COMP_TO_IOM_CLK_2_DP")
	)
	(segment
		(start 161.664396 -88.072722)
		(end 164.81806 -88.957912)
		(width 0.1397)
		(layer "In5.Cu")
		(net "PCIE_COMP_TO_IOM_CLK_2_DP")
	)
	(segment
		(start 145.039334 -44.944284)
		(end 146.694906 -47.45609)
		(width 0.1397)
		(layer "In5.Cu")
		(net "PCIE_COMP_TO_IOM_CLK_2_DP")
	)
	(segment
		(start 158.384494 -84.488274)
		(end 159.504888 -86.7664)
		(width 0.1397)
		(layer "In5.Cu")
		(net "PCIE_COMP_TO_IOM_CLK_2_DP")
	)
	(segment
		(start 148.72589 -56.652414)
		(end 147.6121 -63.358776)
		(width 0.1397)
		(layer "In5.Cu")
		(net "PCIE_COMP_TO_IOM_CLK_2_DP")
	)
	(segment
		(start 206.208376 -83.935824)
		(end 206.6544 -83.4898)
		(width 0.1397)
		(layer "In5.Cu")
		(net "PCIE_COMP_TO_IOM_CLK_2_DP")
	)
	(segment
		(start 203.816712 -92.706952)
		(end 205.150466 -90.768424)
		(width 0.1397)
		(layer "In5.Cu")
		(net "PCIE_COMP_TO_IOM_CLK_2_DP")
	)
	(segment
		(start 208.36128 -83.839812)
		(end 208.36128 -83.839558)
		(width 0.1397)
		(layer "In5.Cu")
		(net "PCIE_COMP_TO_IOM_CLK_2_DP")
	)
	(segment
		(start 205.756256 -85.152992)
		(end 206.208376 -83.935824)
		(width 0.1397)
		(layer "In5.Cu")
		(net "PCIE_COMP_TO_IOM_CLK_2_DP")
	)
	(segment
		(start 141.515846 -43.332146)
		(end 143.06804 -43.332146)
		(width 0.1397)
		(layer "In5.Cu")
		(net "PCIE_COMP_TO_IOM_CLK_2_DP")
	)
	(segment
		(start 146.694906 -47.45609)
		(end 148.72589 -56.652414)
		(width 0.1397)
		(layer "In5.Cu")
		(net "PCIE_COMP_TO_IOM_CLK_2_DP")
	)
	(segment
		(start 208.36128 -83.839558)
		(end 208.60131 -84.079588)
		(width 0.1397)
		(layer "In5.Cu")
		(net "PCIE_COMP_TO_IOM_CLK_2_DP")
	)
	(segment
		(start 205.150466 -90.768424)
		(end 206.168752 -86.459822)
		(width 0.1397)
		(layer "In5.Cu")
		(net "PCIE_COMP_TO_IOM_CLK_2_DP")
	)
	(segment
		(start 164.81806 -88.957912)
		(end 172.641768 -94.26575)
		(width 0.1397)
		(layer "In5.Cu")
		(net "PCIE_COMP_TO_IOM_CLK_2_DP")
	)
	(arc
		(start 208.60131 -84.079588)
		(mid 208.798414 -84.161306)
		(end 208.995518 -84.079588)
		(width 0.1397)
		(layer "In5.Cu")
		(net "PCIE_COMP_TO_IOM_CLK_2_DP")
	)
	(arc
		(start 141.299946 -43.116246)
		(mid 141.363182 -43.26891)
		(end 141.515846 -43.332146)
		(width 0.1397)
		(layer "In5.Cu")
		(net "PCIE_COMP_TO_IOM_CLK_2_DP")
	)
	(segment
		(start 206.622904 -80.113378)
		(end 203.767436 -80.113378)
		(width 0.14605)
		(layer "F.Cu")
		(net "PCIE_COMP_TO_IOM_CLK_2_DN")
	)
	(segment
		(start 207.458564 -82.300064)
		(end 207.0735 -81.915)
		(width 0.14605)
		(layer "F.Cu")
		(net "PCIE_COMP_TO_IOM_CLK_2_DN")
	)
	(segment
		(start 208.078578 -84.011262)
		(end 207.458564 -83.39074)
		(width 0.14605)
		(layer "F.Cu")
		(net "PCIE_COMP_TO_IOM_CLK_2_DN")
	)
	(segment
		(start 201.447654 -76.947522)
		(end 201.200004 -76.699872)
		(width 0.14605)
		(layer "F.Cu")
		(net "PCIE_COMP_TO_IOM_CLK_2_DN")
	)
	(segment
		(start 207.53705 -81.45145)
		(end 207.53705 -81.027524)
		(width 0.14605)
		(layer "F.Cu")
		(net "PCIE_COMP_TO_IOM_CLK_2_DN")
	)
	(segment
		(start 207.0735 -81.915)
		(end 207.53705 -81.45145)
		(width 0.14605)
		(layer "F.Cu")
		(net "PCIE_COMP_TO_IOM_CLK_2_DN")
	)
	(segment
		(start 207.53705 -81.027524)
		(end 206.622904 -80.113378)
		(width 0.14605)
		(layer "F.Cu")
		(net "PCIE_COMP_TO_IOM_CLK_2_DN")
	)
	(segment
		(start 203.767436 -80.113378)
		(end 201.447654 -77.793596)
		(width 0.14605)
		(layer "F.Cu")
		(net "PCIE_COMP_TO_IOM_CLK_2_DN")
	)
	(segment
		(start 207.458564 -83.39074)
		(end 207.458564 -82.300064)
		(width 0.14605)
		(layer "F.Cu")
		(net "PCIE_COMP_TO_IOM_CLK_2_DN")
	)
	(segment
		(start 201.447654 -77.793596)
		(end 201.447654 -76.947522)
		(width 0.14605)
		(layer "F.Cu")
		(net "PCIE_COMP_TO_IOM_CLK_2_DN")
	)
	(segment
		(start 208.367122 -84.299806)
		(end 208.078578 -84.011262)
		(width 0.14605)
		(layer "F.Cu")
		(net "PCIE_COMP_TO_IOM_CLK_2_DN")
	)
	(arc
		(start 208.367122 -84.707984)
		(mid 208.451606 -84.503932)
		(end 208.367122 -84.299806)
		(width 0.14605)
		(layer "F.Cu")
		(net "PCIE_COMP_TO_IOM_CLK_2_DN")
	)
	(segment
		(start 146.385534 -47.5869)
		(end 144.791176 -45.168312)
		(width 0.1397)
		(layer "In5.Cu")
		(net "PCIE_COMP_TO_IOM_CLK_2_DN")
	)
	(segment
		(start 202.957176 -93.65742)
		(end 202.955398 -93.658436)
		(width 0.1397)
		(layer "In5.Cu")
		(net "PCIE_COMP_TO_IOM_CLK_2_DN")
	)
	(segment
		(start 185.259726 -97.005394)
		(end 185.259726 -97.00514)
		(width 0.1397)
		(layer "In5.Cu")
		(net "PCIE_COMP_TO_IOM_CLK_2_DN")
	)
	(segment
		(start 185.259726 -97.00514)
		(end 172.51299 -94.577408)
		(width 0.1397)
		(layer "In5.Cu")
		(net "PCIE_COMP_TO_IOM_CLK_2_DN")
	)
	(segment
		(start 149.778466 -76.29398)
		(end 147.276566 -63.363348)
		(width 0.1397)
		(layer "In5.Cu")
		(net "PCIE_COMP_TO_IOM_CLK_2_DN")
	)
	(segment
		(start 185.262774 -97.005902)
		(end 185.259726 -97.005394)
		(width 0.1397)
		(layer "In5.Cu")
		(net "PCIE_COMP_TO_IOM_CLK_2_DN")
	)
	(segment
		(start 161.531808 -88.378538)
		(end 159.251142 -86.999064)
		(width 0.1397)
		(layer "In5.Cu")
		(net "PCIE_COMP_TO_IOM_CLK_2_DN")
	)
	(segment
		(start 206.105506 -85.161628)
		(end 206.511144 -86.447122)
		(width 0.1397)
		(layer "In5.Cu")
		(net "PCIE_COMP_TO_IOM_CLK_2_DN")
	)
	(segment
		(start 148.38934 -56.661304)
		(end 147.38731 -52.124102)
		(width 0.1397)
		(layer "In5.Cu")
		(net "PCIE_COMP_TO_IOM_CLK_2_DN")
	)
	(segment
		(start 144.791176 -45.168312)
		(end 142.950184 -43.662346)
		(width 0.1397)
		(layer "In5.Cu")
		(net "PCIE_COMP_TO_IOM_CLK_2_DN")
	)
	(segment
		(start 153.953718 -82.087974)
		(end 149.778466 -76.29398)
		(width 0.1397)
		(layer "In5.Cu")
		(net "PCIE_COMP_TO_IOM_CLK_2_DN")
	)
	(segment
		(start 206.791306 -83.82)
		(end 206.492856 -84.11845)
		(width 0.1397)
		(layer "In5.Cu")
		(net "PCIE_COMP_TO_IOM_CLK_2_DN")
	)
	(segment
		(start 141.299946 -43.878246)
		(end 141.299946 -44.200064)
		(width 0.1397)
		(layer "In5.Cu")
		(net "PCIE_COMP_TO_IOM_CLK_2_DN")
	)
	(segment
		(start 172.51299 -94.577408)
		(end 170.500548 -93.212158)
		(width 0.1397)
		(layer "In5.Cu")
		(net "PCIE_COMP_TO_IOM_CLK_2_DN")
	)
	(segment
		(start 158.129224 -84.718144)
		(end 153.953718 -82.087974)
		(width 0.1397)
		(layer "In5.Cu")
		(net "PCIE_COMP_TO_IOM_CLK_2_DN")
	)
	(segment
		(start 202.957176 -93.657166)
		(end 202.957176 -93.65742)
		(width 0.1397)
		(layer "In5.Cu")
		(net "PCIE_COMP_TO_IOM_CLK_2_DN")
	)
	(segment
		(start 164.67709 -89.261442)
		(end 161.531808 -88.378538)
		(width 0.1397)
		(layer "In5.Cu")
		(net "PCIE_COMP_TO_IOM_CLK_2_DN")
	)
	(segment
		(start 207.874362 -83.82)
		(end 206.791306 -83.82)
		(width 0.1397)
		(layer "In5.Cu")
		(net "PCIE_COMP_TO_IOM_CLK_2_DN")
	)
	(segment
		(start 148.389594 -56.661304)
		(end 148.38934 -56.661304)
		(width 0.1397)
		(layer "In5.Cu")
		(net "PCIE_COMP_TO_IOM_CLK_2_DN")
	)
	(segment
		(start 208.36763 -84.313268)
		(end 207.874362 -83.82)
		(width 0.1397)
		(layer "In5.Cu")
		(net "PCIE_COMP_TO_IOM_CLK_2_DN")
	)
	(segment
		(start 168.544748 -91.885516)
		(end 164.67709 -89.261442)
		(width 0.1397)
		(layer "In5.Cu")
		(net "PCIE_COMP_TO_IOM_CLK_2_DN")
	)
	(segment
		(start 147.38731 -52.124102)
		(end 146.385534 -47.5869)
		(width 0.1397)
		(layer "In5.Cu")
		(net "PCIE_COMP_TO_IOM_CLK_2_DN")
	)
	(segment
		(start 202.955398 -93.658436)
		(end 185.262774 -97.005902)
		(width 0.1397)
		(layer "In5.Cu")
		(net "PCIE_COMP_TO_IOM_CLK_2_DN")
	)
	(segment
		(start 206.492856 -84.11845)
		(end 206.105506 -85.161628)
		(width 0.1397)
		(layer "In5.Cu")
		(net "PCIE_COMP_TO_IOM_CLK_2_DN")
	)
	(segment
		(start 142.950184 -43.662346)
		(end 141.515846 -43.662346)
		(width 0.1397)
		(layer "In5.Cu")
		(net "PCIE_COMP_TO_IOM_CLK_2_DN")
	)
	(segment
		(start 205.457806 -90.904822)
		(end 204.051662 -92.948506)
		(width 0.1397)
		(layer "In5.Cu")
		(net "PCIE_COMP_TO_IOM_CLK_2_DN")
	)
	(segment
		(start 206.511144 -86.447122)
		(end 205.457806 -90.904822)
		(width 0.1397)
		(layer "In5.Cu")
		(net "PCIE_COMP_TO_IOM_CLK_2_DN")
	)
	(segment
		(start 204.051662 -92.948506)
		(end 202.957176 -93.657166)
		(width 0.1397)
		(layer "In5.Cu")
		(net "PCIE_COMP_TO_IOM_CLK_2_DN")
	)
	(segment
		(start 170.500548 -93.212158)
		(end 168.544748 -91.885516)
		(width 0.1397)
		(layer "In5.Cu")
		(net "PCIE_COMP_TO_IOM_CLK_2_DN")
	)
	(segment
		(start 159.251142 -86.999064)
		(end 158.129224 -84.718144)
		(width 0.1397)
		(layer "In5.Cu")
		(net "PCIE_COMP_TO_IOM_CLK_2_DN")
	)
	(segment
		(start 147.276566 -63.363348)
		(end 148.389594 -56.661304)
		(width 0.1397)
		(layer "In5.Cu")
		(net "PCIE_COMP_TO_IOM_CLK_2_DN")
	)
	(arc
		(start 208.367122 -84.707984)
		(mid 208.448901 -84.510731)
		(end 208.36763 -84.313268)
		(width 0.1397)
		(layer "In5.Cu")
		(net "PCIE_COMP_TO_IOM_CLK_2_DN")
	)
	(arc
		(start 141.515846 -43.662346)
		(mid 141.363182 -43.725582)
		(end 141.299946 -43.878246)
		(width 0.1397)
		(layer "In5.Cu")
		(net "PCIE_COMP_TO_IOM_CLK_2_DN")
	)
	(segment
		(start 198.76389 -77.8256)
		(end 198.76389 -76.73594)
		(width 0.14605)
		(layer "F.Cu")
		(net "PCIE_COMP_TO_IOM_9_DP")
	)
	(segment
		(start 201.429366 -85.461602)
		(end 200.432416 -84.464652)
		(width 0.14605)
		(layer "F.Cu")
		(net "PCIE_COMP_TO_IOM_9_DP")
	)
	(segment
		(start 200.432416 -79.494126)
		(end 198.76389 -77.8256)
		(width 0.14605)
		(layer "F.Cu")
		(net "PCIE_COMP_TO_IOM_9_DP")
	)
	(segment
		(start 198.76389 -76.73594)
		(end 198.799958 -76.699872)
		(width 0.14605)
		(layer "F.Cu")
		(net "PCIE_COMP_TO_IOM_9_DP")
	)
	(segment
		(start 200.432416 -84.464652)
		(end 200.432416 -79.494126)
		(width 0.14605)
		(layer "F.Cu")
		(net "PCIE_COMP_TO_IOM_9_DP")
	)
	(arc
		(start 201.837798 -85.461602)
		(mid 201.633582 -85.546191)
		(end 201.429366 -85.461602)
		(width 0.14605)
		(layer "F.Cu")
		(net "PCIE_COMP_TO_IOM_9_DP")
	)
	(segment
		(start 150.170134 -52.230782)
		(end 149.960838 -52.091082)
		(width 0.1397)
		(layer "In5.Cu")
		(net "PCIE_COMP_TO_IOM_9_DP")
	)
	(segment
		(start 147.442174 -38.59276)
		(end 147.232878 -38.453314)
		(width 0.1397)
		(layer "In5.Cu")
		(net "PCIE_COMP_TO_IOM_9_DP")
	)
	(segment
		(start 139.499848 -33.503362)
		(end 139.499848 -33.200086)
		(width 0.1397)
		(layer "In5.Cu")
		(net "PCIE_COMP_TO_IOM_9_DP")
	)
	(segment
		(start 146.821906 -35.491928)
		(end 146.73961 -35.080956)
		(width 0.1397)
		(layer "In5.Cu")
		(net "PCIE_COMP_TO_IOM_9_DP")
	)
	(segment
		(start 199.910446 -90.710258)
		(end 199.86117 -90.956892)
		(width 0.1397)
		(layer "In5.Cu")
		(net "PCIE_COMP_TO_IOM_9_DP")
	)
	(segment
		(start 146.73961 -35.080956)
		(end 146.530314 -34.94151)
		(width 0.1397)
		(layer "In5.Cu")
		(net "PCIE_COMP_TO_IOM_9_DP")
	)
	(segment
		(start 152.361138 -75.427332)
		(end 149.939756 -63.325248)
		(width 0.1397)
		(layer "In5.Cu")
		(net "PCIE_COMP_TO_IOM_9_DP")
	)
	(segment
		(start 150.581106 -55.192168)
		(end 150.720552 -54.982872)
		(width 0.1397)
		(layer "In5.Cu")
		(net "PCIE_COMP_TO_IOM_9_DP")
	)
	(segment
		(start 200.282048 -90.454988)
		(end 200.259188 -90.477848)
		(width 0.1397)
		(layer "In5.Cu")
		(net "PCIE_COMP_TO_IOM_9_DP")
	)
	(segment
		(start 147.290028 -37.833046)
		(end 147.207986 -37.422074)
		(width 0.1397)
		(layer "In5.Cu")
		(net "PCIE_COMP_TO_IOM_9_DP")
	)
	(segment
		(start 151.164036 -57.200292)
		(end 150.872444 -55.742586)
		(width 0.1397)
		(layer "In5.Cu")
		(net "PCIE_COMP_TO_IOM_9_DP")
	)
	(segment
		(start 198.917052 -91.372436)
		(end 198.867776 -91.61907)
		(width 0.1397)
		(layer "In5.Cu")
		(net "PCIE_COMP_TO_IOM_9_DP")
	)
	(segment
		(start 149.878542 -51.680364)
		(end 150.017988 -51.471068)
		(width 0.1397)
		(layer "In5.Cu")
		(net "PCIE_COMP_TO_IOM_9_DP")
	)
	(segment
		(start 198.867776 -91.61907)
		(end 198.519034 -91.85148)
		(width 0.1397)
		(layer "In5.Cu")
		(net "PCIE_COMP_TO_IOM_9_DP")
	)
	(segment
		(start 150.638256 -54.5719)
		(end 150.429214 -54.432454)
		(width 0.1397)
		(layer "In5.Cu")
		(net "PCIE_COMP_TO_IOM_9_DP")
	)
	(segment
		(start 146.486626 -33.81629)
		(end 144.232122 -30.403546)
		(width 0.1397)
		(layer "In5.Cu")
		(net "PCIE_COMP_TO_IOM_9_DP")
	)
	(segment
		(start 198.519034 -91.85148)
		(end 198.272654 -91.802204)
		(width 0.1397)
		(layer "In5.Cu")
		(net "PCIE_COMP_TO_IOM_9_DP")
	)
	(segment
		(start 147.232878 -38.453314)
		(end 147.150582 -38.042342)
		(width 0.1397)
		(layer "In5.Cu")
		(net "PCIE_COMP_TO_IOM_9_DP")
	)
	(segment
		(start 147.207986 -37.422074)
		(end 146.99869 -37.282628)
		(width 0.1397)
		(layer "In5.Cu")
		(net "PCIE_COMP_TO_IOM_9_DP")
	)
	(segment
		(start 155.775914 -80.547464)
		(end 152.361138 -75.427332)
		(width 0.1397)
		(layer "In5.Cu")
		(net "PCIE_COMP_TO_IOM_9_DP")
	)
	(segment
		(start 147.056094 -36.662614)
		(end 146.973798 -36.251642)
		(width 0.1397)
		(layer "In5.Cu")
		(net "PCIE_COMP_TO_IOM_9_DP")
	)
	(segment
		(start 146.916394 -36.871656)
		(end 147.056094 -36.662614)
		(width 0.1397)
		(layer "In5.Cu")
		(net "PCIE_COMP_TO_IOM_9_DP")
	)
	(segment
		(start 200.259188 -90.477848)
		(end 199.910446 -90.710258)
		(width 0.1397)
		(layer "In5.Cu")
		(net "PCIE_COMP_TO_IOM_9_DP")
	)
	(segment
		(start 146.764502 -36.112196)
		(end 146.68246 -35.701224)
		(width 0.1397)
		(layer "In5.Cu")
		(net "PCIE_COMP_TO_IOM_9_DP")
	)
	(segment
		(start 202.611228 -88.125554)
		(end 200.282048 -90.454734)
		(width 0.1397)
		(layer "In5.Cu")
		(net "PCIE_COMP_TO_IOM_9_DP")
	)
	(segment
		(start 147.150582 -38.042342)
		(end 147.290028 -37.833046)
		(width 0.1397)
		(layer "In5.Cu")
		(net "PCIE_COMP_TO_IOM_9_DP")
	)
	(segment
		(start 173.93793 -92.65539)
		(end 155.775914 -80.547464)
		(width 0.1397)
		(layer "In5.Cu")
		(net "PCIE_COMP_TO_IOM_9_DP")
	)
	(segment
		(start 202.611228 -86.63051)
		(end 202.611228 -88.125554)
		(width 0.1397)
		(layer "In5.Cu")
		(net "PCIE_COMP_TO_IOM_9_DP")
	)
	(segment
		(start 199.265794 -91.140026)
		(end 198.917052 -91.372436)
		(width 0.1397)
		(layer "In5.Cu")
		(net "PCIE_COMP_TO_IOM_9_DP")
	)
	(segment
		(start 150.872444 -55.742586)
		(end 150.663148 -55.60314)
		(width 0.1397)
		(layer "In5.Cu")
		(net "PCIE_COMP_TO_IOM_9_DP")
	)
	(segment
		(start 201.837798 -85.85708)
		(end 202.611228 -86.63051)
		(width 0.1397)
		(layer "In5.Cu")
		(net "PCIE_COMP_TO_IOM_9_DP")
	)
	(segment
		(start 150.720552 -54.982872)
		(end 150.638256 -54.5719)
		(width 0.1397)
		(layer "In5.Cu")
		(net "PCIE_COMP_TO_IOM_9_DP")
	)
	(segment
		(start 146.68246 -35.701224)
		(end 146.821906 -35.491928)
		(width 0.1397)
		(layer "In5.Cu")
		(net "PCIE_COMP_TO_IOM_9_DP")
	)
	(segment
		(start 146.530314 -34.94151)
		(end 146.448272 -34.530538)
		(width 0.1397)
		(layer "In5.Cu")
		(net "PCIE_COMP_TO_IOM_9_DP")
	)
	(segment
		(start 146.99869 -37.282628)
		(end 146.916394 -36.871656)
		(width 0.1397)
		(layer "In5.Cu")
		(net "PCIE_COMP_TO_IOM_9_DP")
	)
	(segment
		(start 150.486364 -53.812186)
		(end 150.404068 -53.401214)
		(width 0.1397)
		(layer "In5.Cu")
		(net "PCIE_COMP_TO_IOM_9_DP")
	)
	(segment
		(start 146.973798 -36.251642)
		(end 146.764502 -36.112196)
		(width 0.1397)
		(layer "In5.Cu")
		(net "PCIE_COMP_TO_IOM_9_DP")
	)
	(segment
		(start 143.11249 -29.284168)
		(end 140.41374 -29.284168)
		(width 0.1397)
		(layer "In5.Cu")
		(net "PCIE_COMP_TO_IOM_9_DP")
	)
	(segment
		(start 200.282048 -90.454734)
		(end 200.282048 -90.454988)
		(width 0.1397)
		(layer "In5.Cu")
		(net "PCIE_COMP_TO_IOM_9_DP")
	)
	(segment
		(start 150.404068 -53.401214)
		(end 150.195026 -53.261768)
		(width 0.1397)
		(layer "In5.Cu")
		(net "PCIE_COMP_TO_IOM_9_DP")
	)
	(segment
		(start 146.587718 -34.321242)
		(end 146.486626 -33.81629)
		(width 0.1397)
		(layer "In5.Cu")
		(net "PCIE_COMP_TO_IOM_9_DP")
	)
	(segment
		(start 140.41374 -29.284168)
		(end 138.765026 -30.932882)
		(width 0.1397)
		(layer "In5.Cu")
		(net "PCIE_COMP_TO_IOM_9_DP")
	)
	(segment
		(start 150.195026 -53.261768)
		(end 150.11273 -52.850796)
		(width 0.1397)
		(layer "In5.Cu")
		(net "PCIE_COMP_TO_IOM_9_DP")
	)
	(segment
		(start 199.86117 -90.956892)
		(end 199.512428 -91.189302)
		(width 0.1397)
		(layer "In5.Cu")
		(net "PCIE_COMP_TO_IOM_9_DP")
	)
	(segment
		(start 185.13552 -94.836996)
		(end 173.93793 -92.65539)
		(width 0.1397)
		(layer "In5.Cu")
		(net "PCIE_COMP_TO_IOM_9_DP")
	)
	(segment
		(start 138.765026 -30.932882)
		(end 138.765026 -33.447736)
		(width 0.1397)
		(layer "In5.Cu")
		(net "PCIE_COMP_TO_IOM_9_DP")
	)
	(segment
		(start 150.11273 -52.850796)
		(end 150.252176 -52.641754)
		(width 0.1397)
		(layer "In5.Cu")
		(net "PCIE_COMP_TO_IOM_9_DP")
	)
	(segment
		(start 150.346918 -54.021482)
		(end 150.486364 -53.812186)
		(width 0.1397)
		(layer "In5.Cu")
		(net "PCIE_COMP_TO_IOM_9_DP")
	)
	(segment
		(start 150.017988 -51.471068)
		(end 147.442174 -38.59276)
		(width 0.1397)
		(layer "In5.Cu")
		(net "PCIE_COMP_TO_IOM_9_DP")
	)
	(segment
		(start 150.429214 -54.432454)
		(end 150.346918 -54.021482)
		(width 0.1397)
		(layer "In5.Cu")
		(net "PCIE_COMP_TO_IOM_9_DP")
	)
	(segment
		(start 198.272654 -91.802204)
		(end 197.398132 -92.385134)
		(width 0.1397)
		(layer "In5.Cu")
		(net "PCIE_COMP_TO_IOM_9_DP")
	)
	(segment
		(start 144.232122 -30.403546)
		(end 143.11249 -29.284168)
		(width 0.1397)
		(layer "In5.Cu")
		(net "PCIE_COMP_TO_IOM_9_DP")
	)
	(segment
		(start 149.939756 -63.325248)
		(end 151.164036 -57.200292)
		(width 0.1397)
		(layer "In5.Cu")
		(net "PCIE_COMP_TO_IOM_9_DP")
	)
	(segment
		(start 197.398132 -92.385134)
		(end 185.13552 -94.836996)
		(width 0.1397)
		(layer "In5.Cu")
		(net "PCIE_COMP_TO_IOM_9_DP")
	)
	(segment
		(start 199.512428 -91.189302)
		(end 199.265794 -91.140026)
		(width 0.1397)
		(layer "In5.Cu")
		(net "PCIE_COMP_TO_IOM_9_DP")
	)
	(segment
		(start 150.252176 -52.641754)
		(end 150.170134 -52.230782)
		(width 0.1397)
		(layer "In5.Cu")
		(net "PCIE_COMP_TO_IOM_9_DP")
	)
	(segment
		(start 139.0523 -33.73501)
		(end 139.2682 -33.73501)
		(width 0.1397)
		(layer "In5.Cu")
		(net "PCIE_COMP_TO_IOM_9_DP")
	)
	(segment
		(start 149.960838 -52.091082)
		(end 149.878542 -51.680364)
		(width 0.1397)
		(layer "In5.Cu")
		(net "PCIE_COMP_TO_IOM_9_DP")
	)
	(segment
		(start 150.663148 -55.60314)
		(end 150.581106 -55.192168)
		(width 0.1397)
		(layer "In5.Cu")
		(net "PCIE_COMP_TO_IOM_9_DP")
	)
	(segment
		(start 146.448272 -34.530538)
		(end 146.587718 -34.321242)
		(width 0.1397)
		(layer "In5.Cu")
		(net "PCIE_COMP_TO_IOM_9_DP")
	)
	(arc
		(start 139.2682 -33.73501)
		(mid 139.432 -33.667162)
		(end 139.499848 -33.503362)
		(width 0.1397)
		(layer "In5.Cu")
		(net "PCIE_COMP_TO_IOM_9_DP")
	)
	(arc
		(start 138.765026 -33.447736)
		(mid 138.849167 -33.650869)
		(end 139.0523 -33.73501)
		(width 0.1397)
		(layer "In5.Cu")
		(net "PCIE_COMP_TO_IOM_9_DP")
	)
	(arc
		(start 201.837798 -85.461602)
		(mid 201.755839 -85.659378)
		(end 201.837798 -85.85708)
		(width 0.1397)
		(layer "In5.Cu")
		(net "PCIE_COMP_TO_IOM_9_DP")
	)
	(segment
		(start 200.163938 -84.636356)
		(end 200.121266 -84.593938)
		(width 0.14605)
		(layer "F.Cu")
		(net "PCIE_COMP_TO_IOM_9_DN")
	)
	(segment
		(start 200.121266 -79.623158)
		(end 198.45274 -77.954632)
		(width 0.14605)
		(layer "F.Cu")
		(net "PCIE_COMP_TO_IOM_9_DN")
	)
	(segment
		(start 198.4248 -76.823316)
		(end 198.4248 -76.3778)
		(width 0.14605)
		(layer "F.Cu")
		(net "PCIE_COMP_TO_IOM_9_DN")
	)
	(segment
		(start 198.4248 -76.3778)
		(end 198.799958 -75.900026)
		(width 0.14605)
		(layer "F.Cu")
		(net "PCIE_COMP_TO_IOM_9_DN")
	)
	(segment
		(start 201.209402 -85.68182)
		(end 200.163938 -84.636356)
		(width 0.14605)
		(layer "F.Cu")
		(net "PCIE_COMP_TO_IOM_9_DN")
	)
	(segment
		(start 198.45274 -76.851256)
		(end 198.4248 -76.823316)
		(width 0.14605)
		(layer "F.Cu")
		(net "PCIE_COMP_TO_IOM_9_DN")
	)
	(segment
		(start 198.45274 -77.954632)
		(end 198.45274 -76.851256)
		(width 0.14605)
		(layer "F.Cu")
		(net "PCIE_COMP_TO_IOM_9_DN")
	)
	(segment
		(start 200.121266 -84.593938)
		(end 200.121266 -79.623158)
		(width 0.14605)
		(layer "F.Cu")
		(net "PCIE_COMP_TO_IOM_9_DN")
	)
	(arc
		(start 201.209402 -86.089998)
		(mid 201.293886 -85.885946)
		(end 201.209402 -85.68182)
		(width 0.14605)
		(layer "F.Cu")
		(net "PCIE_COMP_TO_IOM_9_DN")
	)
	(segment
		(start 197.269354 -92.073984)
		(end 185.134758 -94.500192)
		(width 0.1397)
		(layer "In5.Cu")
		(net "PCIE_COMP_TO_IOM_9_DN")
	)
	(segment
		(start 143.249396 -28.953968)
		(end 140.276834 -28.953968)
		(width 0.1397)
		(layer "In5.Cu")
		(net "PCIE_COMP_TO_IOM_9_DN")
	)
	(segment
		(start 185.134758 -94.500192)
		(end 174.0662 -92.343732)
		(width 0.1397)
		(layer "In5.Cu")
		(net "PCIE_COMP_TO_IOM_9_DN")
	)
	(segment
		(start 174.0662 -92.343732)
		(end 156.014166 -80.309212)
		(width 0.1397)
		(layer "In5.Cu")
		(net "PCIE_COMP_TO_IOM_9_DN")
	)
	(segment
		(start 150.27656 -63.325248)
		(end 151.50084 -57.200292)
		(width 0.1397)
		(layer "In5.Cu")
		(net "PCIE_COMP_TO_IOM_9_DN")
	)
	(segment
		(start 202.281028 -86.767416)
		(end 202.281028 -87.988648)
		(width 0.1397)
		(layer "In5.Cu")
		(net "PCIE_COMP_TO_IOM_9_DN")
	)
	(segment
		(start 156.014166 -80.309212)
		(end 152.672288 -75.2983)
		(width 0.1397)
		(layer "In5.Cu")
		(net "PCIE_COMP_TO_IOM_9_DN")
	)
	(segment
		(start 202.098402 -86.585044)
		(end 202.130152 -86.61654)
		(width 0.1397)
		(layer "In5.Cu")
		(net "PCIE_COMP_TO_IOM_9_DN")
	)
	(segment
		(start 144.489424 -30.193488)
		(end 143.249396 -28.953968)
		(width 0.1397)
		(layer "In5.Cu")
		(net "PCIE_COMP_TO_IOM_9_DN")
	)
	(segment
		(start 151.50084 -57.200292)
		(end 146.79803 -33.68802)
		(width 0.1397)
		(layer "In5.Cu")
		(net "PCIE_COMP_TO_IOM_9_DN")
	)
	(segment
		(start 152.672288 -75.2983)
		(end 150.27656 -63.325248)
		(width 0.1397)
		(layer "In5.Cu")
		(net "PCIE_COMP_TO_IOM_9_DN")
	)
	(segment
		(start 140.276834 -28.953968)
		(end 138.434826 -30.795976)
		(width 0.1397)
		(layer "In5.Cu")
		(net "PCIE_COMP_TO_IOM_9_DN")
	)
	(segment
		(start 202.130152 -86.61654)
		(end 202.281028 -86.767416)
		(width 0.1397)
		(layer "In5.Cu")
		(net "PCIE_COMP_TO_IOM_9_DN")
	)
	(segment
		(start 202.281028 -87.988648)
		(end 200.048622 -90.221054)
		(width 0.1397)
		(layer "In5.Cu")
		(net "PCIE_COMP_TO_IOM_9_DN")
	)
	(segment
		(start 201.604118 -86.09076)
		(end 202.098402 -86.585044)
		(width 0.1397)
		(layer "In5.Cu")
		(net "PCIE_COMP_TO_IOM_9_DN")
	)
	(segment
		(start 139.499848 -34.296858)
		(end 139.499848 -34.600134)
		(width 0.1397)
		(layer "In5.Cu")
		(net "PCIE_COMP_TO_IOM_9_DN")
	)
	(segment
		(start 200.048622 -90.221054)
		(end 197.269354 -92.073984)
		(width 0.1397)
		(layer "In5.Cu")
		(net "PCIE_COMP_TO_IOM_9_DN")
	)
	(segment
		(start 146.79803 -33.68802)
		(end 144.489424 -30.193488)
		(width 0.1397)
		(layer "In5.Cu")
		(net "PCIE_COMP_TO_IOM_9_DN")
	)
	(segment
		(start 139.0523 -34.06521)
		(end 139.2682 -34.06521)
		(width 0.1397)
		(layer "In5.Cu")
		(net "PCIE_COMP_TO_IOM_9_DN")
	)
	(segment
		(start 138.434826 -30.795976)
		(end 138.434826 -33.447736)
		(width 0.1397)
		(layer "In5.Cu")
		(net "PCIE_COMP_TO_IOM_9_DN")
	)
	(arc
		(start 138.434826 -33.447736)
		(mid 138.61568 -33.884356)
		(end 139.0523 -34.06521)
		(width 0.1397)
		(layer "In5.Cu")
		(net "PCIE_COMP_TO_IOM_9_DN")
	)
	(arc
		(start 201.209402 -86.089998)
		(mid 201.406506 -86.00828)
		(end 201.60361 -86.089998)
		(width 0.1397)
		(layer "In5.Cu")
		(net "PCIE_COMP_TO_IOM_9_DN")
	)
	(arc
		(start 139.2682 -34.06521)
		(mid 139.432 -34.133058)
		(end 139.499848 -34.296858)
		(width 0.1397)
		(layer "In5.Cu")
		(net "PCIE_COMP_TO_IOM_9_DN")
	)
	(arc
		(start 201.60361 -86.089998)
		(mid 201.603864 -86.090379)
		(end 201.604118 -86.09076)
		(width 0.1397)
		(layer "In5.Cu")
		(net "PCIE_COMP_TO_IOM_9_DN")
	)
	(segment
		(start 199.600058 -77.370178)
		(end 199.600058 -76.699872)
		(width 0.14605)
		(layer "F.Cu")
		(net "PCIE_COMP_TO_IOM_8_DP")
	)
	(segment
		(start 204.428598 -84.877402)
		(end 204.401928 -84.904072)
		(width 0.14605)
		(layer "F.Cu")
		(net "PCIE_COMP_TO_IOM_8_DP")
	)
	(segment
		(start 204.046328 -84.904072)
		(end 203.817728 -84.675472)
		(width 0.14605)
		(layer "F.Cu")
		(net "PCIE_COMP_TO_IOM_8_DP")
	)
	(segment
		(start 203.25715 -84.11464)
		(end 203.25715 -81.02727)
		(width 0.14605)
		(layer "F.Cu")
		(net "PCIE_COMP_TO_IOM_8_DP")
	)
	(segment
		(start 203.25715 -81.02727)
		(end 199.600058 -77.370178)
		(width 0.14605)
		(layer "F.Cu")
		(net "PCIE_COMP_TO_IOM_8_DP")
	)
	(segment
		(start 203.817728 -84.675472)
		(end 203.25715 -84.11464)
		(width 0.14605)
		(layer "F.Cu")
		(net "PCIE_COMP_TO_IOM_8_DP")
	)
	(arc
		(start 204.401928 -84.904072)
		(mid 204.224128 -84.977719)
		(end 204.046328 -84.904072)
		(width 0.14605)
		(layer "F.Cu")
		(net "PCIE_COMP_TO_IOM_8_DP")
	)
	(segment
		(start 142.65529 -30.061154)
		(end 140.957046 -30.061154)
		(width 0.1397)
		(layer "In5.Cu")
		(net "PCIE_COMP_TO_IOM_8_DP")
	)
	(segment
		(start 204.428598 -85.27288)
		(end 204.568298 -85.41258)
		(width 0.1397)
		(layer "In5.Cu")
		(net "PCIE_COMP_TO_IOM_8_DP")
	)
	(segment
		(start 145.408904 -34.407094)
		(end 145.54962 -34.198814)
		(width 0.1397)
		(layer "In5.Cu")
		(net "PCIE_COMP_TO_IOM_8_DP")
	)
	(segment
		(start 146.23288 -37.714428)
		(end 146.15287 -37.302948)
		(width 0.1397)
		(layer "In5.Cu")
		(net "PCIE_COMP_TO_IOM_8_DP")
	)
	(segment
		(start 161.964878 -85.967316)
		(end 161.617406 -85.732874)
		(width 0.1397)
		(layer "In5.Cu")
		(net "PCIE_COMP_TO_IOM_8_DP")
	)
	(segment
		(start 145.925032 -36.130992)
		(end 145.716752 -35.99053)
		(width 0.1397)
		(layer "In5.Cu")
		(net "PCIE_COMP_TO_IOM_8_DP")
	)
	(segment
		(start 140.852398 -32.535114)
		(end 141.068298 -32.535114)
		(width 0.1397)
		(layer "In5.Cu")
		(net "PCIE_COMP_TO_IOM_8_DP")
	)
	(segment
		(start 149.442424 -54.226968)
		(end 149.362414 -53.815488)
		(width 0.1397)
		(layer "In5.Cu")
		(net "PCIE_COMP_TO_IOM_8_DP")
	)
	(segment
		(start 149.15388 -53.675026)
		(end 149.074124 -53.263546)
		(width 0.1397)
		(layer "In5.Cu")
		(net "PCIE_COMP_TO_IOM_8_DP")
	)
	(segment
		(start 146.005042 -36.542472)
		(end 145.925032 -36.130992)
		(width 0.1397)
		(layer "In5.Cu")
		(net "PCIE_COMP_TO_IOM_8_DP")
	)
	(segment
		(start 146.092164 -37.922708)
		(end 146.23288 -37.714428)
		(width 0.1397)
		(layer "In5.Cu")
		(net "PCIE_COMP_TO_IOM_8_DP")
	)
	(segment
		(start 149.590252 -54.987444)
		(end 149.381718 -54.846728)
		(width 0.1397)
		(layer "In5.Cu")
		(net "PCIE_COMP_TO_IOM_8_DP")
	)
	(segment
		(start 160.579816 -84.818728)
		(end 154.92984 -81.007712)
		(width 0.1397)
		(layer "In5.Cu")
		(net "PCIE_COMP_TO_IOM_8_DP")
	)
	(segment
		(start 161.5694 -85.485986)
		(end 161.222182 -85.251798)
		(width 0.1397)
		(layer "In5.Cu")
		(net "PCIE_COMP_TO_IOM_8_DP")
	)
	(segment
		(start 204.7748 -89.25687)
		(end 201.53503 -92.494862)
		(width 0.1397)
		(layer "In5.Cu")
		(net "PCIE_COMP_TO_IOM_8_DP")
	)
	(segment
		(start 160.627822 -85.065362)
		(end 160.579816 -84.818728)
		(width 0.1397)
		(layer "In5.Cu")
		(net "PCIE_COMP_TO_IOM_8_DP")
	)
	(segment
		(start 149.362414 -53.815488)
		(end 149.15388 -53.675026)
		(width 0.1397)
		(layer "In5.Cu")
		(net "PCIE_COMP_TO_IOM_8_DP")
	)
	(segment
		(start 148.952458 -63.609982)
		(end 150.125684 -57.742582)
		(width 0.1397)
		(layer "In5.Cu")
		(net "PCIE_COMP_TO_IOM_8_DP")
	)
	(segment
		(start 204.568044 -85.41258)
		(end 204.7748 -85.619336)
		(width 0.1397)
		(layer "In5.Cu")
		(net "PCIE_COMP_TO_IOM_8_DP")
	)
	(segment
		(start 146.380708 -38.474904)
		(end 146.172174 -38.334188)
		(width 0.1397)
		(layer "In5.Cu")
		(net "PCIE_COMP_TO_IOM_8_DP")
	)
	(segment
		(start 161.222182 -85.251798)
		(end 160.975294 -85.299804)
		(width 0.1397)
		(layer "In5.Cu")
		(net "PCIE_COMP_TO_IOM_8_DP")
	)
	(segment
		(start 149.897846 -56.570626)
		(end 149.817836 -56.1594)
		(width 0.1397)
		(layer "In5.Cu")
		(net "PCIE_COMP_TO_IOM_8_DP")
	)
	(segment
		(start 150.045674 -57.331102)
		(end 149.83714 -57.19064)
		(width 0.1397)
		(layer "In5.Cu")
		(net "PCIE_COMP_TO_IOM_8_DP")
	)
	(segment
		(start 146.15287 -37.302948)
		(end 145.944336 -37.162232)
		(width 0.1397)
		(layer "In5.Cu")
		(net "PCIE_COMP_TO_IOM_8_DP")
	)
	(segment
		(start 145.86458 -36.751006)
		(end 146.005042 -36.542472)
		(width 0.1397)
		(layer "In5.Cu")
		(net "PCIE_COMP_TO_IOM_8_DP")
	)
	(segment
		(start 149.301708 -54.435502)
		(end 149.442424 -54.226968)
		(width 0.1397)
		(layer "In5.Cu")
		(net "PCIE_COMP_TO_IOM_8_DP")
	)
	(segment
		(start 146.172174 -38.334188)
		(end 146.092164 -37.922708)
		(width 0.1397)
		(layer "In5.Cu")
		(net "PCIE_COMP_TO_IOM_8_DP")
	)
	(segment
		(start 149.381718 -54.846728)
		(end 149.301708 -54.435502)
		(width 0.1397)
		(layer "In5.Cu")
		(net "PCIE_COMP_TO_IOM_8_DP")
	)
	(segment
		(start 141.299946 -32.303466)
		(end 141.299946 -32.00019)
		(width 0.1397)
		(layer "In5.Cu")
		(net "PCIE_COMP_TO_IOM_8_DP")
	)
	(segment
		(start 140.957046 -30.061154)
		(end 140.565124 -30.453076)
		(width 0.1397)
		(layer "In5.Cu")
		(net "PCIE_COMP_TO_IOM_8_DP")
	)
	(segment
		(start 145.46961 -33.787334)
		(end 143.645128 -31.050992)
		(width 0.1397)
		(layer "In5.Cu")
		(net "PCIE_COMP_TO_IOM_8_DP")
	)
	(segment
		(start 162.211766 -85.91931)
		(end 161.964878 -85.967316)
		(width 0.1397)
		(layer "In5.Cu")
		(net "PCIE_COMP_TO_IOM_8_DP")
	)
	(segment
		(start 204.568298 -85.41258)
		(end 204.568044 -85.41258)
		(width 0.1397)
		(layer "In5.Cu")
		(net "PCIE_COMP_TO_IOM_8_DP")
	)
	(segment
		(start 140.565124 -30.453076)
		(end 140.565124 -32.24784)
		(width 0.1397)
		(layer "In5.Cu")
		(net "PCIE_COMP_TO_IOM_8_DP")
	)
	(segment
		(start 149.83714 -57.19064)
		(end 149.757384 -56.77916)
		(width 0.1397)
		(layer "In5.Cu")
		(net "PCIE_COMP_TO_IOM_8_DP")
	)
	(segment
		(start 160.975294 -85.299804)
		(end 160.627822 -85.065362)
		(width 0.1397)
		(layer "In5.Cu")
		(net "PCIE_COMP_TO_IOM_8_DP")
	)
	(segment
		(start 154.92984 -81.007712)
		(end 151.376634 -75.740006)
		(width 0.1397)
		(layer "In5.Cu")
		(net "PCIE_COMP_TO_IOM_8_DP")
	)
	(segment
		(start 185.28919 -95.743268)
		(end 173.329854 -93.418406)
		(width 0.1397)
		(layer "In5.Cu")
		(net "PCIE_COMP_TO_IOM_8_DP")
	)
	(segment
		(start 151.376634 -75.740006)
		(end 148.952458 -63.609982)
		(width 0.1397)
		(layer "In5.Cu")
		(net "PCIE_COMP_TO_IOM_8_DP")
	)
	(segment
		(start 204.7748 -85.619336)
		(end 204.7748 -89.25687)
		(width 0.1397)
		(layer "In5.Cu")
		(net "PCIE_COMP_TO_IOM_8_DP")
	)
	(segment
		(start 145.636742 -35.57905)
		(end 145.777458 -35.370516)
		(width 0.1397)
		(layer "In5.Cu")
		(net "PCIE_COMP_TO_IOM_8_DP")
	)
	(segment
		(start 149.670262 -55.398924)
		(end 149.590252 -54.987444)
		(width 0.1397)
		(layer "In5.Cu")
		(net "PCIE_COMP_TO_IOM_8_DP")
	)
	(segment
		(start 193.395346 -94.12224)
		(end 185.28919 -95.743268)
		(width 0.1397)
		(layer "In5.Cu")
		(net "PCIE_COMP_TO_IOM_8_DP")
	)
	(segment
		(start 150.125684 -57.742582)
		(end 150.045674 -57.331102)
		(width 0.1397)
		(layer "In5.Cu")
		(net "PCIE_COMP_TO_IOM_8_DP")
	)
	(segment
		(start 201.53503 -92.494862)
		(end 193.395346 -94.12224)
		(width 0.1397)
		(layer "In5.Cu")
		(net "PCIE_COMP_TO_IOM_8_DP")
	)
	(segment
		(start 145.697448 -34.95929)
		(end 145.488914 -34.818574)
		(width 0.1397)
		(layer "In5.Cu")
		(net "PCIE_COMP_TO_IOM_8_DP")
	)
	(segment
		(start 149.817836 -56.1594)
		(end 149.609556 -56.018684)
		(width 0.1397)
		(layer "In5.Cu")
		(net "PCIE_COMP_TO_IOM_8_DP")
	)
	(segment
		(start 145.54962 -34.198814)
		(end 145.46961 -33.787334)
		(width 0.1397)
		(layer "In5.Cu")
		(net "PCIE_COMP_TO_IOM_8_DP")
	)
	(segment
		(start 149.609556 -56.018684)
		(end 149.529546 -55.607204)
		(width 0.1397)
		(layer "In5.Cu")
		(net "PCIE_COMP_TO_IOM_8_DP")
	)
	(segment
		(start 149.074124 -53.263546)
		(end 149.214586 -53.055012)
		(width 0.1397)
		(layer "In5.Cu")
		(net "PCIE_COMP_TO_IOM_8_DP")
	)
	(segment
		(start 173.329854 -93.418406)
		(end 162.211766 -85.91931)
		(width 0.1397)
		(layer "In5.Cu")
		(net "PCIE_COMP_TO_IOM_8_DP")
	)
	(segment
		(start 149.214586 -53.055012)
		(end 146.380708 -38.474904)
		(width 0.1397)
		(layer "In5.Cu")
		(net "PCIE_COMP_TO_IOM_8_DP")
	)
	(segment
		(start 143.645128 -31.050992)
		(end 142.65529 -30.061154)
		(width 0.1397)
		(layer "In5.Cu")
		(net "PCIE_COMP_TO_IOM_8_DP")
	)
	(segment
		(start 145.944336 -37.162232)
		(end 145.86458 -36.751006)
		(width 0.1397)
		(layer "In5.Cu")
		(net "PCIE_COMP_TO_IOM_8_DP")
	)
	(segment
		(start 149.757384 -56.77916)
		(end 149.897846 -56.570626)
		(width 0.1397)
		(layer "In5.Cu")
		(net "PCIE_COMP_TO_IOM_8_DP")
	)
	(segment
		(start 145.488914 -34.818574)
		(end 145.408904 -34.407094)
		(width 0.1397)
		(layer "In5.Cu")
		(net "PCIE_COMP_TO_IOM_8_DP")
	)
	(segment
		(start 145.716752 -35.99053)
		(end 145.636742 -35.57905)
		(width 0.1397)
		(layer "In5.Cu")
		(net "PCIE_COMP_TO_IOM_8_DP")
	)
	(segment
		(start 145.777458 -35.370516)
		(end 145.697448 -34.95929)
		(width 0.1397)
		(layer "In5.Cu")
		(net "PCIE_COMP_TO_IOM_8_DP")
	)
	(segment
		(start 161.617406 -85.732874)
		(end 161.5694 -85.485986)
		(width 0.1397)
		(layer "In5.Cu")
		(net "PCIE_COMP_TO_IOM_8_DP")
	)
	(segment
		(start 149.529546 -55.607204)
		(end 149.670262 -55.398924)
		(width 0.1397)
		(layer "In5.Cu")
		(net "PCIE_COMP_TO_IOM_8_DP")
	)
	(arc
		(start 141.068298 -32.535114)
		(mid 141.232098 -32.467266)
		(end 141.299946 -32.303466)
		(width 0.1397)
		(layer "In5.Cu")
		(net "PCIE_COMP_TO_IOM_8_DP")
	)
	(arc
		(start 204.428598 -84.877402)
		(mid 204.346639 -85.075178)
		(end 204.428598 -85.27288)
		(width 0.1397)
		(layer "In5.Cu")
		(net "PCIE_COMP_TO_IOM_8_DP")
	)
	(arc
		(start 140.565124 -32.24784)
		(mid 140.649265 -32.450973)
		(end 140.852398 -32.535114)
		(width 0.1397)
		(layer "In5.Cu")
		(net "PCIE_COMP_TO_IOM_8_DP")
	)
	(segment
		(start 203.82611 -85.12429)
		(end 203.49591 -84.79409)
		(width 0.14605)
		(layer "F.Cu")
		(net "PCIE_COMP_TO_IOM_8_DN")
	)
	(segment
		(start 202.946 -84.243672)
		(end 202.946 -81.156302)
		(width 0.14605)
		(layer "F.Cu")
		(net "PCIE_COMP_TO_IOM_8_DN")
	)
	(segment
		(start 202.946 -81.156302)
		(end 199.288908 -77.49921)
		(width 0.14605)
		(layer "F.Cu")
		(net "PCIE_COMP_TO_IOM_8_DN")
	)
	(segment
		(start 199.288908 -77.49921)
		(end 199.288908 -76.88072)
		(width 0.14605)
		(layer "F.Cu")
		(net "PCIE_COMP_TO_IOM_8_DN")
	)
	(segment
		(start 203.800202 -85.505798)
		(end 203.82611 -85.47989)
		(width 0.14605)
		(layer "F.Cu")
		(net "PCIE_COMP_TO_IOM_8_DN")
	)
	(segment
		(start 199.288908 -76.88072)
		(end 199.2122 -76.804012)
		(width 0.14605)
		(layer "F.Cu")
		(net "PCIE_COMP_TO_IOM_8_DN")
	)
	(segment
		(start 199.2122 -76.287884)
		(end 199.600058 -75.900026)
		(width 0.14605)
		(layer "F.Cu")
		(net "PCIE_COMP_TO_IOM_8_DN")
	)
	(segment
		(start 203.49591 -84.79409)
		(end 202.946 -84.243672)
		(width 0.14605)
		(layer "F.Cu")
		(net "PCIE_COMP_TO_IOM_8_DN")
	)
	(segment
		(start 199.2122 -76.804012)
		(end 199.2122 -76.287884)
		(width 0.14605)
		(layer "F.Cu")
		(net "PCIE_COMP_TO_IOM_8_DN")
	)
	(arc
		(start 203.82611 -85.47989)
		(mid 203.899757 -85.30209)
		(end 203.82611 -85.12429)
		(width 0.14605)
		(layer "F.Cu")
		(net "PCIE_COMP_TO_IOM_8_DN")
	)
	(segment
		(start 201.372216 -92.19057)
		(end 185.288174 -95.406464)
		(width 0.1397)
		(layer "In5.Cu")
		(net "PCIE_COMP_TO_IOM_8_DN")
	)
	(segment
		(start 140.852398 -32.865314)
		(end 141.068298 -32.865314)
		(width 0.1397)
		(layer "In5.Cu")
		(net "PCIE_COMP_TO_IOM_8_DN")
	)
	(segment
		(start 142.792196 -29.730954)
		(end 140.82014 -29.730954)
		(width 0.1397)
		(layer "In5.Cu")
		(net "PCIE_COMP_TO_IOM_8_DN")
	)
	(segment
		(start 155.167838 -80.769714)
		(end 151.68753 -75.610212)
		(width 0.1397)
		(layer "In5.Cu")
		(net "PCIE_COMP_TO_IOM_8_DN")
	)
	(segment
		(start 204.4446 -89.119964)
		(end 201.372216 -92.19057)
		(width 0.1397)
		(layer "In5.Cu")
		(net "PCIE_COMP_TO_IOM_8_DN")
	)
	(segment
		(start 140.234924 -30.31617)
		(end 140.234924 -32.24784)
		(width 0.1397)
		(layer "In5.Cu")
		(net "PCIE_COMP_TO_IOM_8_DN")
	)
	(segment
		(start 150.462488 -57.743598)
		(end 145.781268 -33.659318)
		(width 0.1397)
		(layer "In5.Cu")
		(net "PCIE_COMP_TO_IOM_8_DN")
	)
	(segment
		(start 149.289262 -63.609982)
		(end 150.462488 -57.743598)
		(width 0.1397)
		(layer "In5.Cu")
		(net "PCIE_COMP_TO_IOM_8_DN")
	)
	(segment
		(start 204.194918 -85.50656)
		(end 204.4446 -85.756242)
		(width 0.1397)
		(layer "In5.Cu")
		(net "PCIE_COMP_TO_IOM_8_DN")
	)
	(segment
		(start 179.37353 -94.25686)
		(end 173.458886 -93.107002)
		(width 0.1397)
		(layer "In5.Cu")
		(net "PCIE_COMP_TO_IOM_8_DN")
	)
	(segment
		(start 145.781268 -33.659318)
		(end 143.901922 -30.840426)
		(width 0.1397)
		(layer "In5.Cu")
		(net "PCIE_COMP_TO_IOM_8_DN")
	)
	(segment
		(start 140.82014 -29.730954)
		(end 140.234924 -30.31617)
		(width 0.1397)
		(layer "In5.Cu")
		(net "PCIE_COMP_TO_IOM_8_DN")
	)
	(segment
		(start 185.288174 -95.406464)
		(end 179.37353 -94.25686)
		(width 0.1397)
		(layer "In5.Cu")
		(net "PCIE_COMP_TO_IOM_8_DN")
	)
	(segment
		(start 173.458886 -93.107002)
		(end 155.167838 -80.769714)
		(width 0.1397)
		(layer "In5.Cu")
		(net "PCIE_COMP_TO_IOM_8_DN")
	)
	(segment
		(start 151.68753 -75.610212)
		(end 149.289262 -63.609982)
		(width 0.1397)
		(layer "In5.Cu")
		(net "PCIE_COMP_TO_IOM_8_DN")
	)
	(segment
		(start 143.901922 -30.840426)
		(end 142.792196 -29.730954)
		(width 0.1397)
		(layer "In5.Cu")
		(net "PCIE_COMP_TO_IOM_8_DN")
	)
	(segment
		(start 141.299946 -33.096962)
		(end 141.299946 -33.399984)
		(width 0.1397)
		(layer "In5.Cu")
		(net "PCIE_COMP_TO_IOM_8_DN")
	)
	(segment
		(start 204.4446 -85.756242)
		(end 204.4446 -89.119964)
		(width 0.1397)
		(layer "In5.Cu")
		(net "PCIE_COMP_TO_IOM_8_DN")
	)
	(arc
		(start 204.19441 -85.505798)
		(mid 204.194664 -85.506179)
		(end 204.194918 -85.50656)
		(width 0.1397)
		(layer "In5.Cu")
		(net "PCIE_COMP_TO_IOM_8_DN")
	)
	(arc
		(start 141.068298 -32.865314)
		(mid 141.232098 -32.933162)
		(end 141.299946 -33.096962)
		(width 0.1397)
		(layer "In5.Cu")
		(net "PCIE_COMP_TO_IOM_8_DN")
	)
	(arc
		(start 140.234924 -32.24784)
		(mid 140.415778 -32.68446)
		(end 140.852398 -32.865314)
		(width 0.1397)
		(layer "In5.Cu")
		(net "PCIE_COMP_TO_IOM_8_DN")
	)
	(arc
		(start 203.800202 -85.505798)
		(mid 203.997306 -85.42408)
		(end 204.19441 -85.505798)
		(width 0.1397)
		(layer "In5.Cu")
		(net "PCIE_COMP_TO_IOM_8_DN")
	)
	(segment
		(start 76.32954 -92.95003)
		(end 76.57719 -93.19768)
		(width 0.14605)
		(layer "F.Cu")
		(net "PCIE_COMP_TO_IOM_23_DP")
	)
	(segment
		(start 76.57719 -93.19768)
		(end 77.033628 -93.19768)
		(width 0.14605)
		(layer "F.Cu")
		(net "PCIE_COMP_TO_IOM_23_DP")
	)
	(segment
		(start 77.283818 -92.94749)
		(end 77.283818 -92.911168)
		(width 0.14605)
		(layer "F.Cu")
		(net "PCIE_COMP_TO_IOM_23_DP")
	)
	(segment
		(start 75.475084 -92.95003)
		(end 76.32954 -92.95003)
		(width 0.14605)
		(layer "F.Cu")
		(net "PCIE_COMP_TO_IOM_23_DP")
	)
	(arc
		(start 77.033628 -93.19768)
		(mid 77.210539 -93.124401)
		(end 77.283818 -92.94749)
		(width 0.14605)
		(layer "F.Cu")
		(net "PCIE_COMP_TO_IOM_23_DP")
	)
	(segment
		(start 80.567276 -93.199966)
		(end 77.516228 -93.199966)
		(width 0.14605)
		(layer "B.Cu")
		(net "PCIE_COMP_TO_IOM_23_DP")
	)
	(segment
		(start 77.283818 -92.967556)
		(end 77.283818 -92.911168)
		(width 0.14605)
		(layer "B.Cu")
		(net "PCIE_COMP_TO_IOM_23_DP")
	)
	(segment
		(start 107.099862 -33.200086)
		(end 107.099862 -33.587182)
		(width 0.14605)
		(layer "B.Cu")
		(net "PCIE_COMP_TO_IOM_23_DP")
	)
	(segment
		(start 98.347276 -44.92625)
		(end 99.666806 -51.525424)
		(width 0.14605)
		(layer "B.Cu")
		(net "PCIE_COMP_TO_IOM_23_DP")
	)
	(segment
		(start 81.516474 -92.250768)
		(end 80.567276 -93.199966)
		(width 0.14605)
		(layer "B.Cu")
		(net "PCIE_COMP_TO_IOM_23_DP")
	)
	(segment
		(start 100.228908 -36.658804)
		(end 99.899216 -37.150548)
		(width 0.14605)
		(layer "B.Cu")
		(net "PCIE_COMP_TO_IOM_23_DP")
	)
	(segment
		(start 98.550222 -43.90898)
		(end 98.347276 -44.92625)
		(width 0.14605)
		(layer "B.Cu")
		(net "PCIE_COMP_TO_IOM_23_DP")
	)
	(segment
		(start 89.348818 -86.983062)
		(end 88.548972 -90.357706)
		(width 0.14605)
		(layer "B.Cu")
		(net "PCIE_COMP_TO_IOM_23_DP")
	)
	(segment
		(start 85.24113 -93.665548)
		(end 84.795868 -93.665548)
		(width 0.14605)
		(layer "B.Cu")
		(net "PCIE_COMP_TO_IOM_23_DP")
	)
	(segment
		(start 83.381088 -92.250768)
		(end 81.516474 -92.250768)
		(width 0.14605)
		(layer "B.Cu")
		(net "PCIE_COMP_TO_IOM_23_DP")
	)
	(segment
		(start 93.958664 -80.06715)
		(end 89.348818 -86.983062)
		(width 0.14605)
		(layer "B.Cu")
		(net "PCIE_COMP_TO_IOM_23_DP")
	)
	(segment
		(start 99.899216 -37.150548)
		(end 98.645726 -43.430698)
		(width 0.14605)
		(layer "B.Cu")
		(net "PCIE_COMP_TO_IOM_23_DP")
	)
	(segment
		(start 105.586022 -33.744408)
		(end 104.178354 -34.026094)
		(width 0.14605)
		(layer "B.Cu")
		(net "PCIE_COMP_TO_IOM_23_DP")
	)
	(segment
		(start 98.645726 -43.430698)
		(end 98.550222 -43.90898)
		(width 0.14605)
		(layer "B.Cu")
		(net "PCIE_COMP_TO_IOM_23_DP")
	)
	(segment
		(start 104.178354 -34.026094)
		(end 100.228908 -36.658804)
		(width 0.14605)
		(layer "B.Cu")
		(net "PCIE_COMP_TO_IOM_23_DP")
	)
	(segment
		(start 106.942382 -33.744408)
		(end 105.586022 -33.744408)
		(width 0.14605)
		(layer "B.Cu")
		(net "PCIE_COMP_TO_IOM_23_DP")
	)
	(segment
		(start 88.548972 -90.357706)
		(end 85.24113 -93.665548)
		(width 0.14605)
		(layer "B.Cu")
		(net "PCIE_COMP_TO_IOM_23_DP")
	)
	(segment
		(start 99.666806 -51.525424)
		(end 93.958664 -80.06715)
		(width 0.14605)
		(layer "B.Cu")
		(net "PCIE_COMP_TO_IOM_23_DP")
	)
	(segment
		(start 84.795868 -93.665548)
		(end 83.381088 -92.250768)
		(width 0.14605)
		(layer "B.Cu")
		(net "PCIE_COMP_TO_IOM_23_DP")
	)
	(arc
		(start 107.053888 -33.69818)
		(mid 107.002743 -33.732417)
		(end 106.942382 -33.744408)
		(width 0.14605)
		(layer "B.Cu")
		(net "PCIE_COMP_TO_IOM_23_DP")
	)
	(arc
		(start 77.516228 -93.199966)
		(mid 77.351889 -93.131895)
		(end 77.283818 -92.967556)
		(width 0.14605)
		(layer "B.Cu")
		(net "PCIE_COMP_TO_IOM_23_DP")
	)
	(arc
		(start 107.099862 -33.587182)
		(mid 107.087913 -33.647253)
		(end 107.053888 -33.69818)
		(width 0.14605)
		(layer "B.Cu")
		(net "PCIE_COMP_TO_IOM_23_DP")
	)
	(segment
		(start 77.283818 -93.75902)
		(end 77.283818 -93.800168)
		(width 0.14605)
		(layer "F.Cu")
		(net "PCIE_COMP_TO_IOM_23_DN")
	)
	(segment
		(start 76.318872 -93.75013)
		(end 76.560172 -93.50883)
		(width 0.14605)
		(layer "F.Cu")
		(net "PCIE_COMP_TO_IOM_23_DN")
	)
	(segment
		(start 76.560172 -93.50883)
		(end 77.033628 -93.50883)
		(width 0.14605)
		(layer "F.Cu")
		(net "PCIE_COMP_TO_IOM_23_DN")
	)
	(segment
		(start 75.475084 -93.75013)
		(end 76.318872 -93.75013)
		(width 0.14605)
		(layer "F.Cu")
		(net "PCIE_COMP_TO_IOM_23_DN")
	)
	(arc
		(start 77.033628 -93.50883)
		(mid 77.210539 -93.582109)
		(end 77.283818 -93.75902)
		(width 0.14605)
		(layer "F.Cu")
		(net "PCIE_COMP_TO_IOM_23_DN")
	)
	(segment
		(start 105.61701 -34.055558)
		(end 104.299766 -34.31921)
		(width 0.14605)
		(layer "B.Cu")
		(net "PCIE_COMP_TO_IOM_23_DN")
	)
	(segment
		(start 89.638886 -87.1093)
		(end 88.83142 -90.51544)
		(width 0.14605)
		(layer "B.Cu")
		(net "PCIE_COMP_TO_IOM_23_DN")
	)
	(segment
		(start 99.984306 -51.525424)
		(end 94.25178 -80.188562)
		(width 0.14605)
		(layer "B.Cu")
		(net "PCIE_COMP_TO_IOM_23_DN")
	)
	(segment
		(start 99.046538 -43.013376)
		(end 98.783902 -44.329096)
		(width 0.14605)
		(layer "B.Cu")
		(net "PCIE_COMP_TO_IOM_23_DN")
	)
	(segment
		(start 80.696308 -93.511116)
		(end 77.516228 -93.511116)
		(width 0.14605)
		(layer "B.Cu")
		(net "PCIE_COMP_TO_IOM_23_DN")
	)
	(segment
		(start 77.283818 -93.743526)
		(end 77.283818 -93.800168)
		(width 0.14605)
		(layer "B.Cu")
		(net "PCIE_COMP_TO_IOM_23_DN")
	)
	(segment
		(start 83.252056 -92.561918)
		(end 81.645506 -92.561918)
		(width 0.14605)
		(layer "B.Cu")
		(net "PCIE_COMP_TO_IOM_23_DN")
	)
	(segment
		(start 99.046792 -43.013122)
		(end 99.046538 -43.013376)
		(width 0.14605)
		(layer "B.Cu")
		(net "PCIE_COMP_TO_IOM_23_DN")
	)
	(segment
		(start 84.666836 -93.976698)
		(end 83.252056 -92.561918)
		(width 0.14605)
		(layer "B.Cu")
		(net "PCIE_COMP_TO_IOM_23_DN")
	)
	(segment
		(start 88.83142 -90.51544)
		(end 85.370162 -93.976698)
		(width 0.14605)
		(layer "B.Cu")
		(net "PCIE_COMP_TO_IOM_23_DN")
	)
	(segment
		(start 100.45319 -36.883594)
		(end 100.192332 -37.272468)
		(width 0.14605)
		(layer "B.Cu")
		(net "PCIE_COMP_TO_IOM_23_DN")
	)
	(segment
		(start 98.664776 -44.92625)
		(end 99.984306 -51.525424)
		(width 0.14605)
		(layer "B.Cu")
		(net "PCIE_COMP_TO_IOM_23_DN")
	)
	(segment
		(start 98.760026 -44.44873)
		(end 98.664776 -44.92625)
		(width 0.14605)
		(layer "B.Cu")
		(net "PCIE_COMP_TO_IOM_23_DN")
	)
	(segment
		(start 94.25178 -80.188562)
		(end 89.638886 -87.1093)
		(width 0.14605)
		(layer "B.Cu")
		(net "PCIE_COMP_TO_IOM_23_DN")
	)
	(segment
		(start 104.299766 -34.31921)
		(end 100.45319 -36.883594)
		(width 0.14605)
		(layer "B.Cu")
		(net "PCIE_COMP_TO_IOM_23_DN")
	)
	(segment
		(start 107.099862 -34.600134)
		(end 107.099862 -34.272728)
		(width 0.14605)
		(layer "B.Cu")
		(net "PCIE_COMP_TO_IOM_23_DN")
	)
	(segment
		(start 99.4283 -41.09974)
		(end 99.046792 -43.013122)
		(width 0.14605)
		(layer "B.Cu")
		(net "PCIE_COMP_TO_IOM_23_DN")
	)
	(segment
		(start 106.911902 -34.055558)
		(end 105.61701 -34.055558)
		(width 0.14605)
		(layer "B.Cu")
		(net "PCIE_COMP_TO_IOM_23_DN")
	)
	(segment
		(start 107.036108 -34.119312)
		(end 107.015534 -34.098484)
		(width 0.14605)
		(layer "B.Cu")
		(net "PCIE_COMP_TO_IOM_23_DN")
	)
	(segment
		(start 85.370162 -93.976698)
		(end 84.666836 -93.976698)
		(width 0.14605)
		(layer "B.Cu")
		(net "PCIE_COMP_TO_IOM_23_DN")
	)
	(segment
		(start 98.783902 -44.329096)
		(end 98.760026 -44.44873)
		(width 0.14605)
		(layer "B.Cu")
		(net "PCIE_COMP_TO_IOM_23_DN")
	)
	(segment
		(start 100.192332 -37.272468)
		(end 99.4283 -41.09974)
		(width 0.14605)
		(layer "B.Cu")
		(net "PCIE_COMP_TO_IOM_23_DN")
	)
	(segment
		(start 81.645506 -92.561918)
		(end 80.696308 -93.511116)
		(width 0.14605)
		(layer "B.Cu")
		(net "PCIE_COMP_TO_IOM_23_DN")
	)
	(arc
		(start 107.015534 -34.098484)
		(mid 106.968001 -34.06669)
		(end 106.911902 -34.055558)
		(width 0.14605)
		(layer "B.Cu")
		(net "PCIE_COMP_TO_IOM_23_DN")
	)
	(arc
		(start 107.099862 -34.272728)
		(mid 107.083248 -34.189674)
		(end 107.036108 -34.119312)
		(width 0.14605)
		(layer "B.Cu")
		(net "PCIE_COMP_TO_IOM_23_DN")
	)
	(arc
		(start 77.516228 -93.511116)
		(mid 77.351889 -93.579187)
		(end 77.283818 -93.743526)
		(width 0.14605)
		(layer "B.Cu")
		(net "PCIE_COMP_TO_IOM_23_DN")
	)
	(segment
		(start 76.56068 -89.997534)
		(end 77.835252 -89.997534)
		(width 0.14605)
		(layer "F.Cu")
		(net "PCIE_COMP_TO_IOM_22_DP")
	)
	(segment
		(start 76.313284 -89.750138)
		(end 76.56068 -89.997534)
		(width 0.14605)
		(layer "F.Cu")
		(net "PCIE_COMP_TO_IOM_22_DP")
	)
	(segment
		(start 75.475084 -89.750138)
		(end 76.313284 -89.750138)
		(width 0.14605)
		(layer "F.Cu")
		(net "PCIE_COMP_TO_IOM_22_DP")
	)
	(arc
		(start 77.835252 -89.997534)
		(mid 78.038026 -89.913542)
		(end 78.122018 -89.710768)
		(width 0.14605)
		(layer "F.Cu")
		(net "PCIE_COMP_TO_IOM_22_DP")
	)
	(segment
		(start 87.190072 -88.137746)
		(end 86.231222 -89.096596)
		(width 0.14605)
		(layer "B.Cu")
		(net "PCIE_COMP_TO_IOM_22_DP")
	)
	(segment
		(start 106.781346 -30.949392)
		(end 106.105452 -31.083758)
		(width 0.14605)
		(layer "B.Cu")
		(net "PCIE_COMP_TO_IOM_22_DP")
	)
	(segment
		(start 108.155486 -31.510986)
		(end 107.593892 -30.949392)
		(width 0.14605)
		(layer "B.Cu")
		(net "PCIE_COMP_TO_IOM_22_DP")
	)
	(segment
		(start 108.89996 -32.00019)
		(end 108.89996 -32.318198)
		(width 0.14605)
		(layer "B.Cu")
		(net "PCIE_COMP_TO_IOM_22_DP")
	)
	(segment
		(start 86.231222 -89.096596)
		(end 84.924646 -89.096596)
		(width 0.14605)
		(layer "B.Cu")
		(net "PCIE_COMP_TO_IOM_22_DP")
	)
	(segment
		(start 80.832198 -89.999566)
		(end 78.410816 -89.999566)
		(width 0.14605)
		(layer "B.Cu")
		(net "PCIE_COMP_TO_IOM_22_DP")
	)
	(segment
		(start 83.409028 -90.612214)
		(end 81.444846 -90.612214)
		(width 0.14605)
		(layer "B.Cu")
		(net "PCIE_COMP_TO_IOM_22_DP")
	)
	(segment
		(start 99.657662 -35.368738)
		(end 97.863152 -38.028372)
		(width 0.14605)
		(layer "B.Cu")
		(net "PCIE_COMP_TO_IOM_22_DP")
	)
	(segment
		(start 81.444846 -90.612214)
		(end 80.832198 -89.999566)
		(width 0.14605)
		(layer "B.Cu")
		(net "PCIE_COMP_TO_IOM_22_DP")
	)
	(segment
		(start 84.924646 -89.096596)
		(end 83.409028 -90.612214)
		(width 0.14605)
		(layer "B.Cu")
		(net "PCIE_COMP_TO_IOM_22_DP")
	)
	(segment
		(start 96.647 -44.280328)
		(end 98.245168 -52.25288)
		(width 0.14605)
		(layer "B.Cu")
		(net "PCIE_COMP_TO_IOM_22_DP")
	)
	(segment
		(start 107.593892 -30.949392)
		(end 106.781346 -30.949392)
		(width 0.14605)
		(layer "B.Cu")
		(net "PCIE_COMP_TO_IOM_22_DP")
	)
	(segment
		(start 108.155486 -32.253682)
		(end 108.155486 -31.510986)
		(width 0.14605)
		(layer "B.Cu")
		(net "PCIE_COMP_TO_IOM_22_DP")
	)
	(segment
		(start 97.863152 -38.028372)
		(end 96.647 -44.280328)
		(width 0.14605)
		(layer "B.Cu")
		(net "PCIE_COMP_TO_IOM_22_DP")
	)
	(segment
		(start 98.245168 -52.25288)
		(end 92.729558 -79.828136)
		(width 0.14605)
		(layer "B.Cu")
		(net "PCIE_COMP_TO_IOM_22_DP")
	)
	(segment
		(start 92.729558 -79.828136)
		(end 87.190072 -88.137746)
		(width 0.14605)
		(layer "B.Cu")
		(net "PCIE_COMP_TO_IOM_22_DP")
	)
	(segment
		(start 108.674154 -32.544258)
		(end 108.446062 -32.544258)
		(width 0.14605)
		(layer "B.Cu")
		(net "PCIE_COMP_TO_IOM_22_DP")
	)
	(segment
		(start 106.105452 -31.083758)
		(end 99.657662 -35.368738)
		(width 0.14605)
		(layer "B.Cu")
		(net "PCIE_COMP_TO_IOM_22_DP")
	)
	(arc
		(start 108.89996 -32.318198)
		(mid 108.882733 -32.404805)
		(end 108.833666 -32.478218)
		(width 0.14605)
		(layer "B.Cu")
		(net "PCIE_COMP_TO_IOM_22_DP")
	)
	(arc
		(start 108.446062 -32.544258)
		(mid 108.240594 -32.45915)
		(end 108.155486 -32.253682)
		(width 0.14605)
		(layer "B.Cu")
		(net "PCIE_COMP_TO_IOM_22_DP")
	)
	(arc
		(start 78.410816 -89.999566)
		(mid 78.206605 -89.914979)
		(end 78.122018 -89.710768)
		(width 0.14605)
		(layer "B.Cu")
		(net "PCIE_COMP_TO_IOM_22_DP")
	)
	(arc
		(start 108.833666 -32.478218)
		(mid 108.760481 -32.527118)
		(end 108.674154 -32.544258)
		(width 0.14605)
		(layer "B.Cu")
		(net "PCIE_COMP_TO_IOM_22_DP")
	)
	(segment
		(start 75.475084 -90.549984)
		(end 76.4159 -90.549984)
		(width 0.14605)
		(layer "F.Cu")
		(net "PCIE_COMP_TO_IOM_22_DN")
	)
	(segment
		(start 76.6572 -90.308684)
		(end 77.830934 -90.308684)
		(width 0.14605)
		(layer "F.Cu")
		(net "PCIE_COMP_TO_IOM_22_DN")
	)
	(segment
		(start 76.4159 -90.549984)
		(end 76.6572 -90.308684)
		(width 0.14605)
		(layer "F.Cu")
		(net "PCIE_COMP_TO_IOM_22_DN")
	)
	(arc
		(start 77.830934 -90.308684)
		(mid 78.036761 -90.393941)
		(end 78.122018 -90.599768)
		(width 0.14605)
		(layer "F.Cu")
		(net "PCIE_COMP_TO_IOM_22_DN")
	)
	(segment
		(start 96.9645 -44.279312)
		(end 97.751392 -48.20539)
		(width 0.14605)
		(layer "B.Cu")
		(net "PCIE_COMP_TO_IOM_22_DN")
	)
	(segment
		(start 80.703166 -90.310716)
		(end 78.41107 -90.310716)
		(width 0.14605)
		(layer "B.Cu")
		(net "PCIE_COMP_TO_IOM_22_DN")
	)
	(segment
		(start 107.46486 -31.260542)
		(end 106.81208 -31.260542)
		(width 0.14605)
		(layer "B.Cu")
		(net "PCIE_COMP_TO_IOM_22_DN")
	)
	(segment
		(start 98.156522 -38.150038)
		(end 96.9645 -44.279312)
		(width 0.14605)
		(layer "B.Cu")
		(net "PCIE_COMP_TO_IOM_22_DN")
	)
	(segment
		(start 106.22661 -31.377128)
		(end 99.881436 -35.594036)
		(width 0.14605)
		(layer "B.Cu")
		(net "PCIE_COMP_TO_IOM_22_DN")
	)
	(segment
		(start 108.89996 -33.399984)
		(end 108.89996 -33.026604)
		(width 0.14605)
		(layer "B.Cu")
		(net "PCIE_COMP_TO_IOM_22_DN")
	)
	(segment
		(start 106.81208 -31.260542)
		(end 106.22661 -31.377128)
		(width 0.14605)
		(layer "B.Cu")
		(net "PCIE_COMP_TO_IOM_22_DN")
	)
	(segment
		(start 108.72851 -32.855408)
		(end 108.446062 -32.855408)
		(width 0.14605)
		(layer "B.Cu")
		(net "PCIE_COMP_TO_IOM_22_DN")
	)
	(segment
		(start 85.053678 -89.407746)
		(end 83.53806 -90.923364)
		(width 0.14605)
		(layer "B.Cu")
		(net "PCIE_COMP_TO_IOM_22_DN")
	)
	(segment
		(start 81.315814 -90.923364)
		(end 80.703166 -90.310716)
		(width 0.14605)
		(layer "B.Cu")
		(net "PCIE_COMP_TO_IOM_22_DN")
	)
	(segment
		(start 97.751392 -48.20539)
		(end 98.562668 -52.25288)
		(width 0.14605)
		(layer "B.Cu")
		(net "PCIE_COMP_TO_IOM_22_DN")
	)
	(segment
		(start 87.432134 -88.335866)
		(end 86.360254 -89.407746)
		(width 0.14605)
		(layer "B.Cu")
		(net "PCIE_COMP_TO_IOM_22_DN")
	)
	(segment
		(start 83.53806 -90.923364)
		(end 81.315814 -90.923364)
		(width 0.14605)
		(layer "B.Cu")
		(net "PCIE_COMP_TO_IOM_22_DN")
	)
	(segment
		(start 93.022674 -79.949548)
		(end 87.432134 -88.335866)
		(width 0.14605)
		(layer "B.Cu")
		(net "PCIE_COMP_TO_IOM_22_DN")
	)
	(segment
		(start 86.360254 -89.407746)
		(end 85.053678 -89.407746)
		(width 0.14605)
		(layer "B.Cu")
		(net "PCIE_COMP_TO_IOM_22_DN")
	)
	(segment
		(start 99.881436 -35.594036)
		(end 98.156522 -38.150038)
		(width 0.14605)
		(layer "B.Cu")
		(net "PCIE_COMP_TO_IOM_22_DN")
	)
	(segment
		(start 107.844336 -31.640018)
		(end 107.46486 -31.260542)
		(width 0.14605)
		(layer "B.Cu")
		(net "PCIE_COMP_TO_IOM_22_DN")
	)
	(segment
		(start 107.844336 -32.253682)
		(end 107.844336 -31.640018)
		(width 0.14605)
		(layer "B.Cu")
		(net "PCIE_COMP_TO_IOM_22_DN")
	)
	(segment
		(start 98.562668 -52.25288)
		(end 93.022674 -79.949548)
		(width 0.14605)
		(layer "B.Cu")
		(net "PCIE_COMP_TO_IOM_22_DN")
	)
	(arc
		(start 108.89996 -33.026604)
		(mid 108.886963 -32.961173)
		(end 108.849922 -32.9057)
		(width 0.14605)
		(layer "B.Cu")
		(net "PCIE_COMP_TO_IOM_22_DN")
	)
	(arc
		(start 108.446062 -32.855408)
		(mid 108.020577 -32.679167)
		(end 107.844336 -32.253682)
		(width 0.14605)
		(layer "B.Cu")
		(net "PCIE_COMP_TO_IOM_22_DN")
	)
	(arc
		(start 108.849922 -32.9057)
		(mid 108.794218 -32.86848)
		(end 108.72851 -32.855408)
		(width 0.14605)
		(layer "B.Cu")
		(net "PCIE_COMP_TO_IOM_22_DN")
	)
	(arc
		(start 78.41107 -90.310716)
		(mid 78.206679 -90.395377)
		(end 78.122018 -90.599768)
		(width 0.14605)
		(layer "B.Cu")
		(net "PCIE_COMP_TO_IOM_22_DN")
	)
	(segment
		(start 75.475084 -86.549992)
		(end 76.281788 -86.549992)
		(width 0.14605)
		(layer "F.Cu")
		(net "PCIE_COMP_TO_IOM_21_DP")
	)
	(segment
		(start 76.281788 -86.549992)
		(end 76.529438 -86.797642)
		(width 0.14605)
		(layer "F.Cu")
		(net "PCIE_COMP_TO_IOM_21_DP")
	)
	(segment
		(start 76.529438 -86.797642)
		(end 76.996544 -86.797642)
		(width 0.14605)
		(layer "F.Cu")
		(net "PCIE_COMP_TO_IOM_21_DP")
	)
	(arc
		(start 76.996544 -86.797642)
		(mid 77.199677 -86.713501)
		(end 77.283818 -86.510368)
		(width 0.14605)
		(layer "F.Cu")
		(net "PCIE_COMP_TO_IOM_21_DP")
	)
	(segment
		(start 98.71964 -34.591244)
		(end 96.758506 -37.498528)
		(width 0.14605)
		(layer "B.Cu")
		(net "PCIE_COMP_TO_IOM_21_DP")
	)
	(segment
		(start 95.429324 -44.147994)
		(end 96.858074 -51.28895)
		(width 0.14605)
		(layer "B.Cu")
		(net "PCIE_COMP_TO_IOM_21_DP")
	)
	(segment
		(start 87.13216 -85.99424)
		(end 85.757004 -87.369396)
		(width 0.14605)
		(layer "B.Cu")
		(net "PCIE_COMP_TO_IOM_21_DP")
	)
	(segment
		(start 91.079828 -80.180688)
		(end 87.13216 -85.99424)
		(width 0.14605)
		(layer "B.Cu")
		(net "PCIE_COMP_TO_IOM_21_DP")
	)
	(segment
		(start 83.567778 -86.0679)
		(end 81.298542 -86.0679)
		(width 0.14605)
		(layer "B.Cu")
		(net "PCIE_COMP_TO_IOM_21_DP")
	)
	(segment
		(start 81.298542 -86.0679)
		(end 80.567276 -86.799166)
		(width 0.14605)
		(layer "B.Cu")
		(net "PCIE_COMP_TO_IOM_21_DP")
	)
	(segment
		(start 109.249464 -29.784294)
		(end 105.969562 -29.784294)
		(width 0.14605)
		(layer "B.Cu")
		(net "PCIE_COMP_TO_IOM_21_DP")
	)
	(segment
		(start 110.700058 -33.200086)
		(end 110.700058 -33.518348)
		(width 0.14605)
		(layer "B.Cu")
		(net "PCIE_COMP_TO_IOM_21_DP")
	)
	(segment
		(start 85.757004 -87.369396)
		(end 84.869274 -87.369396)
		(width 0.14605)
		(layer "B.Cu")
		(net "PCIE_COMP_TO_IOM_21_DP")
	)
	(segment
		(start 96.858074 -51.28895)
		(end 91.079828 -80.180688)
		(width 0.14605)
		(layer "B.Cu")
		(net "PCIE_COMP_TO_IOM_21_DP")
	)
	(segment
		(start 109.955584 -30.490414)
		(end 109.249464 -29.784294)
		(width 0.14605)
		(layer "B.Cu")
		(net "PCIE_COMP_TO_IOM_21_DP")
	)
	(segment
		(start 84.869274 -87.369396)
		(end 83.567778 -86.0679)
		(width 0.14605)
		(layer "B.Cu")
		(net "PCIE_COMP_TO_IOM_21_DP")
	)
	(segment
		(start 105.969562 -29.784294)
		(end 98.71964 -34.591244)
		(width 0.14605)
		(layer "B.Cu")
		(net "PCIE_COMP_TO_IOM_21_DP")
	)
	(segment
		(start 110.474252 -33.744408)
		(end 110.24616 -33.744408)
		(width 0.14605)
		(layer "B.Cu")
		(net "PCIE_COMP_TO_IOM_21_DP")
	)
	(segment
		(start 96.758506 -37.498528)
		(end 95.429324 -44.147994)
		(width 0.14605)
		(layer "B.Cu")
		(net "PCIE_COMP_TO_IOM_21_DP")
	)
	(segment
		(start 109.955584 -33.453832)
		(end 109.955584 -30.490414)
		(width 0.14605)
		(layer "B.Cu")
		(net "PCIE_COMP_TO_IOM_21_DP")
	)
	(segment
		(start 80.567276 -86.799166)
		(end 77.572616 -86.799166)
		(width 0.14605)
		(layer "B.Cu")
		(net "PCIE_COMP_TO_IOM_21_DP")
	)
	(arc
		(start 110.24616 -33.744408)
		(mid 110.040692 -33.6593)
		(end 109.955584 -33.453832)
		(width 0.14605)
		(layer "B.Cu")
		(net "PCIE_COMP_TO_IOM_21_DP")
	)
	(arc
		(start 77.572616 -86.799166)
		(mid 77.368405 -86.714579)
		(end 77.283818 -86.510368)
		(width 0.14605)
		(layer "B.Cu")
		(net "PCIE_COMP_TO_IOM_21_DP")
	)
	(arc
		(start 110.633764 -33.678368)
		(mid 110.560579 -33.727268)
		(end 110.474252 -33.744408)
		(width 0.14605)
		(layer "B.Cu")
		(net "PCIE_COMP_TO_IOM_21_DP")
	)
	(arc
		(start 110.700058 -33.518348)
		(mid 110.682831 -33.604955)
		(end 110.633764 -33.678368)
		(width 0.14605)
		(layer "B.Cu")
		(net "PCIE_COMP_TO_IOM_21_DP")
	)
	(segment
		(start 76.607924 -87.108792)
		(end 76.993242 -87.108792)
		(width 0.14605)
		(layer "F.Cu")
		(net "PCIE_COMP_TO_IOM_21_DN")
	)
	(segment
		(start 76.366624 -87.350092)
		(end 76.607924 -87.108792)
		(width 0.14605)
		(layer "F.Cu")
		(net "PCIE_COMP_TO_IOM_21_DN")
	)
	(segment
		(start 75.475084 -87.350092)
		(end 76.366624 -87.350092)
		(width 0.14605)
		(layer "F.Cu")
		(net "PCIE_COMP_TO_IOM_21_DN")
	)
	(arc
		(start 76.993242 -87.108792)
		(mid 77.19871 -87.1939)
		(end 77.283818 -87.399368)
		(width 0.14605)
		(layer "F.Cu")
		(net "PCIE_COMP_TO_IOM_21_DN")
	)
	(segment
		(start 106.063542 -30.095444)
		(end 98.94316 -34.816542)
		(width 0.14605)
		(layer "B.Cu")
		(net "PCIE_COMP_TO_IOM_21_DN")
	)
	(segment
		(start 109.120432 -30.095444)
		(end 106.063542 -30.095444)
		(width 0.14605)
		(layer "B.Cu")
		(net "PCIE_COMP_TO_IOM_21_DN")
	)
	(segment
		(start 83.438746 -86.37905)
		(end 81.427574 -86.37905)
		(width 0.14605)
		(layer "B.Cu")
		(net "PCIE_COMP_TO_IOM_21_DN")
	)
	(segment
		(start 110.700058 -34.600134)
		(end 110.700058 -34.226754)
		(width 0.14605)
		(layer "B.Cu")
		(net "PCIE_COMP_TO_IOM_21_DN")
	)
	(segment
		(start 95.746824 -44.147994)
		(end 97.175574 -51.28895)
		(width 0.14605)
		(layer "B.Cu")
		(net "PCIE_COMP_TO_IOM_21_DN")
	)
	(segment
		(start 84.740242 -87.680546)
		(end 83.438746 -86.37905)
		(width 0.14605)
		(layer "B.Cu")
		(net "PCIE_COMP_TO_IOM_21_DN")
	)
	(segment
		(start 91.37269 -80.30337)
		(end 87.37346 -86.193122)
		(width 0.14605)
		(layer "B.Cu")
		(net "PCIE_COMP_TO_IOM_21_DN")
	)
	(segment
		(start 87.37346 -86.193122)
		(end 85.886036 -87.680546)
		(width 0.14605)
		(layer "B.Cu")
		(net "PCIE_COMP_TO_IOM_21_DN")
	)
	(segment
		(start 109.644434 -33.453832)
		(end 109.644434 -30.619446)
		(width 0.14605)
		(layer "B.Cu")
		(net "PCIE_COMP_TO_IOM_21_DN")
	)
	(segment
		(start 80.696308 -87.110316)
		(end 77.57287 -87.110316)
		(width 0.14605)
		(layer "B.Cu")
		(net "PCIE_COMP_TO_IOM_21_DN")
	)
	(segment
		(start 110.528608 -34.055558)
		(end 110.24616 -34.055558)
		(width 0.14605)
		(layer "B.Cu")
		(net "PCIE_COMP_TO_IOM_21_DN")
	)
	(segment
		(start 98.94316 -34.816542)
		(end 97.051622 -37.620956)
		(width 0.14605)
		(layer "B.Cu")
		(net "PCIE_COMP_TO_IOM_21_DN")
	)
	(segment
		(start 97.175574 -51.28895)
		(end 91.37269 -80.30337)
		(width 0.14605)
		(layer "B.Cu")
		(net "PCIE_COMP_TO_IOM_21_DN")
	)
	(segment
		(start 81.427574 -86.37905)
		(end 80.696308 -87.110316)
		(width 0.14605)
		(layer "B.Cu")
		(net "PCIE_COMP_TO_IOM_21_DN")
	)
	(segment
		(start 97.051622 -37.620956)
		(end 95.746824 -44.147994)
		(width 0.14605)
		(layer "B.Cu")
		(net "PCIE_COMP_TO_IOM_21_DN")
	)
	(segment
		(start 109.644434 -30.619446)
		(end 109.120432 -30.095444)
		(width 0.14605)
		(layer "B.Cu")
		(net "PCIE_COMP_TO_IOM_21_DN")
	)
	(segment
		(start 85.886036 -87.680546)
		(end 84.740242 -87.680546)
		(width 0.14605)
		(layer "B.Cu")
		(net "PCIE_COMP_TO_IOM_21_DN")
	)
	(arc
		(start 77.57287 -87.110316)
		(mid 77.368479 -87.194977)
		(end 77.283818 -87.399368)
		(width 0.14605)
		(layer "B.Cu")
		(net "PCIE_COMP_TO_IOM_21_DN")
	)
	(arc
		(start 110.65002 -34.10585)
		(mid 110.594316 -34.06863)
		(end 110.528608 -34.055558)
		(width 0.14605)
		(layer "B.Cu")
		(net "PCIE_COMP_TO_IOM_21_DN")
	)
	(arc
		(start 110.700058 -34.226754)
		(mid 110.687061 -34.161323)
		(end 110.65002 -34.10585)
		(width 0.14605)
		(layer "B.Cu")
		(net "PCIE_COMP_TO_IOM_21_DN")
	)
	(arc
		(start 110.24616 -34.055558)
		(mid 109.820675 -33.879317)
		(end 109.644434 -33.453832)
		(width 0.14605)
		(layer "B.Cu")
		(net "PCIE_COMP_TO_IOM_21_DN")
	)
	(segment
		(start 76.614528 -83.622896)
		(end 77.846428 -83.622896)
		(width 0.14605)
		(layer "F.Cu")
		(net "PCIE_COMP_TO_IOM_20_DP")
	)
	(segment
		(start 75.475084 -83.3501)
		(end 76.341732 -83.3501)
		(width 0.14605)
		(layer "F.Cu")
		(net "PCIE_COMP_TO_IOM_20_DP")
	)
	(segment
		(start 78.122018 -83.347306)
		(end 78.122018 -83.335368)
		(width 0.14605)
		(layer "F.Cu")
		(net "PCIE_COMP_TO_IOM_20_DP")
	)
	(segment
		(start 76.341732 -83.3501)
		(end 76.614528 -83.622896)
		(width 0.14605)
		(layer "F.Cu")
		(net "PCIE_COMP_TO_IOM_20_DP")
	)
	(arc
		(start 77.846428 -83.622896)
		(mid 78.0413 -83.542178)
		(end 78.122018 -83.347306)
		(width 0.14605)
		(layer "F.Cu")
		(net "PCIE_COMP_TO_IOM_20_DP")
	)
	(segment
		(start 95.678752 -51.295554)
		(end 90.072972 -79.319628)
		(width 0.14605)
		(layer "B.Cu")
		(net "PCIE_COMP_TO_IOM_20_DP")
	)
	(segment
		(start 81.62417 -84.492338)
		(end 81.135982 -84.003642)
		(width 0.14605)
		(layer "B.Cu")
		(net "PCIE_COMP_TO_IOM_20_DP")
	)
	(segment
		(start 105.454958 -28.641294)
		(end 97.623376 -33.862518)
		(width 0.14605)
		(layer "B.Cu")
		(net "PCIE_COMP_TO_IOM_20_DP")
	)
	(segment
		(start 80.756252 -83.624166)
		(end 78.410816 -83.624166)
		(width 0.14605)
		(layer "B.Cu")
		(net "PCIE_COMP_TO_IOM_20_DP")
	)
	(segment
		(start 84.747862 -82.937858)
		(end 83.193382 -84.492338)
		(width 0.14605)
		(layer "B.Cu")
		(net "PCIE_COMP_TO_IOM_20_DP")
	)
	(segment
		(start 111.755428 -30.673294)
		(end 109.723428 -28.641294)
		(width 0.14605)
		(layer "B.Cu")
		(net "PCIE_COMP_TO_IOM_20_DP")
	)
	(segment
		(start 95.694754 -36.758118)
		(end 94.230698 -44.06646)
		(width 0.14605)
		(layer "B.Cu")
		(net "PCIE_COMP_TO_IOM_20_DP")
	)
	(segment
		(start 97.623376 -33.862518)
		(end 95.694754 -36.758118)
		(width 0.14605)
		(layer "B.Cu")
		(net "PCIE_COMP_TO_IOM_20_DP")
	)
	(segment
		(start 83.193382 -84.492338)
		(end 81.62417 -84.492338)
		(width 0.14605)
		(layer "B.Cu")
		(net "PCIE_COMP_TO_IOM_20_DP")
	)
	(segment
		(start 90.072972 -79.319628)
		(end 86.454742 -82.937858)
		(width 0.14605)
		(layer "B.Cu")
		(net "PCIE_COMP_TO_IOM_20_DP")
	)
	(segment
		(start 81.135982 -84.003642)
		(end 80.756252 -83.624166)
		(width 0.14605)
		(layer "B.Cu")
		(net "PCIE_COMP_TO_IOM_20_DP")
	)
	(segment
		(start 112.499902 -32.00019)
		(end 112.499902 -32.318198)
		(width 0.14605)
		(layer "B.Cu")
		(net "PCIE_COMP_TO_IOM_20_DP")
	)
	(segment
		(start 86.454742 -82.937858)
		(end 84.747862 -82.937858)
		(width 0.14605)
		(layer "B.Cu")
		(net "PCIE_COMP_TO_IOM_20_DP")
	)
	(segment
		(start 109.723428 -28.641294)
		(end 105.454958 -28.641294)
		(width 0.14605)
		(layer "B.Cu")
		(net "PCIE_COMP_TO_IOM_20_DP")
	)
	(segment
		(start 111.755428 -32.253682)
		(end 111.755428 -30.673294)
		(width 0.14605)
		(layer "B.Cu")
		(net "PCIE_COMP_TO_IOM_20_DP")
	)
	(segment
		(start 112.274096 -32.544258)
		(end 112.046004 -32.544258)
		(width 0.14605)
		(layer "B.Cu")
		(net "PCIE_COMP_TO_IOM_20_DP")
	)
	(segment
		(start 94.230698 -44.06646)
		(end 95.678752 -51.295554)
		(width 0.14605)
		(layer "B.Cu")
		(net "PCIE_COMP_TO_IOM_20_DP")
	)
	(arc
		(start 112.499902 -32.318198)
		(mid 112.482675 -32.404805)
		(end 112.433608 -32.478218)
		(width 0.14605)
		(layer "B.Cu")
		(net "PCIE_COMP_TO_IOM_20_DP")
	)
	(arc
		(start 112.046004 -32.544258)
		(mid 111.840536 -32.45915)
		(end 111.755428 -32.253682)
		(width 0.14605)
		(layer "B.Cu")
		(net "PCIE_COMP_TO_IOM_20_DP")
	)
	(arc
		(start 112.433608 -32.478218)
		(mid 112.360423 -32.527118)
		(end 112.274096 -32.544258)
		(width 0.14605)
		(layer "B.Cu")
		(net "PCIE_COMP_TO_IOM_20_DP")
	)
	(arc
		(start 78.410816 -83.624166)
		(mid 78.206605 -83.539579)
		(end 78.122018 -83.335368)
		(width 0.14605)
		(layer "B.Cu")
		(net "PCIE_COMP_TO_IOM_20_DP")
	)
	(segment
		(start 76.690474 -83.934046)
		(end 77.846428 -83.934046)
		(width 0.14605)
		(layer "F.Cu")
		(net "PCIE_COMP_TO_IOM_20_DN")
	)
	(segment
		(start 76.474574 -84.149946)
		(end 76.690474 -83.934046)
		(width 0.14605)
		(layer "F.Cu")
		(net "PCIE_COMP_TO_IOM_20_DN")
	)
	(segment
		(start 78.122018 -84.209636)
		(end 78.122018 -84.224368)
		(width 0.14605)
		(layer "F.Cu")
		(net "PCIE_COMP_TO_IOM_20_DN")
	)
	(segment
		(start 75.475084 -84.149946)
		(end 76.474574 -84.149946)
		(width 0.14605)
		(layer "F.Cu")
		(net "PCIE_COMP_TO_IOM_20_DN")
	)
	(arc
		(start 77.846428 -83.934046)
		(mid 78.0413 -84.014764)
		(end 78.122018 -84.209636)
		(width 0.14605)
		(layer "F.Cu")
		(net "PCIE_COMP_TO_IOM_20_DN")
	)
	(segment
		(start 111.444278 -32.253682)
		(end 111.444278 -30.802326)
		(width 0.14605)
		(layer "B.Cu")
		(net "PCIE_COMP_TO_IOM_20_DN")
	)
	(segment
		(start 105.549192 -28.952444)
		(end 97.847912 -34.0868)
		(width 0.14605)
		(layer "B.Cu")
		(net "PCIE_COMP_TO_IOM_20_DN")
	)
	(segment
		(start 94.548198 -44.06646)
		(end 95.996252 -51.295554)
		(width 0.14605)
		(layer "B.Cu")
		(net "PCIE_COMP_TO_IOM_20_DN")
	)
	(segment
		(start 109.594396 -28.952444)
		(end 105.549192 -28.952444)
		(width 0.14605)
		(layer "B.Cu")
		(net "PCIE_COMP_TO_IOM_20_DN")
	)
	(segment
		(start 97.847912 -34.0868)
		(end 95.98787 -36.87953)
		(width 0.14605)
		(layer "B.Cu")
		(net "PCIE_COMP_TO_IOM_20_DN")
	)
	(segment
		(start 112.328452 -32.855408)
		(end 112.046004 -32.855408)
		(width 0.14605)
		(layer "B.Cu")
		(net "PCIE_COMP_TO_IOM_20_DN")
	)
	(segment
		(start 86.583774 -83.249008)
		(end 84.876894 -83.249008)
		(width 0.14605)
		(layer "B.Cu")
		(net "PCIE_COMP_TO_IOM_20_DN")
	)
	(segment
		(start 80.62722 -83.935316)
		(end 78.41107 -83.935316)
		(width 0.14605)
		(layer "B.Cu")
		(net "PCIE_COMP_TO_IOM_20_DN")
	)
	(segment
		(start 90.359738 -79.473044)
		(end 86.583774 -83.249008)
		(width 0.14605)
		(layer "B.Cu")
		(net "PCIE_COMP_TO_IOM_20_DN")
	)
	(segment
		(start 84.876894 -83.249008)
		(end 83.322414 -84.803488)
		(width 0.14605)
		(layer "B.Cu")
		(net "PCIE_COMP_TO_IOM_20_DN")
	)
	(segment
		(start 80.915764 -84.22386)
		(end 80.62722 -83.935316)
		(width 0.14605)
		(layer "B.Cu")
		(net "PCIE_COMP_TO_IOM_20_DN")
	)
	(segment
		(start 95.98787 -36.87953)
		(end 94.548198 -44.06646)
		(width 0.14605)
		(layer "B.Cu")
		(net "PCIE_COMP_TO_IOM_20_DN")
	)
	(segment
		(start 112.499902 -33.399984)
		(end 112.499902 -33.026604)
		(width 0.14605)
		(layer "B.Cu")
		(net "PCIE_COMP_TO_IOM_20_DN")
	)
	(segment
		(start 95.996252 -51.295554)
		(end 90.359738 -79.473044)
		(width 0.14605)
		(layer "B.Cu")
		(net "PCIE_COMP_TO_IOM_20_DN")
	)
	(segment
		(start 111.444278 -30.802326)
		(end 109.594396 -28.952444)
		(width 0.14605)
		(layer "B.Cu")
		(net "PCIE_COMP_TO_IOM_20_DN")
	)
	(segment
		(start 81.495138 -84.803488)
		(end 80.915764 -84.22386)
		(width 0.14605)
		(layer "B.Cu")
		(net "PCIE_COMP_TO_IOM_20_DN")
	)
	(segment
		(start 83.322414 -84.803488)
		(end 81.495138 -84.803488)
		(width 0.14605)
		(layer "B.Cu")
		(net "PCIE_COMP_TO_IOM_20_DN")
	)
	(arc
		(start 78.41107 -83.935316)
		(mid 78.206679 -84.019977)
		(end 78.122018 -84.224368)
		(width 0.14605)
		(layer "B.Cu")
		(net "PCIE_COMP_TO_IOM_20_DN")
	)
	(arc
		(start 112.449864 -32.9057)
		(mid 112.39416 -32.86848)
		(end 112.328452 -32.855408)
		(width 0.14605)
		(layer "B.Cu")
		(net "PCIE_COMP_TO_IOM_20_DN")
	)
	(arc
		(start 112.499902 -33.026604)
		(mid 112.486905 -32.961173)
		(end 112.449864 -32.9057)
		(width 0.14605)
		(layer "B.Cu")
		(net "PCIE_COMP_TO_IOM_20_DN")
	)
	(arc
		(start 112.046004 -32.855408)
		(mid 111.620519 -32.679167)
		(end 111.444278 -32.253682)
		(width 0.14605)
		(layer "B.Cu")
		(net "PCIE_COMP_TO_IOM_20_DN")
	)
	(segment
		(start 76.589128 -80.397604)
		(end 76.995782 -80.397604)
		(width 0.14605)
		(layer "F.Cu")
		(net "PCIE_COMP_TO_IOM_19_DP")
	)
	(segment
		(start 75.475084 -80.149954)
		(end 76.341478 -80.149954)
		(width 0.14605)
		(layer "F.Cu")
		(net "PCIE_COMP_TO_IOM_19_DP")
	)
	(segment
		(start 76.341478 -80.149954)
		(end 76.589128 -80.397604)
		(width 0.14605)
		(layer "F.Cu")
		(net "PCIE_COMP_TO_IOM_19_DP")
	)
	(arc
		(start 76.995782 -80.397604)
		(mid 77.199454 -80.31324)
		(end 77.283818 -80.109568)
		(width 0.14605)
		(layer "F.Cu")
		(net "PCIE_COMP_TO_IOM_19_DP")
	)
	(segment
		(start 93.737684 -49.814988)
		(end 93.317568 -51.911758)
		(width 0.14605)
		(layer "B.Cu")
		(net "PCIE_COMP_TO_IOM_19_DP")
	)
	(segment
		(start 93.768164 -37.188648)
		(end 92.489528 -43.577764)
		(width 0.14605)
		(layer "B.Cu")
		(net "PCIE_COMP_TO_IOM_19_DP")
	)
	(segment
		(start 114.3 -33.200086)
		(end 114.3 -33.518348)
		(width 0.14605)
		(layer "B.Cu")
		(net "PCIE_COMP_TO_IOM_19_DP")
	)
	(segment
		(start 113.555526 -33.453832)
		(end 113.555526 -30.211776)
		(width 0.14605)
		(layer "B.Cu")
		(net "PCIE_COMP_TO_IOM_19_DP")
	)
	(segment
		(start 92.50172 -43.638724)
		(end 93.119702 -46.72711)
		(width 0.14605)
		(layer "B.Cu")
		(net "PCIE_COMP_TO_IOM_19_DP")
	)
	(segment
		(start 114.074194 -33.744408)
		(end 113.846102 -33.744408)
		(width 0.14605)
		(layer "B.Cu")
		(net "PCIE_COMP_TO_IOM_19_DP")
	)
	(segment
		(start 110.842044 -27.498294)
		(end 104.847644 -27.498294)
		(width 0.14605)
		(layer "B.Cu")
		(net "PCIE_COMP_TO_IOM_19_DP")
	)
	(segment
		(start 96.513142 -33.090358)
		(end 96.513396 -33.090358)
		(width 0.14605)
		(layer "B.Cu")
		(net "PCIE_COMP_TO_IOM_19_DP")
	)
	(segment
		(start 93.317568 -51.911758)
		(end 93.847412 -54.574948)
		(width 0.14605)
		(layer "B.Cu")
		(net "PCIE_COMP_TO_IOM_19_DP")
	)
	(segment
		(start 104.847644 -27.498294)
		(end 96.547686 -33.038796)
		(width 0.14605)
		(layer "B.Cu")
		(net "PCIE_COMP_TO_IOM_19_DP")
	)
	(segment
		(start 77.283818 -80.191356)
		(end 77.283818 -80.109568)
		(width 0.14605)
		(layer "B.Cu")
		(net "PCIE_COMP_TO_IOM_19_DP")
	)
	(segment
		(start 92.489528 -43.577764)
		(end 92.50172 -43.638724)
		(width 0.14605)
		(layer "B.Cu")
		(net "PCIE_COMP_TO_IOM_19_DP")
	)
	(segment
		(start 96.513396 -33.090358)
		(end 95.158052 -35.113976)
		(width 0.14605)
		(layer "B.Cu")
		(net "PCIE_COMP_TO_IOM_19_DP")
	)
	(segment
		(start 86.615524 -80.872076)
		(end 84.729574 -80.872076)
		(width 0.14605)
		(layer "B.Cu")
		(net "PCIE_COMP_TO_IOM_19_DP")
	)
	(segment
		(start 113.555526 -30.211776)
		(end 110.842044 -27.498294)
		(width 0.14605)
		(layer "B.Cu")
		(net "PCIE_COMP_TO_IOM_19_DP")
	)
	(segment
		(start 80.567276 -80.398366)
		(end 77.490828 -80.398366)
		(width 0.14605)
		(layer "B.Cu")
		(net "PCIE_COMP_TO_IOM_19_DP")
	)
	(segment
		(start 95.158052 -35.113976)
		(end 93.768164 -37.188648)
		(width 0.14605)
		(layer "B.Cu")
		(net "PCIE_COMP_TO_IOM_19_DP")
	)
	(segment
		(start 93.119702 -46.72711)
		(end 93.737684 -49.814988)
		(width 0.14605)
		(layer "B.Cu")
		(net "PCIE_COMP_TO_IOM_19_DP")
	)
	(segment
		(start 96.547686 -33.038796)
		(end 96.513142 -33.090358)
		(width 0.14605)
		(layer "B.Cu")
		(net "PCIE_COMP_TO_IOM_19_DP")
	)
	(segment
		(start 81.329276 -79.636366)
		(end 80.567276 -80.398366)
		(width 0.14605)
		(layer "B.Cu")
		(net "PCIE_COMP_TO_IOM_19_DP")
	)
	(segment
		(start 83.493864 -79.636366)
		(end 81.329276 -79.636366)
		(width 0.14605)
		(layer "B.Cu")
		(net "PCIE_COMP_TO_IOM_19_DP")
	)
	(segment
		(start 93.847412 -54.574948)
		(end 89.080086 -78.407514)
		(width 0.14605)
		(layer "B.Cu")
		(net "PCIE_COMP_TO_IOM_19_DP")
	)
	(segment
		(start 89.080086 -78.407514)
		(end 86.615524 -80.872076)
		(width 0.14605)
		(layer "B.Cu")
		(net "PCIE_COMP_TO_IOM_19_DP")
	)
	(segment
		(start 84.729574 -80.872076)
		(end 83.493864 -79.636366)
		(width 0.14605)
		(layer "B.Cu")
		(net "PCIE_COMP_TO_IOM_19_DP")
	)
	(arc
		(start 114.3 -33.518348)
		(mid 114.282773 -33.604955)
		(end 114.233706 -33.678368)
		(width 0.14605)
		(layer "B.Cu")
		(net "PCIE_COMP_TO_IOM_19_DP")
	)
	(arc
		(start 77.490828 -80.398366)
		(mid 77.34445 -80.337734)
		(end 77.283818 -80.191356)
		(width 0.14605)
		(layer "B.Cu")
		(net "PCIE_COMP_TO_IOM_19_DP")
	)
	(arc
		(start 114.233706 -33.678368)
		(mid 114.160521 -33.727268)
		(end 114.074194 -33.744408)
		(width 0.14605)
		(layer "B.Cu")
		(net "PCIE_COMP_TO_IOM_19_DP")
	)
	(arc
		(start 113.846102 -33.744408)
		(mid 113.640634 -33.6593)
		(end 113.555526 -33.453832)
		(width 0.14605)
		(layer "B.Cu")
		(net "PCIE_COMP_TO_IOM_19_DP")
	)
	(segment
		(start 76.627228 -80.708754)
		(end 76.994004 -80.708754)
		(width 0.14605)
		(layer "F.Cu")
		(net "PCIE_COMP_TO_IOM_19_DN")
	)
	(segment
		(start 75.475084 -80.950054)
		(end 76.385928 -80.950054)
		(width 0.14605)
		(layer "F.Cu")
		(net "PCIE_COMP_TO_IOM_19_DN")
	)
	(segment
		(start 76.385928 -80.950054)
		(end 76.627228 -80.708754)
		(width 0.14605)
		(layer "F.Cu")
		(net "PCIE_COMP_TO_IOM_19_DN")
	)
	(arc
		(start 76.994004 -80.708754)
		(mid 77.198933 -80.793639)
		(end 77.283818 -80.998568)
		(width 0.14605)
		(layer "F.Cu")
		(net "PCIE_COMP_TO_IOM_19_DN")
	)
	(segment
		(start 89.366852 -78.56093)
		(end 86.744556 -81.183226)
		(width 0.14605)
		(layer "B.Cu")
		(net "PCIE_COMP_TO_IOM_19_DN")
	)
	(segment
		(start 114.3 -34.600134)
		(end 114.3 -34.226754)
		(width 0.14605)
		(layer "B.Cu")
		(net "PCIE_COMP_TO_IOM_19_DN")
	)
	(segment
		(start 81.458308 -79.947516)
		(end 80.696308 -80.709516)
		(width 0.14605)
		(layer "B.Cu")
		(net "PCIE_COMP_TO_IOM_19_DN")
	)
	(segment
		(start 113.244376 -30.340808)
		(end 110.713012 -27.809444)
		(width 0.14605)
		(layer "B.Cu")
		(net "PCIE_COMP_TO_IOM_19_DN")
	)
	(segment
		(start 94.164912 -54.575202)
		(end 89.366852 -78.56093)
		(width 0.14605)
		(layer "B.Cu")
		(net "PCIE_COMP_TO_IOM_19_DN")
	)
	(segment
		(start 94.06128 -37.310568)
		(end 92.807028 -43.577764)
		(width 0.14605)
		(layer "B.Cu")
		(net "PCIE_COMP_TO_IOM_19_DN")
	)
	(segment
		(start 110.713012 -27.809444)
		(end 104.942132 -27.809444)
		(width 0.14605)
		(layer "B.Cu")
		(net "PCIE_COMP_TO_IOM_19_DN")
	)
	(segment
		(start 84.600542 -81.183226)
		(end 83.364832 -79.947516)
		(width 0.14605)
		(layer "B.Cu")
		(net "PCIE_COMP_TO_IOM_19_DN")
	)
	(segment
		(start 94.055184 -49.814988)
		(end 93.635068 -51.912012)
		(width 0.14605)
		(layer "B.Cu")
		(net "PCIE_COMP_TO_IOM_19_DN")
	)
	(segment
		(start 113.244376 -33.453832)
		(end 113.244376 -30.340808)
		(width 0.14605)
		(layer "B.Cu")
		(net "PCIE_COMP_TO_IOM_19_DN")
	)
	(segment
		(start 83.364832 -79.947516)
		(end 81.458308 -79.947516)
		(width 0.14605)
		(layer "B.Cu")
		(net "PCIE_COMP_TO_IOM_19_DN")
	)
	(segment
		(start 114.12855 -34.055558)
		(end 113.846102 -34.055558)
		(width 0.14605)
		(layer "B.Cu")
		(net "PCIE_COMP_TO_IOM_19_DN")
	)
	(segment
		(start 92.807028 -43.577764)
		(end 94.055184 -49.814988)
		(width 0.14605)
		(layer "B.Cu")
		(net "PCIE_COMP_TO_IOM_19_DN")
	)
	(segment
		(start 96.771968 -33.263586)
		(end 94.06128 -37.310568)
		(width 0.14605)
		(layer "B.Cu")
		(net "PCIE_COMP_TO_IOM_19_DN")
	)
	(segment
		(start 93.635068 -51.912012)
		(end 94.164912 -54.575202)
		(width 0.14605)
		(layer "B.Cu")
		(net "PCIE_COMP_TO_IOM_19_DN")
	)
	(segment
		(start 104.942132 -27.809444)
		(end 96.771968 -33.263586)
		(width 0.14605)
		(layer "B.Cu")
		(net "PCIE_COMP_TO_IOM_19_DN")
	)
	(segment
		(start 80.696308 -80.709516)
		(end 77.490828 -80.709516)
		(width 0.14605)
		(layer "B.Cu")
		(net "PCIE_COMP_TO_IOM_19_DN")
	)
	(segment
		(start 86.744556 -81.183226)
		(end 84.600542 -81.183226)
		(width 0.14605)
		(layer "B.Cu")
		(net "PCIE_COMP_TO_IOM_19_DN")
	)
	(segment
		(start 77.283818 -80.916526)
		(end 77.283818 -80.998568)
		(width 0.14605)
		(layer "B.Cu")
		(net "PCIE_COMP_TO_IOM_19_DN")
	)
	(arc
		(start 114.249962 -34.10585)
		(mid 114.194258 -34.06863)
		(end 114.12855 -34.055558)
		(width 0.14605)
		(layer "B.Cu")
		(net "PCIE_COMP_TO_IOM_19_DN")
	)
	(arc
		(start 113.846102 -34.055558)
		(mid 113.420617 -33.879317)
		(end 113.244376 -33.453832)
		(width 0.14605)
		(layer "B.Cu")
		(net "PCIE_COMP_TO_IOM_19_DN")
	)
	(arc
		(start 77.490828 -80.709516)
		(mid 77.34445 -80.770148)
		(end 77.283818 -80.916526)
		(width 0.14605)
		(layer "B.Cu")
		(net "PCIE_COMP_TO_IOM_19_DN")
	)
	(arc
		(start 114.3 -34.226754)
		(mid 114.287003 -34.161323)
		(end 114.249962 -34.10585)
		(width 0.14605)
		(layer "B.Cu")
		(net "PCIE_COMP_TO_IOM_19_DN")
	)
	(segment
		(start 76.91247 -77.203046)
		(end 77.838046 -77.203046)
		(width 0.14605)
		(layer "F.Cu")
		(net "PCIE_COMP_TO_IOM_18_DP")
	)
	(segment
		(start 78.122018 -76.919074)
		(end 78.122018 -76.909168)
		(width 0.14605)
		(layer "F.Cu")
		(net "PCIE_COMP_TO_IOM_18_DP")
	)
	(segment
		(start 76.659486 -76.950062)
		(end 76.91247 -77.203046)
		(width 0.14605)
		(layer "F.Cu")
		(net "PCIE_COMP_TO_IOM_18_DP")
	)
	(segment
		(start 75.475084 -76.950062)
		(end 76.659486 -76.950062)
		(width 0.136652)
		(layer "F.Cu")
		(net "PCIE_COMP_TO_IOM_18_DP")
	)
	(arc
		(start 77.838046 -77.203046)
		(mid 78.038845 -77.119873)
		(end 78.122018 -76.919074)
		(width 0.14605)
		(layer "F.Cu")
		(net "PCIE_COMP_TO_IOM_18_DP")
	)
	(segment
		(start 81.564226 -77.802994)
		(end 80.959198 -77.197966)
		(width 0.14605)
		(layer "B.Cu")
		(net "PCIE_COMP_TO_IOM_18_DP")
	)
	(segment
		(start 96.063308 -31.3436)
		(end 92.792296 -36.227004)
		(width 0.14605)
		(layer "B.Cu")
		(net "PCIE_COMP_TO_IOM_18_DP")
	)
	(segment
		(start 91.261184 -44.005754)
		(end 91.845892 -46.75886)
		(width 0.14605)
		(layer "B.Cu")
		(net "PCIE_COMP_TO_IOM_18_DP")
	)
	(segment
		(start 91.845892 -46.75886)
		(end 92.145104 -48.167036)
		(width 0.14605)
		(layer "B.Cu")
		(net "PCIE_COMP_TO_IOM_18_DP")
	)
	(segment
		(start 92.792296 -36.227004)
		(end 91.247976 -43.943016)
		(width 0.14605)
		(layer "B.Cu")
		(net "PCIE_COMP_TO_IOM_18_DP")
	)
	(segment
		(start 84.553298 -76.691998)
		(end 83.442302 -77.802994)
		(width 0.14605)
		(layer "B.Cu")
		(net "PCIE_COMP_TO_IOM_18_DP")
	)
	(segment
		(start 90.54338 -63.286386)
		(end 90.757756 -64.059308)
		(width 0.14605)
		(layer "B.Cu")
		(net "PCIE_COMP_TO_IOM_18_DP")
	)
	(segment
		(start 90.399108 -62.766194)
		(end 90.54338 -63.286386)
		(width 0.14605)
		(layer "B.Cu")
		(net "PCIE_COMP_TO_IOM_18_DP")
	)
	(segment
		(start 115.35537 -30.17647)
		(end 111.534194 -26.355294)
		(width 0.14605)
		(layer "B.Cu")
		(net "PCIE_COMP_TO_IOM_18_DP")
	)
	(segment
		(start 92.444316 -49.574958)
		(end 92.035884 -51.492658)
		(width 0.14605)
		(layer "B.Cu")
		(net "PCIE_COMP_TO_IOM_18_DP")
	)
	(segment
		(start 86.909402 -76.691998)
		(end 84.553298 -76.691998)
		(width 0.14605)
		(layer "B.Cu")
		(net "PCIE_COMP_TO_IOM_18_DP")
	)
	(segment
		(start 80.959198 -77.197966)
		(end 78.410816 -77.197966)
		(width 0.14605)
		(layer "B.Cu")
		(net "PCIE_COMP_TO_IOM_18_DP")
	)
	(segment
		(start 111.534194 -26.355294)
		(end 103.458518 -26.355294)
		(width 0.14605)
		(layer "B.Cu")
		(net "PCIE_COMP_TO_IOM_18_DP")
	)
	(segment
		(start 83.442302 -77.802994)
		(end 81.564226 -77.802994)
		(width 0.14605)
		(layer "B.Cu")
		(net "PCIE_COMP_TO_IOM_18_DP")
	)
	(segment
		(start 88.561164 -75.040236)
		(end 86.909402 -76.691998)
		(width 0.14605)
		(layer "B.Cu")
		(net "PCIE_COMP_TO_IOM_18_DP")
	)
	(segment
		(start 91.247976 -43.943016)
		(end 91.261184 -44.005754)
		(width 0.14605)
		(layer "B.Cu")
		(net "PCIE_COMP_TO_IOM_18_DP")
	)
	(segment
		(start 115.874038 -32.544258)
		(end 115.645946 -32.544258)
		(width 0.14605)
		(layer "B.Cu")
		(net "PCIE_COMP_TO_IOM_18_DP")
	)
	(segment
		(start 90.072464 -61.589158)
		(end 90.399108 -62.766194)
		(width 0.14605)
		(layer "B.Cu")
		(net "PCIE_COMP_TO_IOM_18_DP")
	)
	(segment
		(start 103.458518 -26.355294)
		(end 96.063308 -31.3436)
		(width 0.14605)
		(layer "B.Cu")
		(net "PCIE_COMP_TO_IOM_18_DP")
	)
	(segment
		(start 115.35537 -32.253682)
		(end 115.35537 -30.17647)
		(width 0.14605)
		(layer "B.Cu")
		(net "PCIE_COMP_TO_IOM_18_DP")
	)
	(segment
		(start 116.099844 -32.00019)
		(end 116.099844 -32.318198)
		(width 0.14605)
		(layer "B.Cu")
		(net "PCIE_COMP_TO_IOM_18_DP")
	)
	(segment
		(start 92.125292 -51.91252)
		(end 90.072464 -61.589158)
		(width 0.14605)
		(layer "B.Cu")
		(net "PCIE_COMP_TO_IOM_18_DP")
	)
	(segment
		(start 92.035884 -51.492658)
		(end 92.125292 -51.91252)
		(width 0.14605)
		(layer "B.Cu")
		(net "PCIE_COMP_TO_IOM_18_DP")
	)
	(segment
		(start 92.145104 -48.167036)
		(end 92.145358 -48.16729)
		(width 0.14605)
		(layer "B.Cu")
		(net "PCIE_COMP_TO_IOM_18_DP")
	)
	(segment
		(start 90.757756 -64.059308)
		(end 88.561164 -75.040236)
		(width 0.14605)
		(layer "B.Cu")
		(net "PCIE_COMP_TO_IOM_18_DP")
	)
	(segment
		(start 92.145358 -48.16729)
		(end 92.444316 -49.574958)
		(width 0.14605)
		(layer "B.Cu")
		(net "PCIE_COMP_TO_IOM_18_DP")
	)
	(arc
		(start 116.03355 -32.478218)
		(mid 115.960365 -32.527118)
		(end 115.874038 -32.544258)
		(width 0.14605)
		(layer "B.Cu")
		(net "PCIE_COMP_TO_IOM_18_DP")
	)
	(arc
		(start 115.645946 -32.544258)
		(mid 115.440478 -32.45915)
		(end 115.35537 -32.253682)
		(width 0.14605)
		(layer "B.Cu")
		(net "PCIE_COMP_TO_IOM_18_DP")
	)
	(arc
		(start 78.410816 -77.197966)
		(mid 78.206605 -77.113379)
		(end 78.122018 -76.909168)
		(width 0.14605)
		(layer "B.Cu")
		(net "PCIE_COMP_TO_IOM_18_DP")
	)
	(arc
		(start 116.099844 -32.318198)
		(mid 116.082617 -32.404805)
		(end 116.03355 -32.478218)
		(width 0.14605)
		(layer "B.Cu")
		(net "PCIE_COMP_TO_IOM_18_DP")
	)
	(segment
		(start 75.475084 -77.749908)
		(end 76.659232 -77.749908)
		(width 0.136652)
		(layer "F.Cu")
		(net "PCIE_COMP_TO_IOM_18_DN")
	)
	(segment
		(start 76.659232 -77.749908)
		(end 76.894944 -77.514196)
		(width 0.14605)
		(layer "F.Cu")
		(net "PCIE_COMP_TO_IOM_18_DN")
	)
	(segment
		(start 76.894944 -77.514196)
		(end 77.838046 -77.514196)
		(width 0.14605)
		(layer "F.Cu")
		(net "PCIE_COMP_TO_IOM_18_DN")
	)
	(arc
		(start 77.838046 -77.514196)
		(mid 78.038845 -77.597369)
		(end 78.122018 -77.798168)
		(width 0.14605)
		(layer "F.Cu")
		(net "PCIE_COMP_TO_IOM_18_DN")
	)
	(segment
		(start 88.84793 -75.193652)
		(end 87.038434 -77.003148)
		(width 0.14605)
		(layer "B.Cu")
		(net "PCIE_COMP_TO_IOM_18_DN")
	)
	(segment
		(start 103.553768 -26.666444)
		(end 96.288098 -31.567628)
		(width 0.14605)
		(layer "B.Cu")
		(net "PCIE_COMP_TO_IOM_18_DN")
	)
	(segment
		(start 116.099844 -33.399984)
		(end 116.099844 -33.026604)
		(width 0.14605)
		(layer "B.Cu")
		(net "PCIE_COMP_TO_IOM_18_DN")
	)
	(segment
		(start 93.085412 -36.348924)
		(end 91.56573 -43.941238)
		(width 0.14605)
		(layer "B.Cu")
		(net "PCIE_COMP_TO_IOM_18_DN")
	)
	(segment
		(start 90.699082 -62.682882)
		(end 90.843354 -63.203074)
		(width 0.14605)
		(layer "B.Cu")
		(net "PCIE_COMP_TO_IOM_18_DN")
	)
	(segment
		(start 91.077542 -64.047624)
		(end 88.84793 -75.193652)
		(width 0.14605)
		(layer "B.Cu")
		(net "PCIE_COMP_TO_IOM_18_DN")
	)
	(segment
		(start 92.59951 -48.806354)
		(end 92.762578 -49.574958)
		(width 0.14605)
		(layer "B.Cu")
		(net "PCIE_COMP_TO_IOM_18_DN")
	)
	(segment
		(start 92.354146 -51.492658)
		(end 92.443554 -51.91252)
		(width 0.14605)
		(layer "B.Cu")
		(net "PCIE_COMP_TO_IOM_18_DN")
	)
	(segment
		(start 91.56573 -43.941238)
		(end 92.59951 -48.806354)
		(width 0.14605)
		(layer "B.Cu")
		(net "PCIE_COMP_TO_IOM_18_DN")
	)
	(segment
		(start 115.04422 -32.253682)
		(end 115.04422 -30.305502)
		(width 0.14605)
		(layer "B.Cu")
		(net "PCIE_COMP_TO_IOM_18_DN")
	)
	(segment
		(start 90.392758 -61.579252)
		(end 90.699082 -62.682882)
		(width 0.14605)
		(layer "B.Cu")
		(net "PCIE_COMP_TO_IOM_18_DN")
	)
	(segment
		(start 81.435194 -78.114144)
		(end 80.830166 -77.509116)
		(width 0.14605)
		(layer "B.Cu")
		(net "PCIE_COMP_TO_IOM_18_DN")
	)
	(segment
		(start 87.038434 -77.003148)
		(end 84.68233 -77.003148)
		(width 0.14605)
		(layer "B.Cu")
		(net "PCIE_COMP_TO_IOM_18_DN")
	)
	(segment
		(start 90.843354 -63.203074)
		(end 90.950542 -63.589916)
		(width 0.14605)
		(layer "B.Cu")
		(net "PCIE_COMP_TO_IOM_18_DN")
	)
	(segment
		(start 92.443554 -51.91252)
		(end 90.392758 -61.579252)
		(width 0.14605)
		(layer "B.Cu")
		(net "PCIE_COMP_TO_IOM_18_DN")
	)
	(segment
		(start 90.950542 -63.589916)
		(end 91.077542 -64.047624)
		(width 0.14605)
		(layer "B.Cu")
		(net "PCIE_COMP_TO_IOM_18_DN")
	)
	(segment
		(start 92.762578 -49.574958)
		(end 92.354146 -51.492658)
		(width 0.14605)
		(layer "B.Cu")
		(net "PCIE_COMP_TO_IOM_18_DN")
	)
	(segment
		(start 115.928394 -32.855408)
		(end 115.645946 -32.855408)
		(width 0.14605)
		(layer "B.Cu")
		(net "PCIE_COMP_TO_IOM_18_DN")
	)
	(segment
		(start 111.405162 -26.666444)
		(end 103.553768 -26.666444)
		(width 0.14605)
		(layer "B.Cu")
		(net "PCIE_COMP_TO_IOM_18_DN")
	)
	(segment
		(start 84.68233 -77.003148)
		(end 83.571334 -78.114144)
		(width 0.14605)
		(layer "B.Cu")
		(net "PCIE_COMP_TO_IOM_18_DN")
	)
	(segment
		(start 83.571334 -78.114144)
		(end 81.435194 -78.114144)
		(width 0.14605)
		(layer "B.Cu")
		(net "PCIE_COMP_TO_IOM_18_DN")
	)
	(segment
		(start 96.288098 -31.567628)
		(end 93.085412 -36.348924)
		(width 0.14605)
		(layer "B.Cu")
		(net "PCIE_COMP_TO_IOM_18_DN")
	)
	(segment
		(start 80.830166 -77.509116)
		(end 78.41107 -77.509116)
		(width 0.14605)
		(layer "B.Cu")
		(net "PCIE_COMP_TO_IOM_18_DN")
	)
	(segment
		(start 115.04422 -30.305502)
		(end 111.405162 -26.666444)
		(width 0.14605)
		(layer "B.Cu")
		(net "PCIE_COMP_TO_IOM_18_DN")
	)
	(arc
		(start 116.099844 -33.026604)
		(mid 116.086847 -32.961173)
		(end 116.049806 -32.9057)
		(width 0.14605)
		(layer "B.Cu")
		(net "PCIE_COMP_TO_IOM_18_DN")
	)
	(arc
		(start 78.41107 -77.509116)
		(mid 78.206679 -77.593777)
		(end 78.122018 -77.798168)
		(width 0.14605)
		(layer "B.Cu")
		(net "PCIE_COMP_TO_IOM_18_DN")
	)
	(arc
		(start 116.049806 -32.9057)
		(mid 115.994102 -32.86848)
		(end 115.928394 -32.855408)
		(width 0.14605)
		(layer "B.Cu")
		(net "PCIE_COMP_TO_IOM_18_DN")
	)
	(arc
		(start 115.645946 -32.855408)
		(mid 115.220461 -32.679167)
		(end 115.04422 -32.253682)
		(width 0.14605)
		(layer "B.Cu")
		(net "PCIE_COMP_TO_IOM_18_DN")
	)
	(segment
		(start 76.293218 -73.749916)
		(end 76.534518 -73.991216)
		(width 0.14605)
		(layer "F.Cu")
		(net "PCIE_COMP_TO_IOM_17_DP")
	)
	(segment
		(start 75.475084 -73.749916)
		(end 76.293218 -73.749916)
		(width 0.14605)
		(layer "F.Cu")
		(net "PCIE_COMP_TO_IOM_17_DP")
	)
	(segment
		(start 76.534518 -73.991216)
		(end 77.00137 -73.991216)
		(width 0.14605)
		(layer "F.Cu")
		(net "PCIE_COMP_TO_IOM_17_DP")
	)
	(arc
		(start 77.00137 -73.991216)
		(mid 77.201091 -73.908489)
		(end 77.283818 -73.708768)
		(width 0.14605)
		(layer "F.Cu")
		(net "PCIE_COMP_TO_IOM_17_DP")
	)
	(segment
		(start 89.440004 -64.786256)
		(end 89.042748 -66.771774)
		(width 0.14605)
		(layer "B.Cu")
		(net "PCIE_COMP_TO_IOM_17_DP")
	)
	(segment
		(start 93.288612 -32.342328)
		(end 92.648278 -33.302956)
		(width 0.14605)
		(layer "B.Cu")
		(net "PCIE_COMP_TO_IOM_17_DP")
	)
	(segment
		(start 90.56243 -52.795424)
		(end 88.697562 -62.110112)
		(width 0.14605)
		(layer "B.Cu")
		(net "PCIE_COMP_TO_IOM_17_DP")
	)
	(segment
		(start 102.926896 -24.81834)
		(end 94.604078 -30.369002)
		(width 0.14605)
		(layer "B.Cu")
		(net "PCIE_COMP_TO_IOM_17_DP")
	)
	(segment
		(start 91.973908 -34.314384)
		(end 90.036396 -44.02074)
		(width 0.14605)
		(layer "B.Cu")
		(net "PCIE_COMP_TO_IOM_17_DP")
	)
	(segment
		(start 88.697562 -62.110112)
		(end 89.440004 -64.786256)
		(width 0.14605)
		(layer "B.Cu")
		(net "PCIE_COMP_TO_IOM_17_DP")
	)
	(segment
		(start 90.600784 -48.351694)
		(end 90.601038 -48.351694)
		(width 0.14605)
		(layer "B.Cu")
		(net "PCIE_COMP_TO_IOM_17_DP")
	)
	(segment
		(start 81.387188 -73.304654)
		(end 80.694276 -73.997566)
		(width 0.14605)
		(layer "B.Cu")
		(net "PCIE_COMP_TO_IOM_17_DP")
	)
	(segment
		(start 117.899942 -33.200086)
		(end 117.899942 -33.518348)
		(width 0.14605)
		(layer "B.Cu")
		(net "PCIE_COMP_TO_IOM_17_DP")
	)
	(segment
		(start 90.601038 -48.351694)
		(end 90.14079 -50.687478)
		(width 0.14605)
		(layer "B.Cu")
		(net "PCIE_COMP_TO_IOM_17_DP")
	)
	(segment
		(start 117.155468 -30.218888)
		(end 111.75492 -24.81834)
		(width 0.14605)
		(layer "B.Cu")
		(net "PCIE_COMP_TO_IOM_17_DP")
	)
	(segment
		(start 90.048334 -44.0817)
		(end 90.048588 -44.0817)
		(width 0.14605)
		(layer "B.Cu")
		(net "PCIE_COMP_TO_IOM_17_DP")
	)
	(segment
		(start 77.283818 -73.765156)
		(end 77.283818 -73.708768)
		(width 0.14605)
		(layer "B.Cu")
		(net "PCIE_COMP_TO_IOM_17_DP")
	)
	(segment
		(start 92.648278 -33.302956)
		(end 91.973908 -34.314384)
		(width 0.14605)
		(layer "B.Cu")
		(net "PCIE_COMP_TO_IOM_17_DP")
	)
	(segment
		(start 89.042494 -66.771774)
		(end 87.851488 -72.727312)
		(width 0.14605)
		(layer "B.Cu")
		(net "PCIE_COMP_TO_IOM_17_DP")
	)
	(segment
		(start 90.14079 -50.687478)
		(end 90.56243 -52.795424)
		(width 0.14605)
		(layer "B.Cu")
		(net "PCIE_COMP_TO_IOM_17_DP")
	)
	(segment
		(start 90.75039 -47.593504)
		(end 90.600784 -48.351694)
		(width 0.14605)
		(layer "B.Cu")
		(net "PCIE_COMP_TO_IOM_17_DP")
	)
	(segment
		(start 87.851488 -72.727312)
		(end 86.099904 -74.478896)
		(width 0.14605)
		(layer "B.Cu")
		(net "PCIE_COMP_TO_IOM_17_DP")
	)
	(segment
		(start 90.750644 -47.593504)
		(end 90.75039 -47.593504)
		(width 0.14605)
		(layer "B.Cu")
		(net "PCIE_COMP_TO_IOM_17_DP")
	)
	(segment
		(start 90.048588 -44.0817)
		(end 90.405712 -45.867828)
		(width 0.14605)
		(layer "B.Cu")
		(net "PCIE_COMP_TO_IOM_17_DP")
	)
	(segment
		(start 117.155468 -33.453832)
		(end 117.155468 -30.218888)
		(width 0.14605)
		(layer "B.Cu")
		(net "PCIE_COMP_TO_IOM_17_DP")
	)
	(segment
		(start 117.674136 -33.744408)
		(end 117.446044 -33.744408)
		(width 0.14605)
		(layer "B.Cu")
		(net "PCIE_COMP_TO_IOM_17_DP")
	)
	(segment
		(start 80.694276 -73.997566)
		(end 77.516228 -73.997566)
		(width 0.14605)
		(layer "B.Cu")
		(net "PCIE_COMP_TO_IOM_17_DP")
	)
	(segment
		(start 84.685124 -74.478896)
		(end 83.510882 -73.304654)
		(width 0.14605)
		(layer "B.Cu")
		(net "PCIE_COMP_TO_IOM_17_DP")
	)
	(segment
		(start 86.099904 -74.478896)
		(end 84.685124 -74.478896)
		(width 0.14605)
		(layer "B.Cu")
		(net "PCIE_COMP_TO_IOM_17_DP")
	)
	(segment
		(start 90.405712 -45.867828)
		(end 90.750644 -47.593504)
		(width 0.14605)
		(layer "B.Cu")
		(net "PCIE_COMP_TO_IOM_17_DP")
	)
	(segment
		(start 83.510882 -73.304654)
		(end 81.387188 -73.304654)
		(width 0.14605)
		(layer "B.Cu")
		(net "PCIE_COMP_TO_IOM_17_DP")
	)
	(segment
		(start 111.75492 -24.81834)
		(end 102.926896 -24.81834)
		(width 0.14605)
		(layer "B.Cu")
		(net "PCIE_COMP_TO_IOM_17_DP")
	)
	(segment
		(start 90.036396 -44.02074)
		(end 90.048334 -44.0817)
		(width 0.14605)
		(layer "B.Cu")
		(net "PCIE_COMP_TO_IOM_17_DP")
	)
	(segment
		(start 94.604078 -30.369002)
		(end 93.288612 -32.342328)
		(width 0.14605)
		(layer "B.Cu")
		(net "PCIE_COMP_TO_IOM_17_DP")
	)
	(segment
		(start 89.042748 -66.771774)
		(end 89.042494 -66.771774)
		(width 0.14605)
		(layer "B.Cu")
		(net "PCIE_COMP_TO_IOM_17_DP")
	)
	(arc
		(start 117.833648 -33.678368)
		(mid 117.760463 -33.727268)
		(end 117.674136 -33.744408)
		(width 0.14605)
		(layer "B.Cu")
		(net "PCIE_COMP_TO_IOM_17_DP")
	)
	(arc
		(start 117.446044 -33.744408)
		(mid 117.240576 -33.6593)
		(end 117.155468 -33.453832)
		(width 0.14605)
		(layer "B.Cu")
		(net "PCIE_COMP_TO_IOM_17_DP")
	)
	(arc
		(start 77.516228 -73.997566)
		(mid 77.351889 -73.929495)
		(end 77.283818 -73.765156)
		(width 0.14605)
		(layer "B.Cu")
		(net "PCIE_COMP_TO_IOM_17_DP")
	)
	(arc
		(start 117.899942 -33.518348)
		(mid 117.882715 -33.604955)
		(end 117.833648 -33.678368)
		(width 0.14605)
		(layer "B.Cu")
		(net "PCIE_COMP_TO_IOM_17_DP")
	)
	(segment
		(start 75.475084 -74.550016)
		(end 76.321666 -74.550016)
		(width 0.14605)
		(layer "F.Cu")
		(net "PCIE_COMP_TO_IOM_17_DN")
	)
	(segment
		(start 76.569316 -74.302366)
		(end 76.988416 -74.302366)
		(width 0.14605)
		(layer "F.Cu")
		(net "PCIE_COMP_TO_IOM_17_DN")
	)
	(segment
		(start 76.321666 -74.550016)
		(end 76.569316 -74.302366)
		(width 0.14605)
		(layer "F.Cu")
		(net "PCIE_COMP_TO_IOM_17_DN")
	)
	(arc
		(start 76.988416 -74.302366)
		(mid 77.197297 -74.388887)
		(end 77.283818 -74.597768)
		(width 0.14605)
		(layer "F.Cu")
		(net "PCIE_COMP_TO_IOM_17_DN")
	)
	(segment
		(start 80.823308 -74.308716)
		(end 77.516228 -74.308716)
		(width 0.14605)
		(layer "B.Cu")
		(net "PCIE_COMP_TO_IOM_17_DN")
	)
	(segment
		(start 88.138254 -72.880728)
		(end 86.228936 -74.790046)
		(width 0.14605)
		(layer "B.Cu")
		(net "PCIE_COMP_TO_IOM_17_DN")
	)
	(segment
		(start 103.021384 -25.12949)
		(end 94.828614 -30.593538)
		(width 0.14605)
		(layer "B.Cu")
		(net "PCIE_COMP_TO_IOM_17_DN")
	)
	(segment
		(start 91.06789 -47.592996)
		(end 90.458036 -50.68697)
		(width 0.14605)
		(layer "B.Cu")
		(net "PCIE_COMP_TO_IOM_17_DN")
	)
	(segment
		(start 117.728492 -34.055558)
		(end 117.446044 -34.055558)
		(width 0.14605)
		(layer "B.Cu")
		(net "PCIE_COMP_TO_IOM_17_DN")
	)
	(segment
		(start 89.75979 -64.774572)
		(end 88.951054 -68.817744)
		(width 0.14605)
		(layer "B.Cu")
		(net "PCIE_COMP_TO_IOM_17_DN")
	)
	(segment
		(start 77.283818 -74.541126)
		(end 77.283818 -74.597768)
		(width 0.14605)
		(layer "B.Cu")
		(net "PCIE_COMP_TO_IOM_17_DN")
	)
	(segment
		(start 86.228936 -74.790046)
		(end 84.556092 -74.790046)
		(width 0.14605)
		(layer "B.Cu")
		(net "PCIE_COMP_TO_IOM_17_DN")
	)
	(segment
		(start 111.625888 -25.12949)
		(end 103.021384 -25.12949)
		(width 0.14605)
		(layer "B.Cu")
		(net "PCIE_COMP_TO_IOM_17_DN")
	)
	(segment
		(start 90.813128 -46.317154)
		(end 91.06789 -47.592996)
		(width 0.14605)
		(layer "B.Cu")
		(net "PCIE_COMP_TO_IOM_17_DN")
	)
	(segment
		(start 116.844318 -33.453832)
		(end 116.844318 -30.34792)
		(width 0.14605)
		(layer "B.Cu")
		(net "PCIE_COMP_TO_IOM_17_DN")
	)
	(segment
		(start 84.556092 -74.790046)
		(end 83.38185 -73.615804)
		(width 0.14605)
		(layer "B.Cu")
		(net "PCIE_COMP_TO_IOM_17_DN")
	)
	(segment
		(start 83.38185 -73.615804)
		(end 81.51622 -73.615804)
		(width 0.14605)
		(layer "B.Cu")
		(net "PCIE_COMP_TO_IOM_17_DN")
	)
	(segment
		(start 88.951054 -68.817744)
		(end 88.138254 -72.880728)
		(width 0.14605)
		(layer "B.Cu")
		(net "PCIE_COMP_TO_IOM_17_DN")
	)
	(segment
		(start 117.899942 -34.600134)
		(end 117.899942 -34.226754)
		(width 0.14605)
		(layer "B.Cu")
		(net "PCIE_COMP_TO_IOM_17_DN")
	)
	(segment
		(start 81.51622 -73.615804)
		(end 80.823308 -74.308716)
		(width 0.14605)
		(layer "B.Cu")
		(net "PCIE_COMP_TO_IOM_17_DN")
	)
	(segment
		(start 94.828614 -30.593538)
		(end 92.267024 -34.435796)
		(width 0.14605)
		(layer "B.Cu")
		(net "PCIE_COMP_TO_IOM_17_DN")
	)
	(segment
		(start 90.458036 -50.68697)
		(end 90.87993 -52.795424)
		(width 0.14605)
		(layer "B.Cu")
		(net "PCIE_COMP_TO_IOM_17_DN")
	)
	(segment
		(start 92.267024 -34.435796)
		(end 90.353896 -44.02074)
		(width 0.14605)
		(layer "B.Cu")
		(net "PCIE_COMP_TO_IOM_17_DN")
	)
	(segment
		(start 116.844318 -30.34792)
		(end 111.625888 -25.12949)
		(width 0.14605)
		(layer "B.Cu")
		(net "PCIE_COMP_TO_IOM_17_DN")
	)
	(segment
		(start 90.87993 -52.795424)
		(end 89.017348 -62.098428)
		(width 0.14605)
		(layer "B.Cu")
		(net "PCIE_COMP_TO_IOM_17_DN")
	)
	(segment
		(start 90.353896 -44.02074)
		(end 90.813128 -46.317154)
		(width 0.14605)
		(layer "B.Cu")
		(net "PCIE_COMP_TO_IOM_17_DN")
	)
	(segment
		(start 89.017348 -62.098428)
		(end 89.75979 -64.774572)
		(width 0.14605)
		(layer "B.Cu")
		(net "PCIE_COMP_TO_IOM_17_DN")
	)
	(arc
		(start 117.849904 -34.10585)
		(mid 117.7942 -34.06863)
		(end 117.728492 -34.055558)
		(width 0.14605)
		(layer "B.Cu")
		(net "PCIE_COMP_TO_IOM_17_DN")
	)
	(arc
		(start 117.446044 -34.055558)
		(mid 117.020559 -33.879317)
		(end 116.844318 -33.453832)
		(width 0.14605)
		(layer "B.Cu")
		(net "PCIE_COMP_TO_IOM_17_DN")
	)
	(arc
		(start 117.899942 -34.226754)
		(mid 117.886945 -34.161323)
		(end 117.849904 -34.10585)
		(width 0.14605)
		(layer "B.Cu")
		(net "PCIE_COMP_TO_IOM_17_DN")
	)
	(arc
		(start 77.516228 -74.308716)
		(mid 77.351889 -74.376787)
		(end 77.283818 -74.541126)
		(width 0.14605)
		(layer "B.Cu")
		(net "PCIE_COMP_TO_IOM_17_DN")
	)
	(segment
		(start 76.659232 -70.550024)
		(end 76.90739 -70.798182)
		(width 0.14605)
		(layer "F.Cu")
		(net "PCIE_COMP_TO_IOM_16_DP")
	)
	(segment
		(start 76.90739 -70.798182)
		(end 77.832204 -70.798182)
		(width 0.14605)
		(layer "F.Cu")
		(net "PCIE_COMP_TO_IOM_16_DP")
	)
	(segment
		(start 75.475084 -70.550024)
		(end 76.659232 -70.550024)
		(width 0.136652)
		(layer "F.Cu")
		(net "PCIE_COMP_TO_IOM_16_DP")
	)
	(arc
		(start 77.832204 -70.798182)
		(mid 78.037133 -70.713297)
		(end 78.122018 -70.508368)
		(width 0.14605)
		(layer "F.Cu")
		(net "PCIE_COMP_TO_IOM_16_DP")
	)
	(segment
		(start 89.265252 -52.481734)
		(end 87.350346 -62.546484)
		(width 0.14605)
		(layer "B.Cu")
		(net "PCIE_COMP_TO_IOM_16_DP")
	)
	(segment
		(start 82.3214 -71.481442)
		(end 81.491074 -71.481442)
		(width 0.14605)
		(layer "B.Cu")
		(net "PCIE_COMP_TO_IOM_16_DP")
	)
	(segment
		(start 119.70004 -32.00019)
		(end 119.70004 -32.318198)
		(width 0.14605)
		(layer "B.Cu")
		(net "PCIE_COMP_TO_IOM_16_DP")
	)
	(segment
		(start 87.596218 -66.036952)
		(end 87.023194 -68.429886)
		(width 0.14605)
		(layer "B.Cu")
		(net "PCIE_COMP_TO_IOM_16_DP")
	)
	(segment
		(start 90.778838 -32.156654)
		(end 90.742008 -32.33928)
		(width 0.14605)
		(layer "B.Cu")
		(net "PCIE_COMP_TO_IOM_16_DP")
	)
	(segment
		(start 89.086944 -49.964086)
		(end 88.930734 -50.761646)
		(width 0.14605)
		(layer "B.Cu")
		(net "PCIE_COMP_TO_IOM_16_DP")
	)
	(segment
		(start 87.365586 -64.540892)
		(end 87.596218 -66.036952)
		(width 0.14605)
		(layer "B.Cu")
		(net "PCIE_COMP_TO_IOM_16_DP")
	)
	(segment
		(start 90.948764 -33.282636)
		(end 88.80221 -44.036742)
		(width 0.14605)
		(layer "B.Cu")
		(net "PCIE_COMP_TO_IOM_16_DP")
	)
	(segment
		(start 87.36584 -64.540892)
		(end 87.365586 -64.540892)
		(width 0.14605)
		(layer "B.Cu")
		(net "PCIE_COMP_TO_IOM_16_DP")
	)
	(segment
		(start 88.930734 -50.761646)
		(end 89.265252 -52.481734)
		(width 0.14605)
		(layer "B.Cu")
		(net "PCIE_COMP_TO_IOM_16_DP")
	)
	(segment
		(start 89.135204 -49.717706)
		(end 89.116408 -49.812448)
		(width 0.14605)
		(layer "B.Cu")
		(net "PCIE_COMP_TO_IOM_16_DP")
	)
	(segment
		(start 119.474234 -32.544258)
		(end 119.246142 -32.544258)
		(width 0.14605)
		(layer "B.Cu")
		(net "PCIE_COMP_TO_IOM_16_DP")
	)
	(segment
		(start 87.455756 -64.067182)
		(end 87.451438 -64.091312)
		(width 0.14605)
		(layer "B.Cu")
		(net "PCIE_COMP_TO_IOM_16_DP")
	)
	(segment
		(start 91.260676 -30.50413)
		(end 90.778838 -32.156654)
		(width 0.14605)
		(layer "B.Cu")
		(net "PCIE_COMP_TO_IOM_16_DP")
	)
	(segment
		(start 88.80221 -44.036742)
		(end 89.532714 -47.688754)
		(width 0.14605)
		(layer "B.Cu")
		(net "PCIE_COMP_TO_IOM_16_DP")
	)
	(segment
		(start 83.629754 -70.173088)
		(end 82.3214 -71.481442)
		(width 0.14605)
		(layer "B.Cu")
		(net "PCIE_COMP_TO_IOM_16_DP")
	)
	(segment
		(start 78.122018 -70.539356)
		(end 78.122018 -70.508368)
		(width 0.14605)
		(layer "B.Cu")
		(net "PCIE_COMP_TO_IOM_16_DP")
	)
	(segment
		(start 90.742008 -32.33928)
		(end 90.948764 -33.282636)
		(width 0.14605)
		(layer "B.Cu")
		(net "PCIE_COMP_TO_IOM_16_DP")
	)
	(segment
		(start 89.14638 -49.66081)
		(end 89.135204 -49.717706)
		(width 0.14605)
		(layer "B.Cu")
		(net "PCIE_COMP_TO_IOM_16_DP")
	)
	(segment
		(start 87.023194 -68.429886)
		(end 85.279992 -70.173088)
		(width 0.14605)
		(layer "B.Cu")
		(net "PCIE_COMP_TO_IOM_16_DP")
	)
	(segment
		(start 85.279992 -70.173088)
		(end 83.629754 -70.173088)
		(width 0.14605)
		(layer "B.Cu")
		(net "PCIE_COMP_TO_IOM_16_DP")
	)
	(segment
		(start 81.491074 -71.481442)
		(end 80.806798 -70.797166)
		(width 0.14605)
		(layer "B.Cu")
		(net "PCIE_COMP_TO_IOM_16_DP")
	)
	(segment
		(start 87.350346 -62.546484)
		(end 87.52713 -63.693548)
		(width 0.14605)
		(layer "B.Cu")
		(net "PCIE_COMP_TO_IOM_16_DP")
	)
	(segment
		(start 87.451438 -64.091312)
		(end 87.413592 -64.28994)
		(width 0.14605)
		(layer "B.Cu")
		(net "PCIE_COMP_TO_IOM_16_DP")
	)
	(segment
		(start 87.413592 -64.28994)
		(end 87.36584 -64.540892)
		(width 0.14605)
		(layer "B.Cu")
		(net "PCIE_COMP_TO_IOM_16_DP")
	)
	(segment
		(start 89.532714 -47.688754)
		(end 89.14638 -49.66081)
		(width 0.14605)
		(layer "B.Cu")
		(net "PCIE_COMP_TO_IOM_16_DP")
	)
	(segment
		(start 89.116408 -49.812448)
		(end 89.086944 -49.964086)
		(width 0.14605)
		(layer "B.Cu")
		(net "PCIE_COMP_TO_IOM_16_DP")
	)
	(segment
		(start 118.955566 -28.511246)
		(end 114.046254 -23.601934)
		(width 0.14605)
		(layer "B.Cu")
		(net "PCIE_COMP_TO_IOM_16_DP")
	)
	(segment
		(start 87.45601 -64.067182)
		(end 87.455756 -64.067182)
		(width 0.14605)
		(layer "B.Cu")
		(net "PCIE_COMP_TO_IOM_16_DP")
	)
	(segment
		(start 87.52713 -63.693548)
		(end 87.45601 -64.067182)
		(width 0.14605)
		(layer "B.Cu")
		(net "PCIE_COMP_TO_IOM_16_DP")
	)
	(segment
		(start 80.806798 -70.797166)
		(end 78.379828 -70.797166)
		(width 0.14605)
		(layer "B.Cu")
		(net "PCIE_COMP_TO_IOM_16_DP")
	)
	(segment
		(start 114.046254 -23.601934)
		(end 101.612446 -23.601934)
		(width 0.14605)
		(layer "B.Cu")
		(net "PCIE_COMP_TO_IOM_16_DP")
	)
	(segment
		(start 118.955566 -32.253682)
		(end 118.955566 -28.511246)
		(width 0.14605)
		(layer "B.Cu")
		(net "PCIE_COMP_TO_IOM_16_DP")
	)
	(segment
		(start 101.612446 -23.601934)
		(end 91.260676 -30.50413)
		(width 0.14605)
		(layer "B.Cu")
		(net "PCIE_COMP_TO_IOM_16_DP")
	)
	(arc
		(start 119.246142 -32.544258)
		(mid 119.040674 -32.45915)
		(end 118.955566 -32.253682)
		(width 0.14605)
		(layer "B.Cu")
		(net "PCIE_COMP_TO_IOM_16_DP")
	)
	(arc
		(start 119.633746 -32.478218)
		(mid 119.560561 -32.527118)
		(end 119.474234 -32.544258)
		(width 0.14605)
		(layer "B.Cu")
		(net "PCIE_COMP_TO_IOM_16_DP")
	)
	(arc
		(start 119.70004 -32.318198)
		(mid 119.682813 -32.404805)
		(end 119.633746 -32.478218)
		(width 0.14605)
		(layer "B.Cu")
		(net "PCIE_COMP_TO_IOM_16_DP")
	)
	(arc
		(start 78.379828 -70.797166)
		(mid 78.197529 -70.721655)
		(end 78.122018 -70.539356)
		(width 0.14605)
		(layer "B.Cu")
		(net "PCIE_COMP_TO_IOM_16_DP")
	)
	(segment
		(start 76.900024 -71.109332)
		(end 77.833982 -71.109332)
		(width 0.14605)
		(layer "F.Cu")
		(net "PCIE_COMP_TO_IOM_16_DN")
	)
	(segment
		(start 76.659232 -71.350124)
		(end 76.900024 -71.109332)
		(width 0.14605)
		(layer "F.Cu")
		(net "PCIE_COMP_TO_IOM_16_DN")
	)
	(segment
		(start 75.475084 -71.350124)
		(end 76.659232 -71.350124)
		(width 0.136652)
		(layer "F.Cu")
		(net "PCIE_COMP_TO_IOM_16_DN")
	)
	(arc
		(start 77.833982 -71.109332)
		(mid 78.037654 -71.193696)
		(end 78.122018 -71.397368)
		(width 0.14605)
		(layer "F.Cu")
		(net "PCIE_COMP_TO_IOM_16_DN")
	)
	(segment
		(start 119.52859 -32.855408)
		(end 119.246142 -32.855408)
		(width 0.14605)
		(layer "B.Cu")
		(net "PCIE_COMP_TO_IOM_16_DN")
	)
	(segment
		(start 87.681562 -64.546988)
		(end 87.91321 -66.049906)
		(width 0.14605)
		(layer "B.Cu")
		(net "PCIE_COMP_TO_IOM_16_DN")
	)
	(segment
		(start 89.537286 -49.285144)
		(end 89.451942 -49.7205)
		(width 0.14605)
		(layer "B.Cu")
		(net "PCIE_COMP_TO_IOM_16_DN")
	)
	(segment
		(start 81.362042 -71.792592)
		(end 80.677766 -71.108316)
		(width 0.14605)
		(layer "B.Cu")
		(net "PCIE_COMP_TO_IOM_16_DN")
	)
	(segment
		(start 91.52763 -30.700218)
		(end 91.081352 -32.231076)
		(width 0.14605)
		(layer "B.Cu")
		(net "PCIE_COMP_TO_IOM_16_DN")
	)
	(segment
		(start 89.84996 -47.687992)
		(end 89.537286 -49.285144)
		(width 0.14605)
		(layer "B.Cu")
		(net "PCIE_COMP_TO_IOM_16_DN")
	)
	(segment
		(start 89.582244 -52.481226)
		(end 87.666068 -62.552072)
		(width 0.14605)
		(layer "B.Cu")
		(net "PCIE_COMP_TO_IOM_16_DN")
	)
	(segment
		(start 101.70668 -23.913084)
		(end 91.52763 -30.700218)
		(width 0.14605)
		(layer "B.Cu")
		(net "PCIE_COMP_TO_IOM_16_DN")
	)
	(segment
		(start 78.122018 -71.366126)
		(end 78.122018 -71.397368)
		(width 0.14605)
		(layer "B.Cu")
		(net "PCIE_COMP_TO_IOM_16_DN")
	)
	(segment
		(start 85.409024 -70.484238)
		(end 83.758786 -70.484238)
		(width 0.14605)
		(layer "B.Cu")
		(net "PCIE_COMP_TO_IOM_16_DN")
	)
	(segment
		(start 87.757254 -64.149478)
		(end 87.681562 -64.546734)
		(width 0.14605)
		(layer "B.Cu")
		(net "PCIE_COMP_TO_IOM_16_DN")
	)
	(segment
		(start 118.644416 -28.640278)
		(end 113.917222 -23.913084)
		(width 0.14605)
		(layer "B.Cu")
		(net "PCIE_COMP_TO_IOM_16_DN")
	)
	(segment
		(start 118.644416 -32.253682)
		(end 118.644416 -28.640278)
		(width 0.14605)
		(layer "B.Cu")
		(net "PCIE_COMP_TO_IOM_16_DN")
	)
	(segment
		(start 113.917222 -23.913084)
		(end 101.70668 -23.913084)
		(width 0.14605)
		(layer "B.Cu")
		(net "PCIE_COMP_TO_IOM_16_DN")
	)
	(segment
		(start 119.70004 -33.399984)
		(end 119.70004 -33.026604)
		(width 0.14605)
		(layer "B.Cu")
		(net "PCIE_COMP_TO_IOM_16_DN")
	)
	(segment
		(start 87.666068 -62.552072)
		(end 87.842852 -63.699136)
		(width 0.14605)
		(layer "B.Cu")
		(net "PCIE_COMP_TO_IOM_16_DN")
	)
	(segment
		(start 89.392506 -50.023776)
		(end 89.24798 -50.7619)
		(width 0.14605)
		(layer "B.Cu")
		(net "PCIE_COMP_TO_IOM_16_DN")
	)
	(segment
		(start 87.681562 -64.546734)
		(end 87.681562 -64.546988)
		(width 0.14605)
		(layer "B.Cu")
		(net "PCIE_COMP_TO_IOM_16_DN")
	)
	(segment
		(start 87.91321 -66.049906)
		(end 87.305388 -68.587874)
		(width 0.14605)
		(layer "B.Cu")
		(net "PCIE_COMP_TO_IOM_16_DN")
	)
	(segment
		(start 89.24798 -50.7619)
		(end 89.582244 -52.481226)
		(width 0.14605)
		(layer "B.Cu")
		(net "PCIE_COMP_TO_IOM_16_DN")
	)
	(segment
		(start 89.451942 -49.7205)
		(end 89.392506 -50.023776)
		(width 0.14605)
		(layer "B.Cu")
		(net "PCIE_COMP_TO_IOM_16_DN")
	)
	(segment
		(start 87.842852 -63.699136)
		(end 87.757254 -64.149478)
		(width 0.14605)
		(layer "B.Cu")
		(net "PCIE_COMP_TO_IOM_16_DN")
	)
	(segment
		(start 87.305388 -68.587874)
		(end 85.409024 -70.484238)
		(width 0.14605)
		(layer "B.Cu")
		(net "PCIE_COMP_TO_IOM_16_DN")
	)
	(segment
		(start 80.677766 -71.108316)
		(end 78.379828 -71.108316)
		(width 0.14605)
		(layer "B.Cu")
		(net "PCIE_COMP_TO_IOM_16_DN")
	)
	(segment
		(start 91.060016 -32.33674)
		(end 91.266772 -33.279588)
		(width 0.14605)
		(layer "B.Cu")
		(net "PCIE_COMP_TO_IOM_16_DN")
	)
	(segment
		(start 91.081352 -32.231076)
		(end 91.060016 -32.33674)
		(width 0.14605)
		(layer "B.Cu")
		(net "PCIE_COMP_TO_IOM_16_DN")
	)
	(segment
		(start 82.450432 -71.792592)
		(end 81.362042 -71.792592)
		(width 0.14605)
		(layer "B.Cu")
		(net "PCIE_COMP_TO_IOM_16_DN")
	)
	(segment
		(start 83.758786 -70.484238)
		(end 82.450432 -71.792592)
		(width 0.14605)
		(layer "B.Cu")
		(net "PCIE_COMP_TO_IOM_16_DN")
	)
	(segment
		(start 89.11971 -44.036742)
		(end 89.84996 -47.687992)
		(width 0.14605)
		(layer "B.Cu")
		(net "PCIE_COMP_TO_IOM_16_DN")
	)
	(segment
		(start 91.266772 -33.279588)
		(end 89.11971 -44.036742)
		(width 0.14605)
		(layer "B.Cu")
		(net "PCIE_COMP_TO_IOM_16_DN")
	)
	(arc
		(start 119.650002 -32.9057)
		(mid 119.594298 -32.86848)
		(end 119.52859 -32.855408)
		(width 0.14605)
		(layer "B.Cu")
		(net "PCIE_COMP_TO_IOM_16_DN")
	)
	(arc
		(start 119.246142 -32.855408)
		(mid 118.820657 -32.679167)
		(end 118.644416 -32.253682)
		(width 0.14605)
		(layer "B.Cu")
		(net "PCIE_COMP_TO_IOM_16_DN")
	)
	(arc
		(start 119.70004 -33.026604)
		(mid 119.687043 -32.961173)
		(end 119.650002 -32.9057)
		(width 0.14605)
		(layer "B.Cu")
		(net "PCIE_COMP_TO_IOM_16_DN")
	)
	(arc
		(start 78.379828 -71.108316)
		(mid 78.197529 -71.183827)
		(end 78.122018 -71.366126)
		(width 0.14605)
		(layer "B.Cu")
		(net "PCIE_COMP_TO_IOM_16_DN")
	)
	(segment
		(start 190.9826 -81.915)
		(end 190.9826 -79.540608)
		(width 0.14605)
		(layer "F.Cu")
		(net "PCIE_COMP_TO_IOM_15_DP")
	)
	(segment
		(start 190.179198 -83.886802)
		(end 190.127382 -83.938618)
		(width 0.14605)
		(layer "F.Cu")
		(net "PCIE_COMP_TO_IOM_15_DP")
	)
	(segment
		(start 191.489076 -76.81087)
		(end 191.600074 -76.699872)
		(width 0.14605)
		(layer "F.Cu")
		(net "PCIE_COMP_TO_IOM_15_DP")
	)
	(segment
		(start 191.489076 -79.034132)
		(end 191.489076 -76.81087)
		(width 0.14605)
		(layer "F.Cu")
		(net "PCIE_COMP_TO_IOM_15_DP")
	)
	(segment
		(start 189.5348 -83.650836)
		(end 189.5348 -83.3628)
		(width 0.14605)
		(layer "F.Cu")
		(net "PCIE_COMP_TO_IOM_15_DP")
	)
	(segment
		(start 189.822582 -83.938618)
		(end 189.5348 -83.650836)
		(width 0.14605)
		(layer "F.Cu")
		(net "PCIE_COMP_TO_IOM_15_DP")
	)
	(segment
		(start 190.9826 -79.540608)
		(end 191.489076 -79.034132)
		(width 0.14605)
		(layer "F.Cu")
		(net "PCIE_COMP_TO_IOM_15_DP")
	)
	(segment
		(start 189.5348 -83.3628)
		(end 190.9826 -81.915)
		(width 0.14605)
		(layer "F.Cu")
		(net "PCIE_COMP_TO_IOM_15_DP")
	)
	(arc
		(start 190.127382 -83.938618)
		(mid 189.974982 -84.001744)
		(end 189.822582 -83.938618)
		(width 0.14605)
		(layer "F.Cu")
		(net "PCIE_COMP_TO_IOM_15_DP")
	)
	(segment
		(start 156.886402 -54.520338)
		(end 156.804106 -54.109366)
		(width 0.1397)
		(layer "In5.Cu")
		(net "PCIE_COMP_TO_IOM_15_DP")
	)
	(segment
		(start 156.570172 -52.93868)
		(end 156.360876 -52.799234)
		(width 0.1397)
		(layer "In5.Cu")
		(net "PCIE_COMP_TO_IOM_15_DP")
	)
	(segment
		(start 152.895808 -34.567622)
		(end 152.813512 -34.15665)
		(width 0.1397)
		(layer "In5.Cu")
		(net "PCIE_COMP_TO_IOM_15_DP")
	)
	(segment
		(start 156.27858 -52.388262)
		(end 156.418026 -52.17922)
		(width 0.1397)
		(layer "In5.Cu")
		(net "PCIE_COMP_TO_IOM_15_DP")
	)
	(segment
		(start 153.36393 -36.90874)
		(end 153.281888 -36.497768)
		(width 0.1397)
		(layer "In5.Cu")
		(net "PCIE_COMP_TO_IOM_15_DP")
	)
	(segment
		(start 152.990296 -35.94735)
		(end 153.129742 -35.738308)
		(width 0.1397)
		(layer "In5.Cu")
		(net "PCIE_COMP_TO_IOM_15_DP")
	)
	(segment
		(start 130.74396 -26.526744)
		(end 130.4925 -26.526744)
		(width 0.1397)
		(layer "In5.Cu")
		(net "PCIE_COMP_TO_IOM_15_DP")
	)
	(segment
		(start 153.224484 -37.118036)
		(end 153.36393 -36.90874)
		(width 0.1397)
		(layer "In5.Cu")
		(net "PCIE_COMP_TO_IOM_15_DP")
	)
	(segment
		(start 153.129742 -35.738308)
		(end 153.0477 -35.327336)
		(width 0.1397)
		(layer "In5.Cu")
		(net "PCIE_COMP_TO_IOM_15_DP")
	)
	(segment
		(start 155.810458 -50.047144)
		(end 155.949904 -49.837848)
		(width 0.1397)
		(layer "In5.Cu")
		(net "PCIE_COMP_TO_IOM_15_DP")
	)
	(segment
		(start 186.16041 -87.134446)
		(end 170.789854 -84.060538)
		(width 0.1397)
		(layer "In5.Cu")
		(net "PCIE_COMP_TO_IOM_15_DP")
	)
	(segment
		(start 153.072592 -36.358322)
		(end 152.990296 -35.94735)
		(width 0.1397)
		(layer "In5.Cu")
		(net "PCIE_COMP_TO_IOM_15_DP")
	)
	(segment
		(start 156.512768 -53.558948)
		(end 156.652214 -53.349652)
		(width 0.1397)
		(layer "In5.Cu")
		(net "PCIE_COMP_TO_IOM_15_DP")
	)
	(segment
		(start 156.595064 -53.96992)
		(end 156.512768 -53.558948)
		(width 0.1397)
		(layer "In5.Cu")
		(net "PCIE_COMP_TO_IOM_15_DP")
	)
	(segment
		(start 131.040124 -26.23058)
		(end 130.74396 -26.526744)
		(width 0.1397)
		(layer "In5.Cu")
		(net "PCIE_COMP_TO_IOM_15_DP")
	)
	(segment
		(start 155.337256 -62.3951)
		(end 155.324556 -62.330584)
		(width 0.1397)
		(layer "In5.Cu")
		(net "PCIE_COMP_TO_IOM_15_DP")
	)
	(segment
		(start 170.789854 -84.060538)
		(end 160.440624 -77.160882)
		(width 0.1397)
		(layer "In5.Cu")
		(net "PCIE_COMP_TO_IOM_15_DP")
	)
	(segment
		(start 160.440624 -77.160882)
		(end 157.368494 -72.552052)
		(width 0.1397)
		(layer "In5.Cu")
		(net "PCIE_COMP_TO_IOM_15_DP")
	)
	(segment
		(start 155.8925 -50.458116)
		(end 155.810458 -50.047144)
		(width 0.1397)
		(layer "In5.Cu")
		(net "PCIE_COMP_TO_IOM_15_DP")
	)
	(segment
		(start 153.75001 -38.83914)
		(end 153.540714 -38.699694)
		(width 0.1397)
		(layer "In5.Cu")
		(net "PCIE_COMP_TO_IOM_15_DP")
	)
	(segment
		(start 145.11782 -24.15032)
		(end 132.868924 -24.15032)
		(width 0.1397)
		(layer "In5.Cu")
		(net "PCIE_COMP_TO_IOM_15_DP")
	)
	(segment
		(start 128.260856 -33.738058)
		(end 128.484122 -33.738058)
		(width 0.1397)
		(layer "In5.Cu")
		(net "PCIE_COMP_TO_IOM_15_DP")
	)
	(segment
		(start 156.335984 -51.768248)
		(end 156.126688 -51.628548)
		(width 0.1397)
		(layer "In5.Cu")
		(net "PCIE_COMP_TO_IOM_15_DP")
	)
	(segment
		(start 127.9652 -29.054044)
		(end 127.9652 -33.442402)
		(width 0.1397)
		(layer "In5.Cu")
		(net "PCIE_COMP_TO_IOM_15_DP")
	)
	(segment
		(start 153.281888 -36.497768)
		(end 153.072592 -36.358322)
		(width 0.1397)
		(layer "In5.Cu")
		(net "PCIE_COMP_TO_IOM_15_DP")
	)
	(segment
		(start 148.192744 -27.225244)
		(end 145.11782 -24.15032)
		(width 0.1397)
		(layer "In5.Cu")
		(net "PCIE_COMP_TO_IOM_15_DP")
	)
	(segment
		(start 155.324556 -62.330584)
		(end 156.886402 -54.520338)
		(width 0.1397)
		(layer "In5.Cu")
		(net "PCIE_COMP_TO_IOM_15_DP")
	)
	(segment
		(start 156.044646 -51.21783)
		(end 156.184092 -51.008534)
		(width 0.1397)
		(layer "In5.Cu")
		(net "PCIE_COMP_TO_IOM_15_DP")
	)
	(segment
		(start 153.30678 -37.529008)
		(end 153.224484 -37.118036)
		(width 0.1397)
		(layer "In5.Cu")
		(net "PCIE_COMP_TO_IOM_15_DP")
	)
	(segment
		(start 156.360876 -52.799234)
		(end 156.27858 -52.388262)
		(width 0.1397)
		(layer "In5.Cu")
		(net "PCIE_COMP_TO_IOM_15_DP")
	)
	(segment
		(start 153.540714 -38.699694)
		(end 153.458672 -38.288722)
		(width 0.1397)
		(layer "In5.Cu")
		(net "PCIE_COMP_TO_IOM_15_DP")
	)
	(segment
		(start 153.0477 -35.327336)
		(end 152.838404 -35.18789)
		(width 0.1397)
		(layer "In5.Cu")
		(net "PCIE_COMP_TO_IOM_15_DP")
	)
	(segment
		(start 131.88442 -25.134824)
		(end 131.88442 -25.386284)
		(width 0.1397)
		(layer "In5.Cu")
		(net "PCIE_COMP_TO_IOM_15_DP")
	)
	(segment
		(start 190.693548 -85.465158)
		(end 189.74054 -86.418166)
		(width 0.1397)
		(layer "In5.Cu")
		(net "PCIE_COMP_TO_IOM_15_DP")
	)
	(segment
		(start 128.700022 -33.522158)
		(end 128.700022 -33.200086)
		(width 0.1397)
		(layer "In5.Cu")
		(net "PCIE_COMP_TO_IOM_15_DP")
	)
	(segment
		(start 155.33751 -62.3951)
		(end 155.337256 -62.3951)
		(width 0.1397)
		(layer "In5.Cu")
		(net "PCIE_COMP_TO_IOM_15_DP")
	)
	(segment
		(start 132.868924 -24.15032)
		(end 131.88442 -25.134824)
		(width 0.1397)
		(layer "In5.Cu")
		(net "PCIE_COMP_TO_IOM_15_DP")
	)
	(segment
		(start 155.949904 -49.837848)
		(end 153.75001 -38.83914)
		(width 0.1397)
		(layer "In5.Cu")
		(net "PCIE_COMP_TO_IOM_15_DP")
	)
	(segment
		(start 131.040124 -25.97912)
		(end 131.040124 -26.23058)
		(width 0.1397)
		(layer "In5.Cu")
		(net "PCIE_COMP_TO_IOM_15_DP")
	)
	(segment
		(start 152.756108 -34.776918)
		(end 152.895808 -34.567622)
		(width 0.1397)
		(layer "In5.Cu")
		(net "PCIE_COMP_TO_IOM_15_DP")
	)
	(segment
		(start 156.804106 -54.109366)
		(end 156.595064 -53.96992)
		(width 0.1397)
		(layer "In5.Cu")
		(net "PCIE_COMP_TO_IOM_15_DP")
	)
	(segment
		(start 131.588002 -25.682702)
		(end 131.336542 -25.682702)
		(width 0.1397)
		(layer "In5.Cu")
		(net "PCIE_COMP_TO_IOM_15_DP")
	)
	(segment
		(start 131.336542 -25.682702)
		(end 131.040124 -25.97912)
		(width 0.1397)
		(layer "In5.Cu")
		(net "PCIE_COMP_TO_IOM_15_DP")
	)
	(segment
		(start 153.515822 -37.668454)
		(end 153.30678 -37.529008)
		(width 0.1397)
		(layer "In5.Cu")
		(net "PCIE_COMP_TO_IOM_15_DP")
	)
	(segment
		(start 130.4925 -26.526744)
		(end 127.9652 -29.054044)
		(width 0.1397)
		(layer "In5.Cu")
		(net "PCIE_COMP_TO_IOM_15_DP")
	)
	(segment
		(start 157.368494 -72.552052)
		(end 155.33751 -62.3951)
		(width 0.1397)
		(layer "In5.Cu")
		(net "PCIE_COMP_TO_IOM_15_DP")
	)
	(segment
		(start 156.652214 -53.349652)
		(end 156.570172 -52.93868)
		(width 0.1397)
		(layer "In5.Cu")
		(net "PCIE_COMP_TO_IOM_15_DP")
	)
	(segment
		(start 153.458672 -38.288722)
		(end 153.598118 -38.079426)
		(width 0.1397)
		(layer "In5.Cu")
		(net "PCIE_COMP_TO_IOM_15_DP")
	)
	(segment
		(start 156.418026 -52.17922)
		(end 156.335984 -51.768248)
		(width 0.1397)
		(layer "In5.Cu")
		(net "PCIE_COMP_TO_IOM_15_DP")
	)
	(segment
		(start 153.598118 -38.079426)
		(end 153.515822 -37.668454)
		(width 0.1397)
		(layer "In5.Cu")
		(net "PCIE_COMP_TO_IOM_15_DP")
	)
	(segment
		(start 190.179198 -84.282026)
		(end 190.693548 -84.796376)
		(width 0.1397)
		(layer "In5.Cu")
		(net "PCIE_COMP_TO_IOM_15_DP")
	)
	(segment
		(start 131.88442 -25.386284)
		(end 131.588002 -25.682702)
		(width 0.1397)
		(layer "In5.Cu")
		(net "PCIE_COMP_TO_IOM_15_DP")
	)
	(segment
		(start 152.813512 -34.15665)
		(end 148.192744 -27.225244)
		(width 0.1397)
		(layer "In5.Cu")
		(net "PCIE_COMP_TO_IOM_15_DP")
	)
	(segment
		(start 156.126688 -51.628548)
		(end 156.044646 -51.21783)
		(width 0.1397)
		(layer "In5.Cu")
		(net "PCIE_COMP_TO_IOM_15_DP")
	)
	(segment
		(start 156.184092 -51.008534)
		(end 156.101796 -50.597562)
		(width 0.1397)
		(layer "In5.Cu")
		(net "PCIE_COMP_TO_IOM_15_DP")
	)
	(segment
		(start 156.101796 -50.597562)
		(end 155.8925 -50.458116)
		(width 0.1397)
		(layer "In5.Cu")
		(net "PCIE_COMP_TO_IOM_15_DP")
	)
	(segment
		(start 190.693548 -84.796376)
		(end 190.693548 -85.465158)
		(width 0.1397)
		(layer "In5.Cu")
		(net "PCIE_COMP_TO_IOM_15_DP")
	)
	(segment
		(start 152.838404 -35.18789)
		(end 152.756108 -34.776918)
		(width 0.1397)
		(layer "In5.Cu")
		(net "PCIE_COMP_TO_IOM_15_DP")
	)
	(segment
		(start 189.74054 -86.418166)
		(end 186.16041 -87.134446)
		(width 0.1397)
		(layer "In5.Cu")
		(net "PCIE_COMP_TO_IOM_15_DP")
	)
	(arc
		(start 127.9652 -33.442402)
		(mid 128.051796 -33.651462)
		(end 128.260856 -33.738058)
		(width 0.1397)
		(layer "In5.Cu")
		(net "PCIE_COMP_TO_IOM_15_DP")
	)
	(arc
		(start 190.179198 -83.886802)
		(mid 190.097344 -84.084414)
		(end 190.179198 -84.282026)
		(width 0.1397)
		(layer "In5.Cu")
		(net "PCIE_COMP_TO_IOM_15_DP")
	)
	(arc
		(start 128.484122 -33.738058)
		(mid 128.636786 -33.674822)
		(end 128.700022 -33.522158)
		(width 0.1397)
		(layer "In5.Cu")
		(net "PCIE_COMP_TO_IOM_15_DP")
	)
	(segment
		(start 191.5668 -75.900026)
		(end 191.177926 -76.2889)
		(width 0.14605)
		(layer "F.Cu")
		(net "PCIE_COMP_TO_IOM_15_DN")
	)
	(segment
		(start 191.600074 -75.900026)
		(end 191.5668 -75.900026)
		(width 0.14605)
		(layer "F.Cu")
		(net "PCIE_COMP_TO_IOM_15_DN")
	)
	(segment
		(start 190.67145 -79.411576)
		(end 190.67145 -81.785968)
		(width 0.14605)
		(layer "F.Cu")
		(net "PCIE_COMP_TO_IOM_15_DN")
	)
	(segment
		(start 189.602364 -84.463636)
		(end 189.550802 -84.515198)
		(width 0.14605)
		(layer "F.Cu")
		(net "PCIE_COMP_TO_IOM_15_DN")
	)
	(segment
		(start 190.67145 -81.785968)
		(end 189.22365 -83.233768)
		(width 0.14605)
		(layer "F.Cu")
		(net "PCIE_COMP_TO_IOM_15_DN")
	)
	(segment
		(start 189.22365 -83.233768)
		(end 189.22365 -83.779868)
		(width 0.14605)
		(layer "F.Cu")
		(net "PCIE_COMP_TO_IOM_15_DN")
	)
	(segment
		(start 191.177926 -76.2889)
		(end 191.177926 -78.9051)
		(width 0.14605)
		(layer "F.Cu")
		(net "PCIE_COMP_TO_IOM_15_DN")
	)
	(segment
		(start 189.22365 -83.779868)
		(end 189.602364 -84.158582)
		(width 0.14605)
		(layer "F.Cu")
		(net "PCIE_COMP_TO_IOM_15_DN")
	)
	(segment
		(start 191.177926 -78.9051)
		(end 190.67145 -79.411576)
		(width 0.14605)
		(layer "F.Cu")
		(net "PCIE_COMP_TO_IOM_15_DN")
	)
	(arc
		(start 189.602364 -84.158582)
		(mid 189.66567 -84.311146)
		(end 189.602364 -84.463636)
		(width 0.14605)
		(layer "F.Cu")
		(net "PCIE_COMP_TO_IOM_15_DN")
	)
	(segment
		(start 145.254726 -23.82012)
		(end 148.449538 -27.014678)
		(width 0.1397)
		(layer "In5.Cu")
		(net "PCIE_COMP_TO_IOM_15_DN")
	)
	(segment
		(start 190.363348 -85.328252)
		(end 190.363348 -84.933282)
		(width 0.1397)
		(layer "In5.Cu")
		(net "PCIE_COMP_TO_IOM_15_DN")
	)
	(segment
		(start 170.918886 -83.749388)
		(end 186.16041 -86.797642)
		(width 0.1397)
		(layer "In5.Cu")
		(net "PCIE_COMP_TO_IOM_15_DN")
	)
	(segment
		(start 128.700022 -34.600134)
		(end 128.700022 -34.284158)
		(width 0.1397)
		(layer "In5.Cu")
		(net "PCIE_COMP_TO_IOM_15_DN")
	)
	(segment
		(start 155.66136 -62.330584)
		(end 157.679644 -72.423274)
		(width 0.1397)
		(layer "In5.Cu")
		(net "PCIE_COMP_TO_IOM_15_DN")
	)
	(segment
		(start 157.223206 -54.520338)
		(end 155.66136 -62.330584)
		(width 0.1397)
		(layer "In5.Cu")
		(net "PCIE_COMP_TO_IOM_15_DN")
	)
	(segment
		(start 128.484122 -34.068258)
		(end 128.260856 -34.068258)
		(width 0.1397)
		(layer "In5.Cu")
		(net "PCIE_COMP_TO_IOM_15_DN")
	)
	(segment
		(start 153.124662 -34.027618)
		(end 157.223206 -54.520338)
		(width 0.1397)
		(layer "In5.Cu")
		(net "PCIE_COMP_TO_IOM_15_DN")
	)
	(segment
		(start 189.577726 -86.113874)
		(end 190.363348 -85.328252)
		(width 0.1397)
		(layer "In5.Cu")
		(net "PCIE_COMP_TO_IOM_15_DN")
	)
	(segment
		(start 148.449538 -27.014678)
		(end 153.124662 -34.027618)
		(width 0.1397)
		(layer "In5.Cu")
		(net "PCIE_COMP_TO_IOM_15_DN")
	)
	(segment
		(start 132.732018 -23.82012)
		(end 145.254726 -23.82012)
		(width 0.1397)
		(layer "In5.Cu")
		(net "PCIE_COMP_TO_IOM_15_DN")
	)
	(segment
		(start 157.679644 -72.423274)
		(end 160.678876 -76.92263)
		(width 0.1397)
		(layer "In5.Cu")
		(net "PCIE_COMP_TO_IOM_15_DN")
	)
	(segment
		(start 127.635 -33.442402)
		(end 127.635 -28.917138)
		(width 0.1397)
		(layer "In5.Cu")
		(net "PCIE_COMP_TO_IOM_15_DN")
	)
	(segment
		(start 186.16041 -86.797642)
		(end 189.577726 -86.113874)
		(width 0.1397)
		(layer "In5.Cu")
		(net "PCIE_COMP_TO_IOM_15_DN")
	)
	(segment
		(start 127.635 -28.917138)
		(end 132.732018 -23.82012)
		(width 0.1397)
		(layer "In5.Cu")
		(net "PCIE_COMP_TO_IOM_15_DN")
	)
	(segment
		(start 190.363348 -84.933282)
		(end 189.945264 -84.515198)
		(width 0.1397)
		(layer "In5.Cu")
		(net "PCIE_COMP_TO_IOM_15_DN")
	)
	(segment
		(start 160.678876 -76.92263)
		(end 170.918886 -83.749388)
		(width 0.1397)
		(layer "In5.Cu")
		(net "PCIE_COMP_TO_IOM_15_DN")
	)
	(arc
		(start 189.945264 -84.515198)
		(mid 189.74807 -84.433555)
		(end 189.550802 -84.515198)
		(width 0.1397)
		(layer "In5.Cu")
		(net "PCIE_COMP_TO_IOM_15_DN")
	)
	(arc
		(start 128.260856 -34.068258)
		(mid 127.818309 -33.884949)
		(end 127.635 -33.442402)
		(width 0.1397)
		(layer "In5.Cu")
		(net "PCIE_COMP_TO_IOM_15_DN")
	)
	(arc
		(start 128.700022 -34.284158)
		(mid 128.636786 -34.131494)
		(end 128.484122 -34.068258)
		(width 0.1397)
		(layer "In5.Cu")
		(net "PCIE_COMP_TO_IOM_15_DN")
	)
	(segment
		(start 192.347088 -76.752704)
		(end 192.39992 -76.699872)
		(width 0.14605)
		(layer "F.Cu")
		(net "PCIE_COMP_TO_IOM_14_DP")
	)
	(segment
		(start 192.347088 -83.872578)
		(end 192.347088 -76.752704)
		(width 0.14605)
		(layer "F.Cu")
		(net "PCIE_COMP_TO_IOM_14_DP")
	)
	(segment
		(start 190.8048 -86.165436)
		(end 190.8048 -85.414866)
		(width 0.14605)
		(layer "F.Cu")
		(net "PCIE_COMP_TO_IOM_14_DP")
	)
	(segment
		(start 190.8048 -85.414866)
		(end 192.347088 -83.872578)
		(width 0.14605)
		(layer "F.Cu")
		(net "PCIE_COMP_TO_IOM_14_DP")
	)
	(segment
		(start 191.320166 -86.680802)
		(end 190.8048 -86.165436)
		(width 0.14605)
		(layer "F.Cu")
		(net "PCIE_COMP_TO_IOM_14_DP")
	)
	(arc
		(start 191.728598 -86.680802)
		(mid 191.524382 -86.765391)
		(end 191.320166 -86.680802)
		(width 0.14605)
		(layer "F.Cu")
		(net "PCIE_COMP_TO_IOM_14_DP")
	)
	(segment
		(start 133.690868 -25.284684)
		(end 133.690868 -25.536144)
		(width 0.1397)
		(layer "In5.Cu")
		(net "PCIE_COMP_TO_IOM_14_DP")
	)
	(segment
		(start 152.363932 -36.851082)
		(end 152.281636 -36.44011)
		(width 0.1397)
		(layer "In5.Cu")
		(net "PCIE_COMP_TO_IOM_14_DP")
	)
	(segment
		(start 154.825954 -50.068988)
		(end 154.9654 -49.859692)
		(width 0.1397)
		(layer "In5.Cu")
		(net "PCIE_COMP_TO_IOM_14_DP")
	)
	(segment
		(start 191.962786 -87.310468)
		(end 191.962786 -87.98052)
		(width 0.1397)
		(layer "In5.Cu")
		(net "PCIE_COMP_TO_IOM_14_DP")
	)
	(segment
		(start 155.199588 -51.030378)
		(end 155.117292 -50.619406)
		(width 0.1397)
		(layer "In5.Cu")
		(net "PCIE_COMP_TO_IOM_14_DP")
	)
	(segment
		(start 152.072594 -36.300664)
		(end 151.990298 -35.889692)
		(width 0.1397)
		(layer "In5.Cu")
		(net "PCIE_COMP_TO_IOM_14_DP")
	)
	(segment
		(start 155.294076 -52.410106)
		(end 155.433522 -52.201064)
		(width 0.1397)
		(layer "In5.Cu")
		(net "PCIE_COMP_TO_IOM_14_DP")
	)
	(segment
		(start 170.337988 -84.905596)
		(end 159.810704 -77.887576)
		(width 0.1397)
		(layer "In5.Cu")
		(net "PCIE_COMP_TO_IOM_14_DP")
	)
	(segment
		(start 155.376372 -52.821078)
		(end 155.294076 -52.410106)
		(width 0.1397)
		(layer "In5.Cu")
		(net "PCIE_COMP_TO_IOM_14_DP")
	)
	(segment
		(start 155.433522 -52.201064)
		(end 155.35148 -51.790092)
		(width 0.1397)
		(layer "In5.Cu")
		(net "PCIE_COMP_TO_IOM_14_DP")
	)
	(segment
		(start 152.281636 -36.44011)
		(end 152.072594 -36.300664)
		(width 0.1397)
		(layer "In5.Cu")
		(net "PCIE_COMP_TO_IOM_14_DP")
	)
	(segment
		(start 130.499866 -32.322008)
		(end 130.499866 -32.00019)
		(width 0.1397)
		(layer "In5.Cu")
		(net "PCIE_COMP_TO_IOM_14_DP")
	)
	(segment
		(start 191.728598 -87.076026)
		(end 191.962786 -87.310468)
		(width 0.1397)
		(layer "In5.Cu")
		(net "PCIE_COMP_TO_IOM_14_DP")
	)
	(segment
		(start 191.962786 -87.98052)
		(end 191.094106 -88.8492)
		(width 0.1397)
		(layer "In5.Cu")
		(net "PCIE_COMP_TO_IOM_14_DP")
	)
	(segment
		(start 133.394704 -25.832308)
		(end 133.143244 -25.832308)
		(width 0.1397)
		(layer "In5.Cu")
		(net "PCIE_COMP_TO_IOM_14_DP")
	)
	(segment
		(start 155.585414 -52.960524)
		(end 155.376372 -52.821078)
		(width 0.1397)
		(layer "In5.Cu")
		(net "PCIE_COMP_TO_IOM_14_DP")
	)
	(segment
		(start 133.143244 -25.832308)
		(end 132.846826 -26.128726)
		(width 0.1397)
		(layer "In5.Cu")
		(net "PCIE_COMP_TO_IOM_14_DP")
	)
	(segment
		(start 152.59812 -38.021768)
		(end 152.515824 -37.610796)
		(width 0.1397)
		(layer "In5.Cu")
		(net "PCIE_COMP_TO_IOM_14_DP")
	)
	(segment
		(start 156.463238 -72.866504)
		(end 154.497024 -62.478412)
		(width 0.1397)
		(layer "In5.Cu")
		(net "PCIE_COMP_TO_IOM_14_DP")
	)
	(segment
		(start 155.610306 -53.991764)
		(end 155.528264 -53.580792)
		(width 0.1397)
		(layer "In5.Cu")
		(net "PCIE_COMP_TO_IOM_14_DP")
	)
	(segment
		(start 147.611846 -27.796998)
		(end 144.803114 -24.988266)
		(width 0.1397)
		(layer "In5.Cu")
		(net "PCIE_COMP_TO_IOM_14_DP")
	)
	(segment
		(start 152.129744 -35.68065)
		(end 152.047702 -35.269678)
		(width 0.1397)
		(layer "In5.Cu")
		(net "PCIE_COMP_TO_IOM_14_DP")
	)
	(segment
		(start 152.306528 -37.47135)
		(end 152.224486 -37.060378)
		(width 0.1397)
		(layer "In5.Cu")
		(net "PCIE_COMP_TO_IOM_14_DP")
	)
	(segment
		(start 154.907996 -50.47996)
		(end 154.825954 -50.068988)
		(width 0.1397)
		(layer "In5.Cu")
		(net "PCIE_COMP_TO_IOM_14_DP")
	)
	(segment
		(start 129.765044 -29.210508)
		(end 129.765044 -32.242252)
		(width 0.1397)
		(layer "In5.Cu")
		(net "PCIE_COMP_TO_IOM_14_DP")
	)
	(segment
		(start 155.117292 -50.619406)
		(end 154.907996 -50.47996)
		(width 0.1397)
		(layer "In5.Cu")
		(net "PCIE_COMP_TO_IOM_14_DP")
	)
	(segment
		(start 151.813514 -34.098992)
		(end 147.611846 -27.796998)
		(width 0.1397)
		(layer "In5.Cu")
		(net "PCIE_COMP_TO_IOM_14_DP")
	)
	(segment
		(start 132.846826 -26.380186)
		(end 132.550408 -26.676604)
		(width 0.1397)
		(layer "In5.Cu")
		(net "PCIE_COMP_TO_IOM_14_DP")
	)
	(segment
		(start 133.987286 -24.988266)
		(end 133.690868 -25.284684)
		(width 0.1397)
		(layer "In5.Cu")
		(net "PCIE_COMP_TO_IOM_14_DP")
	)
	(segment
		(start 155.99283 -54.997858)
		(end 155.819602 -54.13121)
		(width 0.1397)
		(layer "In5.Cu")
		(net "PCIE_COMP_TO_IOM_14_DP")
	)
	(segment
		(start 151.990298 -35.889692)
		(end 152.129744 -35.68065)
		(width 0.1397)
		(layer "In5.Cu")
		(net "PCIE_COMP_TO_IOM_14_DP")
	)
	(segment
		(start 152.45842 -38.231064)
		(end 152.59812 -38.021768)
		(width 0.1397)
		(layer "In5.Cu")
		(net "PCIE_COMP_TO_IOM_14_DP")
	)
	(segment
		(start 132.550408 -26.676604)
		(end 132.298948 -26.676604)
		(width 0.1397)
		(layer "In5.Cu")
		(net "PCIE_COMP_TO_IOM_14_DP")
	)
	(segment
		(start 155.819602 -54.13121)
		(end 155.610306 -53.991764)
		(width 0.1397)
		(layer "In5.Cu")
		(net "PCIE_COMP_TO_IOM_14_DP")
	)
	(segment
		(start 132.298948 -26.676604)
		(end 129.765044 -29.210508)
		(width 0.1397)
		(layer "In5.Cu")
		(net "PCIE_COMP_TO_IOM_14_DP")
	)
	(segment
		(start 152.515824 -37.610796)
		(end 152.306528 -37.47135)
		(width 0.1397)
		(layer "In5.Cu")
		(net "PCIE_COMP_TO_IOM_14_DP")
	)
	(segment
		(start 155.66771 -53.371496)
		(end 155.585414 -52.960524)
		(width 0.1397)
		(layer "In5.Cu")
		(net "PCIE_COMP_TO_IOM_14_DP")
	)
	(segment
		(start 152.540716 -38.642036)
		(end 152.45842 -38.231064)
		(width 0.1397)
		(layer "In5.Cu")
		(net "PCIE_COMP_TO_IOM_14_DP")
	)
	(segment
		(start 155.528264 -53.580792)
		(end 155.66771 -53.371496)
		(width 0.1397)
		(layer "In5.Cu")
		(net "PCIE_COMP_TO_IOM_14_DP")
	)
	(segment
		(start 190.06439 -88.8492)
		(end 170.337988 -84.905596)
		(width 0.1397)
		(layer "In5.Cu")
		(net "PCIE_COMP_TO_IOM_14_DP")
	)
	(segment
		(start 152.047702 -35.269678)
		(end 151.838406 -35.130232)
		(width 0.1397)
		(layer "In5.Cu")
		(net "PCIE_COMP_TO_IOM_14_DP")
	)
	(segment
		(start 151.89581 -34.509964)
		(end 151.813514 -34.098992)
		(width 0.1397)
		(layer "In5.Cu")
		(net "PCIE_COMP_TO_IOM_14_DP")
	)
	(segment
		(start 133.690868 -25.536144)
		(end 133.394704 -25.832308)
		(width 0.1397)
		(layer "In5.Cu")
		(net "PCIE_COMP_TO_IOM_14_DP")
	)
	(segment
		(start 154.497024 -62.478412)
		(end 155.99283 -54.997858)
		(width 0.1397)
		(layer "In5.Cu")
		(net "PCIE_COMP_TO_IOM_14_DP")
	)
	(segment
		(start 159.810704 -77.887576)
		(end 156.463238 -72.866504)
		(width 0.1397)
		(layer "In5.Cu")
		(net "PCIE_COMP_TO_IOM_14_DP")
	)
	(segment
		(start 151.75611 -34.71926)
		(end 151.89581 -34.509964)
		(width 0.1397)
		(layer "In5.Cu")
		(net "PCIE_COMP_TO_IOM_14_DP")
	)
	(segment
		(start 191.094106 -88.8492)
		(end 190.06439 -88.8492)
		(width 0.1397)
		(layer "In5.Cu")
		(net "PCIE_COMP_TO_IOM_14_DP")
	)
	(segment
		(start 154.9654 -49.859692)
		(end 152.750012 -38.781482)
		(width 0.1397)
		(layer "In5.Cu")
		(net "PCIE_COMP_TO_IOM_14_DP")
	)
	(segment
		(start 152.750012 -38.781482)
		(end 152.540716 -38.642036)
		(width 0.1397)
		(layer "In5.Cu")
		(net "PCIE_COMP_TO_IOM_14_DP")
	)
	(segment
		(start 132.846826 -26.128726)
		(end 132.846826 -26.380186)
		(width 0.1397)
		(layer "In5.Cu")
		(net "PCIE_COMP_TO_IOM_14_DP")
	)
	(segment
		(start 152.224486 -37.060378)
		(end 152.363932 -36.851082)
		(width 0.1397)
		(layer "In5.Cu")
		(net "PCIE_COMP_TO_IOM_14_DP")
	)
	(segment
		(start 155.142184 -51.650646)
		(end 155.059888 -51.239674)
		(width 0.1397)
		(layer "In5.Cu")
		(net "PCIE_COMP_TO_IOM_14_DP")
	)
	(segment
		(start 144.803114 -24.988266)
		(end 133.987286 -24.988266)
		(width 0.1397)
		(layer "In5.Cu")
		(net "PCIE_COMP_TO_IOM_14_DP")
	)
	(segment
		(start 151.838406 -35.130232)
		(end 151.75611 -34.71926)
		(width 0.1397)
		(layer "In5.Cu")
		(net "PCIE_COMP_TO_IOM_14_DP")
	)
	(segment
		(start 130.0607 -32.537908)
		(end 130.283966 -32.537908)
		(width 0.1397)
		(layer "In5.Cu")
		(net "PCIE_COMP_TO_IOM_14_DP")
	)
	(segment
		(start 155.35148 -51.790092)
		(end 155.142184 -51.650646)
		(width 0.1397)
		(layer "In5.Cu")
		(net "PCIE_COMP_TO_IOM_14_DP")
	)
	(segment
		(start 155.059888 -51.239674)
		(end 155.199588 -51.030378)
		(width 0.1397)
		(layer "In5.Cu")
		(net "PCIE_COMP_TO_IOM_14_DP")
	)
	(arc
		(start 191.728598 -86.680802)
		(mid 191.646744 -86.878414)
		(end 191.728598 -87.076026)
		(width 0.1397)
		(layer "In5.Cu")
		(net "PCIE_COMP_TO_IOM_14_DP")
	)
	(arc
		(start 130.283966 -32.537908)
		(mid 130.43663 -32.474672)
		(end 130.499866 -32.322008)
		(width 0.1397)
		(layer "In5.Cu")
		(net "PCIE_COMP_TO_IOM_14_DP")
	)
	(arc
		(start 129.765044 -32.242252)
		(mid 129.85164 -32.451312)
		(end 130.0607 -32.537908)
		(width 0.1397)
		(layer "In5.Cu")
		(net "PCIE_COMP_TO_IOM_14_DP")
	)
	(segment
		(start 190.49365 -85.285834)
		(end 190.49365 -86.294468)
		(width 0.14605)
		(layer "F.Cu")
		(net "PCIE_COMP_TO_IOM_14_DN")
	)
	(segment
		(start 192.035938 -83.743546)
		(end 190.49365 -85.285834)
		(width 0.14605)
		(layer "F.Cu")
		(net "PCIE_COMP_TO_IOM_14_DN")
	)
	(segment
		(start 192.035938 -76.1746)
		(end 192.035938 -83.743546)
		(width 0.14605)
		(layer "F.Cu")
		(net "PCIE_COMP_TO_IOM_14_DN")
	)
	(segment
		(start 190.49365 -86.294468)
		(end 191.100202 -86.90102)
		(width 0.14605)
		(layer "F.Cu")
		(net "PCIE_COMP_TO_IOM_14_DN")
	)
	(segment
		(start 192.39992 -75.900026)
		(end 192.310512 -75.900026)
		(width 0.14605)
		(layer "F.Cu")
		(net "PCIE_COMP_TO_IOM_14_DN")
	)
	(segment
		(start 192.310512 -75.900026)
		(end 192.035938 -76.1746)
		(width 0.14605)
		(layer "F.Cu")
		(net "PCIE_COMP_TO_IOM_14_DN")
	)
	(arc
		(start 191.100202 -86.90102)
		(mid 191.184865 -87.105146)
		(end 191.100202 -87.309198)
		(width 0.14605)
		(layer "F.Cu")
		(net "PCIE_COMP_TO_IOM_14_DN")
	)
	(segment
		(start 158.411926 -75.19416)
		(end 156.775404 -72.738996)
		(width 0.1397)
		(layer "In5.Cu")
		(net "PCIE_COMP_TO_IOM_14_DN")
	)
	(segment
		(start 156.775404 -72.738996)
		(end 154.833574 -62.48019)
		(width 0.1397)
		(layer "In5.Cu")
		(net "PCIE_COMP_TO_IOM_14_DN")
	)
	(segment
		(start 129.434844 -29.073602)
		(end 129.434844 -32.242252)
		(width 0.1397)
		(layer "In5.Cu")
		(net "PCIE_COMP_TO_IOM_14_DN")
	)
	(segment
		(start 144.94002 -24.658066)
		(end 133.85038 -24.658066)
		(width 0.1397)
		(layer "In5.Cu")
		(net "PCIE_COMP_TO_IOM_14_DN")
	)
	(segment
		(start 160.048956 -77.649324)
		(end 158.41218 -75.19416)
		(width 0.1397)
		(layer "In5.Cu")
		(net "PCIE_COMP_TO_IOM_14_DN")
	)
	(segment
		(start 152.124664 -33.96996)
		(end 147.86864 -27.586432)
		(width 0.1397)
		(layer "In5.Cu")
		(net "PCIE_COMP_TO_IOM_14_DN")
	)
	(segment
		(start 158.41218 -75.19416)
		(end 158.411926 -75.19416)
		(width 0.1397)
		(layer "In5.Cu")
		(net "PCIE_COMP_TO_IOM_14_DN")
	)
	(segment
		(start 147.86864 -27.586432)
		(end 144.94002 -24.658066)
		(width 0.1397)
		(layer "In5.Cu")
		(net "PCIE_COMP_TO_IOM_14_DN")
	)
	(segment
		(start 190.097156 -88.519)
		(end 170.466766 -84.594446)
		(width 0.1397)
		(layer "In5.Cu")
		(net "PCIE_COMP_TO_IOM_14_DN")
	)
	(segment
		(start 130.499866 -33.084008)
		(end 130.499866 -33.399984)
		(width 0.1397)
		(layer "In5.Cu")
		(net "PCIE_COMP_TO_IOM_14_DN")
	)
	(segment
		(start 156.329634 -54.997858)
		(end 152.124664 -33.96996)
		(width 0.1397)
		(layer "In5.Cu")
		(net "PCIE_COMP_TO_IOM_14_DN")
	)
	(segment
		(start 190.9572 -88.519)
		(end 190.097156 -88.519)
		(width 0.1397)
		(layer "In5.Cu")
		(net "PCIE_COMP_TO_IOM_14_DN")
	)
	(segment
		(start 133.85038 -24.658066)
		(end 129.434844 -29.073602)
		(width 0.1397)
		(layer "In5.Cu")
		(net "PCIE_COMP_TO_IOM_14_DN")
	)
	(segment
		(start 191.49441 -87.309198)
		(end 191.632586 -87.447374)
		(width 0.1397)
		(layer "In5.Cu")
		(net "PCIE_COMP_TO_IOM_14_DN")
	)
	(segment
		(start 154.833574 -62.48019)
		(end 156.329634 -54.997858)
		(width 0.1397)
		(layer "In5.Cu")
		(net "PCIE_COMP_TO_IOM_14_DN")
	)
	(segment
		(start 191.632586 -87.447374)
		(end 191.632586 -87.843614)
		(width 0.1397)
		(layer "In5.Cu")
		(net "PCIE_COMP_TO_IOM_14_DN")
	)
	(segment
		(start 130.0607 -32.868108)
		(end 130.283966 -32.868108)
		(width 0.1397)
		(layer "In5.Cu")
		(net "PCIE_COMP_TO_IOM_14_DN")
	)
	(segment
		(start 170.466766 -84.594446)
		(end 160.048956 -77.649324)
		(width 0.1397)
		(layer "In5.Cu")
		(net "PCIE_COMP_TO_IOM_14_DN")
	)
	(segment
		(start 191.632586 -87.843614)
		(end 190.9572 -88.519)
		(width 0.1397)
		(layer "In5.Cu")
		(net "PCIE_COMP_TO_IOM_14_DN")
	)
	(arc
		(start 191.100202 -87.309198)
		(mid 191.297306 -87.22748)
		(end 191.49441 -87.309198)
		(width 0.1397)
		(layer "In5.Cu")
		(net "PCIE_COMP_TO_IOM_14_DN")
	)
	(arc
		(start 130.283966 -32.868108)
		(mid 130.43663 -32.931344)
		(end 130.499866 -33.084008)
		(width 0.1397)
		(layer "In5.Cu")
		(net "PCIE_COMP_TO_IOM_14_DN")
	)
	(arc
		(start 129.434844 -32.242252)
		(mid 129.618153 -32.684799)
		(end 130.0607 -32.868108)
		(width 0.1397)
		(layer "In5.Cu")
		(net "PCIE_COMP_TO_IOM_14_DN")
	)
	(segment
		(start 194.674998 -83.658202)
		(end 194.673982 -83.659218)
		(width 0.14605)
		(layer "F.Cu")
		(net "PCIE_COMP_TO_IOM_13_DP")
	)
	(segment
		(start 193.872358 -76.82738)
		(end 193.999866 -76.699872)
		(width 0.14605)
		(layer "F.Cu")
		(net "PCIE_COMP_TO_IOM_13_DP")
	)
	(segment
		(start 194.267582 -83.659218)
		(end 193.548 -82.939636)
		(width 0.14605)
		(layer "F.Cu")
		(net "PCIE_COMP_TO_IOM_13_DP")
	)
	(segment
		(start 193.548 -79.246476)
		(end 193.872358 -78.922118)
		(width 0.14605)
		(layer "F.Cu")
		(net "PCIE_COMP_TO_IOM_13_DP")
	)
	(segment
		(start 193.872358 -78.922118)
		(end 193.872358 -76.82738)
		(width 0.14605)
		(layer "F.Cu")
		(net "PCIE_COMP_TO_IOM_13_DP")
	)
	(segment
		(start 193.548 -82.939636)
		(end 193.548 -79.246476)
		(width 0.14605)
		(layer "F.Cu")
		(net "PCIE_COMP_TO_IOM_13_DP")
	)
	(arc
		(start 194.673982 -83.659218)
		(mid 194.470782 -83.743386)
		(end 194.267582 -83.659218)
		(width 0.14605)
		(layer "F.Cu")
		(net "PCIE_COMP_TO_IOM_13_DP")
	)
	(segment
		(start 154.24023 -52.17033)
		(end 154.379676 -51.961288)
		(width 0.1397)
		(layer "In5.Cu")
		(net "PCIE_COMP_TO_IOM_13_DP")
	)
	(segment
		(start 154.765756 -53.891434)
		(end 154.55646 -53.751988)
		(width 0.1397)
		(layer "In5.Cu")
		(net "PCIE_COMP_TO_IOM_13_DP")
	)
	(segment
		(start 151.026622 -35.194748)
		(end 150.817326 -35.055302)
		(width 0.1397)
		(layer "In5.Cu")
		(net "PCIE_COMP_TO_IOM_13_DP")
	)
	(segment
		(start 154.145488 -50.790602)
		(end 151.728932 -38.706552)
		(width 0.1397)
		(layer "In5.Cu")
		(net "PCIE_COMP_TO_IOM_13_DP")
	)
	(segment
		(start 175.21047 -86.719918)
		(end 175.001682 -86.860126)
		(width 0.1397)
		(layer "In5.Cu")
		(net "PCIE_COMP_TO_IOM_13_DP")
	)
	(segment
		(start 150.73503 -34.64433)
		(end 150.87473 -34.435034)
		(width 0.1397)
		(layer "In5.Cu")
		(net "PCIE_COMP_TO_IOM_13_DP")
	)
	(segment
		(start 131.860798 -33.738058)
		(end 132.084064 -33.738058)
		(width 0.1397)
		(layer "In5.Cu")
		(net "PCIE_COMP_TO_IOM_13_DP")
	)
	(segment
		(start 151.108664 -35.60572)
		(end 151.026622 -35.194748)
		(width 0.1397)
		(layer "In5.Cu")
		(net "PCIE_COMP_TO_IOM_13_DP")
	)
	(segment
		(start 176.381664 -86.950296)
		(end 176.172876 -87.090504)
		(width 0.1397)
		(layer "In5.Cu")
		(net "PCIE_COMP_TO_IOM_13_DP")
	)
	(segment
		(start 154.088338 -51.41087)
		(end 154.006042 -50.999898)
		(width 0.1397)
		(layer "In5.Cu")
		(net "PCIE_COMP_TO_IOM_13_DP")
	)
	(segment
		(start 174.450248 -86.570566)
		(end 169.892472 -85.673946)
		(width 0.1397)
		(layer "In5.Cu")
		(net "PCIE_COMP_TO_IOM_13_DP")
	)
	(segment
		(start 144.544542 -25.902158)
		(end 135.170164 -25.902158)
		(width 0.1397)
		(layer "In5.Cu")
		(net "PCIE_COMP_TO_IOM_13_DP")
	)
	(segment
		(start 194.67449 -84.052918)
		(end 195.350638 -84.729066)
		(width 0.1397)
		(layer "In5.Cu")
		(net "PCIE_COMP_TO_IOM_13_DP")
	)
	(segment
		(start 150.969218 -35.814762)
		(end 151.108664 -35.60572)
		(width 0.1397)
		(layer "In5.Cu")
		(net "PCIE_COMP_TO_IOM_13_DP")
	)
	(segment
		(start 153.54427 -63.16091)
		(end 155.081986 -55.473092)
		(width 0.1397)
		(layer "In5.Cu")
		(net "PCIE_COMP_TO_IOM_13_DP")
	)
	(segment
		(start 151.051514 -36.225734)
		(end 150.969218 -35.814762)
		(width 0.1397)
		(layer "In5.Cu")
		(net "PCIE_COMP_TO_IOM_13_DP")
	)
	(segment
		(start 154.322272 -52.581302)
		(end 154.24023 -52.17033)
		(width 0.1397)
		(layer "In5.Cu")
		(net "PCIE_COMP_TO_IOM_13_DP")
	)
	(segment
		(start 189.973966 -89.6239)
		(end 176.381664 -86.950296)
		(width 0.1397)
		(layer "In5.Cu")
		(net "PCIE_COMP_TO_IOM_13_DP")
	)
	(segment
		(start 155.600146 -73.437496)
		(end 153.54427 -63.16091)
		(width 0.1397)
		(layer "In5.Cu")
		(net "PCIE_COMP_TO_IOM_13_DP")
	)
	(segment
		(start 169.892472 -85.673946)
		(end 158.851092 -78.31328)
		(width 0.1397)
		(layer "In5.Cu")
		(net "PCIE_COMP_TO_IOM_13_DP")
	)
	(segment
		(start 154.708352 -54.511702)
		(end 154.847798 -54.302406)
		(width 0.1397)
		(layer "In5.Cu")
		(net "PCIE_COMP_TO_IOM_13_DP")
	)
	(segment
		(start 151.43734 -38.156134)
		(end 151.57704 -37.946838)
		(width 0.1397)
		(layer "In5.Cu")
		(net "PCIE_COMP_TO_IOM_13_DP")
	)
	(segment
		(start 195.350638 -86.208362)
		(end 191.9351 -89.6239)
		(width 0.1397)
		(layer "In5.Cu")
		(net "PCIE_COMP_TO_IOM_13_DP")
	)
	(segment
		(start 150.817326 -35.055302)
		(end 150.73503 -34.64433)
		(width 0.1397)
		(layer "In5.Cu")
		(net "PCIE_COMP_TO_IOM_13_DP")
	)
	(segment
		(start 154.29738 -51.550316)
		(end 154.088338 -51.41087)
		(width 0.1397)
		(layer "In5.Cu")
		(net "PCIE_COMP_TO_IOM_13_DP")
	)
	(segment
		(start 154.006042 -50.999898)
		(end 154.145488 -50.790602)
		(width 0.1397)
		(layer "In5.Cu")
		(net "PCIE_COMP_TO_IOM_13_DP")
	)
	(segment
		(start 191.9351 -89.6239)
		(end 189.973966 -89.6239)
		(width 0.1397)
		(layer "In5.Cu")
		(net "PCIE_COMP_TO_IOM_13_DP")
	)
	(segment
		(start 150.792434 -34.024062)
		(end 147.04441 -28.402026)
		(width 0.1397)
		(layer "In5.Cu")
		(net "PCIE_COMP_TO_IOM_13_DP")
	)
	(segment
		(start 151.342852 -36.776152)
		(end 151.260556 -36.36518)
		(width 0.1397)
		(layer "In5.Cu")
		(net "PCIE_COMP_TO_IOM_13_DP")
	)
	(segment
		(start 175.76165 -87.009732)
		(end 175.621696 -86.800944)
		(width 0.1397)
		(layer "In5.Cu")
		(net "PCIE_COMP_TO_IOM_13_DP")
	)
	(segment
		(start 151.260556 -36.36518)
		(end 151.051514 -36.225734)
		(width 0.1397)
		(layer "In5.Cu")
		(net "PCIE_COMP_TO_IOM_13_DP")
	)
	(segment
		(start 175.621696 -86.800944)
		(end 175.21047 -86.719918)
		(width 0.1397)
		(layer "In5.Cu")
		(net "PCIE_COMP_TO_IOM_13_DP")
	)
	(segment
		(start 151.728932 -38.706552)
		(end 151.519636 -38.567106)
		(width 0.1397)
		(layer "In5.Cu")
		(net "PCIE_COMP_TO_IOM_13_DP")
	)
	(segment
		(start 151.57704 -37.946838)
		(end 151.494744 -37.535866)
		(width 0.1397)
		(layer "In5.Cu")
		(net "PCIE_COMP_TO_IOM_13_DP")
	)
	(segment
		(start 154.847798 -54.302406)
		(end 154.765756 -53.891434)
		(width 0.1397)
		(layer "In5.Cu")
		(net "PCIE_COMP_TO_IOM_13_DP")
	)
	(segment
		(start 176.172876 -87.090504)
		(end 175.76165 -87.009732)
		(width 0.1397)
		(layer "In5.Cu")
		(net "PCIE_COMP_TO_IOM_13_DP")
	)
	(segment
		(start 158.851092 -78.31328)
		(end 155.600146 -73.437496)
		(width 0.1397)
		(layer "In5.Cu")
		(net "PCIE_COMP_TO_IOM_13_DP")
	)
	(segment
		(start 151.494744 -37.535866)
		(end 151.285448 -37.39642)
		(width 0.1397)
		(layer "In5.Cu")
		(net "PCIE_COMP_TO_IOM_13_DP")
	)
	(segment
		(start 154.613864 -53.131974)
		(end 154.531568 -52.721002)
		(width 0.1397)
		(layer "In5.Cu")
		(net "PCIE_COMP_TO_IOM_13_DP")
	)
	(segment
		(start 154.99969 -55.06212)
		(end 154.790648 -54.922674)
		(width 0.1397)
		(layer "In5.Cu")
		(net "PCIE_COMP_TO_IOM_13_DP")
	)
	(segment
		(start 195.350638 -84.729066)
		(end 195.350638 -86.208362)
		(width 0.1397)
		(layer "In5.Cu")
		(net "PCIE_COMP_TO_IOM_13_DP")
	)
	(segment
		(start 132.299964 -33.522158)
		(end 132.299964 -33.200086)
		(width 0.1397)
		(layer "In5.Cu")
		(net "PCIE_COMP_TO_IOM_13_DP")
	)
	(segment
		(start 154.790648 -54.922674)
		(end 154.708352 -54.511702)
		(width 0.1397)
		(layer "In5.Cu")
		(net "PCIE_COMP_TO_IOM_13_DP")
	)
	(segment
		(start 175.001682 -86.860126)
		(end 174.590456 -86.779354)
		(width 0.1397)
		(layer "In5.Cu")
		(net "PCIE_COMP_TO_IOM_13_DP")
	)
	(segment
		(start 147.04441 -28.402026)
		(end 144.544542 -25.902158)
		(width 0.1397)
		(layer "In5.Cu")
		(net "PCIE_COMP_TO_IOM_13_DP")
	)
	(segment
		(start 154.379676 -51.961288)
		(end 154.29738 -51.550316)
		(width 0.1397)
		(layer "In5.Cu")
		(net "PCIE_COMP_TO_IOM_13_DP")
	)
	(segment
		(start 151.519636 -38.567106)
		(end 151.43734 -38.156134)
		(width 0.1397)
		(layer "In5.Cu")
		(net "PCIE_COMP_TO_IOM_13_DP")
	)
	(segment
		(start 151.285448 -37.39642)
		(end 151.203406 -36.985448)
		(width 0.1397)
		(layer "In5.Cu")
		(net "PCIE_COMP_TO_IOM_13_DP")
	)
	(segment
		(start 154.55646 -53.751988)
		(end 154.474418 -53.341016)
		(width 0.1397)
		(layer "In5.Cu")
		(net "PCIE_COMP_TO_IOM_13_DP")
	)
	(segment
		(start 154.474418 -53.341016)
		(end 154.613864 -53.131974)
		(width 0.1397)
		(layer "In5.Cu")
		(net "PCIE_COMP_TO_IOM_13_DP")
	)
	(segment
		(start 131.565142 -29.50718)
		(end 131.565142 -33.442402)
		(width 0.1397)
		(layer "In5.Cu")
		(net "PCIE_COMP_TO_IOM_13_DP")
	)
	(segment
		(start 151.203406 -36.985448)
		(end 151.342852 -36.776152)
		(width 0.1397)
		(layer "In5.Cu")
		(net "PCIE_COMP_TO_IOM_13_DP")
	)
	(segment
		(start 150.87473 -34.435034)
		(end 150.792434 -34.024062)
		(width 0.1397)
		(layer "In5.Cu")
		(net "PCIE_COMP_TO_IOM_13_DP")
	)
	(segment
		(start 174.590456 -86.779354)
		(end 174.450248 -86.570566)
		(width 0.1397)
		(layer "In5.Cu")
		(net "PCIE_COMP_TO_IOM_13_DP")
	)
	(segment
		(start 135.170164 -25.902158)
		(end 131.565142 -29.50718)
		(width 0.1397)
		(layer "In5.Cu")
		(net "PCIE_COMP_TO_IOM_13_DP")
	)
	(segment
		(start 155.081986 -55.473092)
		(end 154.99969 -55.06212)
		(width 0.1397)
		(layer "In5.Cu")
		(net "PCIE_COMP_TO_IOM_13_DP")
	)
	(segment
		(start 154.531568 -52.721002)
		(end 154.322272 -52.581302)
		(width 0.1397)
		(layer "In5.Cu")
		(net "PCIE_COMP_TO_IOM_13_DP")
	)
	(arc
		(start 132.084064 -33.738058)
		(mid 132.236728 -33.674822)
		(end 132.299964 -33.522158)
		(width 0.1397)
		(layer "In5.Cu")
		(net "PCIE_COMP_TO_IOM_13_DP")
	)
	(arc
		(start 194.674998 -83.658202)
		(mid 194.593219 -83.855455)
		(end 194.67449 -84.052918)
		(width 0.1397)
		(layer "In5.Cu")
		(net "PCIE_COMP_TO_IOM_13_DP")
	)
	(arc
		(start 131.565142 -33.442402)
		(mid 131.651738 -33.651462)
		(end 131.860798 -33.738058)
		(width 0.1397)
		(layer "In5.Cu")
		(net "PCIE_COMP_TO_IOM_13_DP")
	)
	(segment
		(start 193.561208 -78.793086)
		(end 193.23685 -79.117444)
		(width 0.14605)
		(layer "F.Cu")
		(net "PCIE_COMP_TO_IOM_13_DN")
	)
	(segment
		(start 193.936874 -75.900026)
		(end 193.561208 -76.275692)
		(width 0.14605)
		(layer "F.Cu")
		(net "PCIE_COMP_TO_IOM_13_DN")
	)
	(segment
		(start 193.999866 -75.900026)
		(end 193.936874 -75.900026)
		(width 0.14605)
		(layer "F.Cu")
		(net "PCIE_COMP_TO_IOM_13_DN")
	)
	(segment
		(start 193.23685 -79.117444)
		(end 193.23685 -83.068922)
		(width 0.14605)
		(layer "F.Cu")
		(net "PCIE_COMP_TO_IOM_13_DN")
	)
	(segment
		(start 194.047364 -84.285836)
		(end 194.046602 -84.286598)
		(width 0.14605)
		(layer "F.Cu")
		(net "PCIE_COMP_TO_IOM_13_DN")
	)
	(segment
		(start 193.23685 -83.068922)
		(end 193.279522 -83.11134)
		(width 0.14605)
		(layer "F.Cu")
		(net "PCIE_COMP_TO_IOM_13_DN")
	)
	(segment
		(start 193.561208 -76.275692)
		(end 193.561208 -78.793086)
		(width 0.14605)
		(layer "F.Cu")
		(net "PCIE_COMP_TO_IOM_13_DN")
	)
	(segment
		(start 193.279522 -83.11134)
		(end 194.047364 -83.879182)
		(width 0.14605)
		(layer "F.Cu")
		(net "PCIE_COMP_TO_IOM_13_DN")
	)
	(arc
		(start 194.047364 -83.879182)
		(mid 194.131712 -84.082546)
		(end 194.047364 -84.285836)
		(width 0.14605)
		(layer "F.Cu")
		(net "PCIE_COMP_TO_IOM_13_DN")
	)
	(segment
		(start 190.006224 -89.2937)
		(end 170.020742 -85.362542)
		(width 0.1397)
		(layer "In5.Cu")
		(net "PCIE_COMP_TO_IOM_13_DN")
	)
	(segment
		(start 159.089344 -78.075028)
		(end 157.50032 -75.691746)
		(width 0.1397)
		(layer "In5.Cu")
		(net "PCIE_COMP_TO_IOM_13_DN")
	)
	(segment
		(start 170.020742 -85.362542)
		(end 159.089344 -78.075028)
		(width 0.1397)
		(layer "In5.Cu")
		(net "PCIE_COMP_TO_IOM_13_DN")
	)
	(segment
		(start 194.650106 -84.49564)
		(end 195.020438 -84.865972)
		(width 0.1397)
		(layer "In5.Cu")
		(net "PCIE_COMP_TO_IOM_13_DN")
	)
	(segment
		(start 131.860798 -34.068258)
		(end 132.084064 -34.068258)
		(width 0.1397)
		(layer "In5.Cu")
		(net "PCIE_COMP_TO_IOM_13_DN")
	)
	(segment
		(start 147.301204 -28.19146)
		(end 144.681448 -25.571958)
		(width 0.1397)
		(layer "In5.Cu")
		(net "PCIE_COMP_TO_IOM_13_DN")
	)
	(segment
		(start 135.033258 -25.571958)
		(end 131.234942 -29.370274)
		(width 0.1397)
		(layer "In5.Cu")
		(net "PCIE_COMP_TO_IOM_13_DN")
	)
	(segment
		(start 191.798194 -89.2937)
		(end 190.006224 -89.2937)
		(width 0.1397)
		(layer "In5.Cu")
		(net "PCIE_COMP_TO_IOM_13_DN")
	)
	(segment
		(start 194.44081 -84.286598)
		(end 194.650106 -84.495894)
		(width 0.1397)
		(layer "In5.Cu")
		(net "PCIE_COMP_TO_IOM_13_DN")
	)
	(segment
		(start 144.681448 -25.571958)
		(end 135.033258 -25.571958)
		(width 0.1397)
		(layer "In5.Cu")
		(net "PCIE_COMP_TO_IOM_13_DN")
	)
	(segment
		(start 131.234942 -29.370274)
		(end 131.234942 -33.442402)
		(width 0.1397)
		(layer "In5.Cu")
		(net "PCIE_COMP_TO_IOM_13_DN")
	)
	(segment
		(start 195.020438 -86.071456)
		(end 191.798194 -89.2937)
		(width 0.1397)
		(layer "In5.Cu")
		(net "PCIE_COMP_TO_IOM_13_DN")
	)
	(segment
		(start 132.299964 -34.284158)
		(end 132.299964 -34.600134)
		(width 0.1397)
		(layer "In5.Cu")
		(net "PCIE_COMP_TO_IOM_13_DN")
	)
	(segment
		(start 157.500066 -75.691746)
		(end 155.911296 -73.308464)
		(width 0.1397)
		(layer "In5.Cu")
		(net "PCIE_COMP_TO_IOM_13_DN")
	)
	(segment
		(start 157.50032 -75.691746)
		(end 157.500066 -75.691746)
		(width 0.1397)
		(layer "In5.Cu")
		(net "PCIE_COMP_TO_IOM_13_DN")
	)
	(segment
		(start 195.020438 -84.865972)
		(end 195.020438 -86.071456)
		(width 0.1397)
		(layer "In5.Cu")
		(net "PCIE_COMP_TO_IOM_13_DN")
	)
	(segment
		(start 194.650106 -84.495894)
		(end 194.650106 -84.49564)
		(width 0.1397)
		(layer "In5.Cu")
		(net "PCIE_COMP_TO_IOM_13_DN")
	)
	(segment
		(start 151.103584 -33.89503)
		(end 147.301204 -28.19146)
		(width 0.1397)
		(layer "In5.Cu")
		(net "PCIE_COMP_TO_IOM_13_DN")
	)
	(segment
		(start 155.41879 -55.473092)
		(end 151.103584 -33.89503)
		(width 0.1397)
		(layer "In5.Cu")
		(net "PCIE_COMP_TO_IOM_13_DN")
	)
	(segment
		(start 153.881074 -63.16091)
		(end 155.41879 -55.473092)
		(width 0.1397)
		(layer "In5.Cu")
		(net "PCIE_COMP_TO_IOM_13_DN")
	)
	(segment
		(start 155.911296 -73.308464)
		(end 153.881074 -63.16091)
		(width 0.1397)
		(layer "In5.Cu")
		(net "PCIE_COMP_TO_IOM_13_DN")
	)
	(arc
		(start 132.084064 -34.068258)
		(mid 132.236728 -34.131494)
		(end 132.299964 -34.284158)
		(width 0.1397)
		(layer "In5.Cu")
		(net "PCIE_COMP_TO_IOM_13_DN")
	)
	(arc
		(start 194.046602 -84.286598)
		(mid 194.243706 -84.20488)
		(end 194.44081 -84.286598)
		(width 0.1397)
		(layer "In5.Cu")
		(net "PCIE_COMP_TO_IOM_13_DN")
	)
	(arc
		(start 131.234942 -33.442402)
		(mid 131.418251 -33.884949)
		(end 131.860798 -34.068258)
		(width 0.1397)
		(layer "In5.Cu")
		(net "PCIE_COMP_TO_IOM_13_DN")
	)
	(segment
		(start 196.22135 -83.81365)
		(end 196.22135 -81.120488)
		(width 0.14605)
		(layer "F.Cu")
		(net "PCIE_COMP_TO_IOM_12_DP")
	)
	(segment
		(start 194.703446 -76.796392)
		(end 194.799966 -76.699872)
		(width 0.14605)
		(layer "F.Cu")
		(net "PCIE_COMP_TO_IOM_12_DP")
	)
	(segment
		(start 193.3702 -87.710264)
		(end 193.3702 -86.6648)
		(width 0.14605)
		(layer "F.Cu")
		(net "PCIE_COMP_TO_IOM_12_DP")
	)
	(segment
		(start 196.22135 -81.120488)
		(end 194.703446 -79.602584)
		(width 0.14605)
		(layer "F.Cu")
		(net "PCIE_COMP_TO_IOM_12_DP")
	)
	(segment
		(start 194.703446 -79.602584)
		(end 194.703446 -76.796392)
		(width 0.14605)
		(layer "F.Cu")
		(net "PCIE_COMP_TO_IOM_12_DP")
	)
	(segment
		(start 194.042538 -88.382602)
		(end 193.3702 -87.710264)
		(width 0.14605)
		(layer "F.Cu")
		(net "PCIE_COMP_TO_IOM_12_DP")
	)
	(segment
		(start 193.3702 -86.6648)
		(end 196.22135 -83.81365)
		(width 0.14605)
		(layer "F.Cu")
		(net "PCIE_COMP_TO_IOM_12_DP")
	)
	(arc
		(start 194.45097 -88.382602)
		(mid 194.246754 -88.467191)
		(end 194.042538 -88.382602)
		(width 0.14605)
		(layer "F.Cu")
		(net "PCIE_COMP_TO_IOM_12_DP")
	)
	(segment
		(start 173.570392 -87.758524)
		(end 172.550582 -87.070692)
		(width 0.1397)
		(layer "In5.Cu")
		(net "PCIE_COMP_TO_IOM_12_DP")
	)
	(segment
		(start 153.795984 -54.215538)
		(end 153.586942 -54.076092)
		(width 0.1397)
		(layer "In5.Cu")
		(net "PCIE_COMP_TO_IOM_12_DP")
	)
	(segment
		(start 150.493984 -37.707824)
		(end 150.284688 -37.568378)
		(width 0.1397)
		(layer "In5.Cu")
		(net "PCIE_COMP_TO_IOM_12_DP")
	)
	(segment
		(start 176.271682 -89.58072)
		(end 175.202342 -88.85936)
		(width 0.1397)
		(layer "In5.Cu")
		(net "PCIE_COMP_TO_IOM_12_DP")
	)
	(segment
		(start 134.100062 -32.322008)
		(end 134.100062 -32.00019)
		(width 0.1397)
		(layer "In5.Cu")
		(net "PCIE_COMP_TO_IOM_12_DP")
	)
	(segment
		(start 153.409904 -52.285392)
		(end 153.327862 -51.87442)
		(width 0.1397)
		(layer "In5.Cu")
		(net "PCIE_COMP_TO_IOM_12_DP")
	)
	(segment
		(start 153.03627 -51.324002)
		(end 153.175716 -51.114706)
		(width 0.1397)
		(layer "In5.Cu")
		(net "PCIE_COMP_TO_IOM_12_DP")
	)
	(segment
		(start 150.107904 -35.777678)
		(end 150.025608 -35.366706)
		(width 0.1397)
		(layer "In5.Cu")
		(net "PCIE_COMP_TO_IOM_12_DP")
	)
	(segment
		(start 173.965616 -88.2396)
		(end 173.618144 -88.005412)
		(width 0.1397)
		(layer "In5.Cu")
		(net "PCIE_COMP_TO_IOM_12_DP")
	)
	(segment
		(start 153.56205 -53.045106)
		(end 153.352754 -52.90566)
		(width 0.1397)
		(layer "In5.Cu")
		(net "PCIE_COMP_TO_IOM_12_DP")
	)
	(segment
		(start 174.212504 -88.191848)
		(end 173.965616 -88.2396)
		(width 0.1397)
		(layer "In5.Cu")
		(net "PCIE_COMP_TO_IOM_12_DP")
	)
	(segment
		(start 194.7672 -89.738708)
		(end 194.085718 -90.42019)
		(width 0.1397)
		(layer "In5.Cu")
		(net "PCIE_COMP_TO_IOM_12_DP")
	)
	(segment
		(start 149.873716 -34.606992)
		(end 149.79142 -34.19602)
		(width 0.1397)
		(layer "In5.Cu")
		(net "PCIE_COMP_TO_IOM_12_DP")
	)
	(segment
		(start 190.55461 -91.149932)
		(end 186.1693 -90.27287)
		(width 0.1397)
		(layer "In5.Cu")
		(net "PCIE_COMP_TO_IOM_12_DP")
	)
	(segment
		(start 174.607982 -88.672924)
		(end 174.559976 -88.426036)
		(width 0.1397)
		(layer "In5.Cu")
		(net "PCIE_COMP_TO_IOM_12_DP")
	)
	(segment
		(start 133.36524 -29.087572)
		(end 133.36524 -32.242252)
		(width 0.1397)
		(layer "In5.Cu")
		(net "PCIE_COMP_TO_IOM_12_DP")
	)
	(segment
		(start 153.738834 -54.835806)
		(end 153.87828 -54.62651)
		(width 0.1397)
		(layer "In5.Cu")
		(net "PCIE_COMP_TO_IOM_12_DP")
	)
	(segment
		(start 150.202392 -37.157406)
		(end 150.341838 -36.94811)
		(width 0.1397)
		(layer "In5.Cu")
		(net "PCIE_COMP_TO_IOM_12_DP")
	)
	(segment
		(start 150.025608 -35.366706)
		(end 149.816312 -35.22726)
		(width 0.1397)
		(layer "In5.Cu")
		(net "PCIE_COMP_TO_IOM_12_DP")
	)
	(segment
		(start 153.327862 -51.87442)
		(end 153.118566 -51.734974)
		(width 0.1397)
		(layer "In5.Cu")
		(net "PCIE_COMP_TO_IOM_12_DP")
	)
	(segment
		(start 169.658284 -86.50859)
		(end 157.938724 -78.695296)
		(width 0.1397)
		(layer "In5.Cu")
		(net "PCIE_COMP_TO_IOM_12_DP")
	)
	(segment
		(start 150.576026 -38.118796)
		(end 150.493984 -37.707824)
		(width 0.1397)
		(layer "In5.Cu")
		(net "PCIE_COMP_TO_IOM_12_DP")
	)
	(segment
		(start 173.618144 -88.005412)
		(end 173.570392 -87.758524)
		(width 0.1397)
		(layer "In5.Cu")
		(net "PCIE_COMP_TO_IOM_12_DP")
	)
	(segment
		(start 146.01317 -28.528518)
		(end 144.239742 -26.75509)
		(width 0.1397)
		(layer "In5.Cu")
		(net "PCIE_COMP_TO_IOM_12_DP")
	)
	(segment
		(start 154.737054 -73.892918)
		(end 152.615646 -63.280544)
		(width 0.1397)
		(layer "In5.Cu")
		(net "PCIE_COMP_TO_IOM_12_DP")
	)
	(segment
		(start 150.518876 -38.739064)
		(end 150.43658 -38.328092)
		(width 0.1397)
		(layer "In5.Cu")
		(net "PCIE_COMP_TO_IOM_12_DP")
	)
	(segment
		(start 150.0505 -36.397692)
		(end 149.968204 -35.98672)
		(width 0.1397)
		(layer "In5.Cu")
		(net "PCIE_COMP_TO_IOM_12_DP")
	)
	(segment
		(start 154.030172 -55.386224)
		(end 153.82113 -55.246778)
		(width 0.1397)
		(layer "In5.Cu")
		(net "PCIE_COMP_TO_IOM_12_DP")
	)
	(segment
		(start 154.112468 -55.797196)
		(end 154.030172 -55.386224)
		(width 0.1397)
		(layer "In5.Cu")
		(net "PCIE_COMP_TO_IOM_12_DP")
	)
	(segment
		(start 157.938724 -78.695296)
		(end 154.737054 -73.892918)
		(width 0.1397)
		(layer "In5.Cu")
		(net "PCIE_COMP_TO_IOM_12_DP")
	)
	(segment
		(start 149.79142 -34.19602)
		(end 146.01317 -28.528518)
		(width 0.1397)
		(layer "In5.Cu")
		(net "PCIE_COMP_TO_IOM_12_DP")
	)
	(segment
		(start 153.586942 -54.076092)
		(end 153.504646 -53.66512)
		(width 0.1397)
		(layer "In5.Cu")
		(net "PCIE_COMP_TO_IOM_12_DP")
	)
	(segment
		(start 153.82113 -55.246778)
		(end 153.738834 -54.835806)
		(width 0.1397)
		(layer "In5.Cu")
		(net "PCIE_COMP_TO_IOM_12_DP")
	)
	(segment
		(start 153.87828 -54.62651)
		(end 153.795984 -54.215538)
		(width 0.1397)
		(layer "In5.Cu")
		(net "PCIE_COMP_TO_IOM_12_DP")
	)
	(segment
		(start 175.202342 -88.85936)
		(end 174.955454 -88.907366)
		(width 0.1397)
		(layer "In5.Cu")
		(net "PCIE_COMP_TO_IOM_12_DP")
	)
	(segment
		(start 150.259796 -36.537138)
		(end 150.0505 -36.397692)
		(width 0.1397)
		(layer "In5.Cu")
		(net "PCIE_COMP_TO_IOM_12_DP")
	)
	(segment
		(start 153.270458 -52.494688)
		(end 153.409904 -52.285392)
		(width 0.1397)
		(layer "In5.Cu")
		(net "PCIE_COMP_TO_IOM_12_DP")
	)
	(segment
		(start 194.085718 -90.42019)
		(end 194.055746 -90.449908)
		(width 0.1397)
		(layer "In5.Cu")
		(net "PCIE_COMP_TO_IOM_12_DP")
	)
	(segment
		(start 153.504646 -53.66512)
		(end 153.644092 -53.456078)
		(width 0.1397)
		(layer "In5.Cu")
		(net "PCIE_COMP_TO_IOM_12_DP")
	)
	(segment
		(start 144.239742 -26.75509)
		(end 135.697722 -26.75509)
		(width 0.1397)
		(layer "In5.Cu")
		(net "PCIE_COMP_TO_IOM_12_DP")
	)
	(segment
		(start 194.7672 -89.09304)
		(end 194.7672 -89.738708)
		(width 0.1397)
		(layer "In5.Cu")
		(net "PCIE_COMP_TO_IOM_12_DP")
	)
	(segment
		(start 194.055746 -90.449908)
		(end 190.55461 -91.149932)
		(width 0.1397)
		(layer "In5.Cu")
		(net "PCIE_COMP_TO_IOM_12_DP")
	)
	(segment
		(start 174.955454 -88.907366)
		(end 174.607982 -88.672924)
		(width 0.1397)
		(layer "In5.Cu")
		(net "PCIE_COMP_TO_IOM_12_DP")
	)
	(segment
		(start 153.644092 -53.456078)
		(end 153.56205 -53.045106)
		(width 0.1397)
		(layer "In5.Cu")
		(net "PCIE_COMP_TO_IOM_12_DP")
	)
	(segment
		(start 172.550582 -87.070692)
		(end 169.658284 -86.50859)
		(width 0.1397)
		(layer "In5.Cu")
		(net "PCIE_COMP_TO_IOM_12_DP")
	)
	(segment
		(start 149.816312 -35.22726)
		(end 149.73427 -34.816288)
		(width 0.1397)
		(layer "In5.Cu")
		(net "PCIE_COMP_TO_IOM_12_DP")
	)
	(segment
		(start 174.559976 -88.426036)
		(end 174.212504 -88.191848)
		(width 0.1397)
		(layer "In5.Cu")
		(net "PCIE_COMP_TO_IOM_12_DP")
	)
	(segment
		(start 186.1693 -90.27287)
		(end 183.000396 -90.906854)
		(width 0.1397)
		(layer "In5.Cu")
		(net "PCIE_COMP_TO_IOM_12_DP")
	)
	(segment
		(start 152.615646 -63.280544)
		(end 154.112468 -55.797196)
		(width 0.1397)
		(layer "In5.Cu")
		(net "PCIE_COMP_TO_IOM_12_DP")
	)
	(segment
		(start 183.000396 -90.906854)
		(end 176.271682 -89.58072)
		(width 0.1397)
		(layer "In5.Cu")
		(net "PCIE_COMP_TO_IOM_12_DP")
	)
	(segment
		(start 153.118566 -51.734974)
		(end 153.03627 -51.324002)
		(width 0.1397)
		(layer "In5.Cu")
		(net "PCIE_COMP_TO_IOM_12_DP")
	)
	(segment
		(start 150.43658 -38.328092)
		(end 150.576026 -38.118796)
		(width 0.1397)
		(layer "In5.Cu")
		(net "PCIE_COMP_TO_IOM_12_DP")
	)
	(segment
		(start 149.968204 -35.98672)
		(end 150.107904 -35.777678)
		(width 0.1397)
		(layer "In5.Cu")
		(net "PCIE_COMP_TO_IOM_12_DP")
	)
	(segment
		(start 150.284688 -37.568378)
		(end 150.202392 -37.157406)
		(width 0.1397)
		(layer "In5.Cu")
		(net "PCIE_COMP_TO_IOM_12_DP")
	)
	(segment
		(start 135.697722 -26.75509)
		(end 133.36524 -29.087572)
		(width 0.1397)
		(layer "In5.Cu")
		(net "PCIE_COMP_TO_IOM_12_DP")
	)
	(segment
		(start 150.341838 -36.94811)
		(end 150.259796 -36.537138)
		(width 0.1397)
		(layer "In5.Cu")
		(net "PCIE_COMP_TO_IOM_12_DP")
	)
	(segment
		(start 149.73427 -34.816288)
		(end 149.873716 -34.606992)
		(width 0.1397)
		(layer "In5.Cu")
		(net "PCIE_COMP_TO_IOM_12_DP")
	)
	(segment
		(start 153.352754 -52.90566)
		(end 153.270458 -52.494688)
		(width 0.1397)
		(layer "In5.Cu")
		(net "PCIE_COMP_TO_IOM_12_DP")
	)
	(segment
		(start 150.728172 -38.87851)
		(end 150.518876 -38.739064)
		(width 0.1397)
		(layer "In5.Cu")
		(net "PCIE_COMP_TO_IOM_12_DP")
	)
	(segment
		(start 194.45097 -88.77681)
		(end 194.7672 -89.09304)
		(width 0.1397)
		(layer "In5.Cu")
		(net "PCIE_COMP_TO_IOM_12_DP")
	)
	(segment
		(start 153.175716 -51.114706)
		(end 150.728172 -38.87851)
		(width 0.1397)
		(layer "In5.Cu")
		(net "PCIE_COMP_TO_IOM_12_DP")
	)
	(segment
		(start 133.660896 -32.537908)
		(end 133.884162 -32.537908)
		(width 0.1397)
		(layer "In5.Cu")
		(net "PCIE_COMP_TO_IOM_12_DP")
	)
	(arc
		(start 133.884162 -32.537908)
		(mid 134.036826 -32.474672)
		(end 134.100062 -32.322008)
		(width 0.1397)
		(layer "In5.Cu")
		(net "PCIE_COMP_TO_IOM_12_DP")
	)
	(arc
		(start 133.36524 -32.242252)
		(mid 133.451836 -32.451312)
		(end 133.660896 -32.537908)
		(width 0.1397)
		(layer "In5.Cu")
		(net "PCIE_COMP_TO_IOM_12_DP")
	)
	(arc
		(start 194.45097 -88.382602)
		(mid 194.369327 -88.579706)
		(end 194.45097 -88.77681)
		(width 0.1397)
		(layer "In5.Cu")
		(net "PCIE_COMP_TO_IOM_12_DP")
	)
	(segment
		(start 195.9102 -83.684618)
		(end 193.05905 -86.535768)
		(width 0.14605)
		(layer "F.Cu")
		(net "PCIE_COMP_TO_IOM_12_DN")
	)
	(segment
		(start 194.392296 -76.270104)
		(end 194.392296 -79.731616)
		(width 0.14605)
		(layer "F.Cu")
		(net "PCIE_COMP_TO_IOM_12_DN")
	)
	(segment
		(start 194.762374 -75.900026)
		(end 194.392296 -76.270104)
		(width 0.14605)
		(layer "F.Cu")
		(net "PCIE_COMP_TO_IOM_12_DN")
	)
	(segment
		(start 195.9102 -81.24952)
		(end 195.9102 -83.684618)
		(width 0.14605)
		(layer "F.Cu")
		(net "PCIE_COMP_TO_IOM_12_DN")
	)
	(segment
		(start 193.05905 -86.535768)
		(end 193.05905 -87.839296)
		(width 0.14605)
		(layer "F.Cu")
		(net "PCIE_COMP_TO_IOM_12_DN")
	)
	(segment
		(start 194.799966 -75.900026)
		(end 194.762374 -75.900026)
		(width 0.14605)
		(layer "F.Cu")
		(net "PCIE_COMP_TO_IOM_12_DN")
	)
	(segment
		(start 194.392296 -79.731616)
		(end 195.9102 -81.24952)
		(width 0.14605)
		(layer "F.Cu")
		(net "PCIE_COMP_TO_IOM_12_DN")
	)
	(segment
		(start 193.05905 -87.839296)
		(end 193.822574 -88.60282)
		(width 0.14605)
		(layer "F.Cu")
		(net "PCIE_COMP_TO_IOM_12_DN")
	)
	(arc
		(start 193.822574 -88.60282)
		(mid 193.907237 -88.806946)
		(end 193.822574 -89.010998)
		(width 0.14605)
		(layer "F.Cu")
		(net "PCIE_COMP_TO_IOM_12_DN")
	)
	(segment
		(start 158.176976 -78.457044)
		(end 155.048204 -73.76414)
		(width 0.1397)
		(layer "In5.Cu")
		(net "PCIE_COMP_TO_IOM_12_DN")
	)
	(segment
		(start 146.269964 -28.317952)
		(end 144.376648 -26.42489)
		(width 0.1397)
		(layer "In5.Cu")
		(net "PCIE_COMP_TO_IOM_12_DN")
	)
	(segment
		(start 172.679614 -86.759288)
		(end 169.7863 -86.196932)
		(width 0.1397)
		(layer "In5.Cu")
		(net "PCIE_COMP_TO_IOM_12_DN")
	)
	(segment
		(start 169.7863 -86.196932)
		(end 158.176976 -78.457044)
		(width 0.1397)
		(layer "In5.Cu")
		(net "PCIE_COMP_TO_IOM_12_DN")
	)
	(segment
		(start 186.1693 -89.936066)
		(end 182.999888 -90.57005)
		(width 0.1397)
		(layer "In5.Cu")
		(net "PCIE_COMP_TO_IOM_12_DN")
	)
	(segment
		(start 133.660896 -32.868108)
		(end 133.884162 -32.868108)
		(width 0.1397)
		(layer "In5.Cu")
		(net "PCIE_COMP_TO_IOM_12_DN")
	)
	(segment
		(start 194.217798 -89.010998)
		(end 194.436746 -89.229946)
		(width 0.1397)
		(layer "In5.Cu")
		(net "PCIE_COMP_TO_IOM_12_DN")
	)
	(segment
		(start 190.55461 -90.813128)
		(end 186.1693 -89.936066)
		(width 0.1397)
		(layer "In5.Cu")
		(net "PCIE_COMP_TO_IOM_12_DN")
	)
	(segment
		(start 144.376648 -26.42489)
		(end 135.560816 -26.42489)
		(width 0.1397)
		(layer "In5.Cu")
		(net "PCIE_COMP_TO_IOM_12_DN")
	)
	(segment
		(start 150.10257 -34.066988)
		(end 148.176996 -31.179008)
		(width 0.1397)
		(layer "In5.Cu")
		(net "PCIE_COMP_TO_IOM_12_DN")
	)
	(segment
		(start 193.892932 -90.145616)
		(end 190.55461 -90.813128)
		(width 0.1397)
		(layer "In5.Cu")
		(net "PCIE_COMP_TO_IOM_12_DN")
	)
	(segment
		(start 133.03504 -28.950666)
		(end 133.03504 -32.242252)
		(width 0.1397)
		(layer "In5.Cu")
		(net "PCIE_COMP_TO_IOM_12_DN")
	)
	(segment
		(start 194.436746 -89.229946)
		(end 194.437 -89.229946)
		(width 0.1397)
		(layer "In5.Cu")
		(net "PCIE_COMP_TO_IOM_12_DN")
	)
	(segment
		(start 193.893186 -90.145616)
		(end 193.892932 -90.145616)
		(width 0.1397)
		(layer "In5.Cu")
		(net "PCIE_COMP_TO_IOM_12_DN")
	)
	(segment
		(start 134.100062 -33.084008)
		(end 134.100062 -33.399984)
		(width 0.1397)
		(layer "In5.Cu")
		(net "PCIE_COMP_TO_IOM_12_DN")
	)
	(segment
		(start 155.048204 -73.76414)
		(end 152.95245 -63.280544)
		(width 0.1397)
		(layer "In5.Cu")
		(net "PCIE_COMP_TO_IOM_12_DN")
	)
	(segment
		(start 135.560816 -26.42489)
		(end 133.03504 -28.950666)
		(width 0.1397)
		(layer "In5.Cu")
		(net "PCIE_COMP_TO_IOM_12_DN")
	)
	(segment
		(start 148.176996 -31.178754)
		(end 146.269964 -28.317952)
		(width 0.1397)
		(layer "In5.Cu")
		(net "PCIE_COMP_TO_IOM_12_DN")
	)
	(segment
		(start 152.95245 -63.280544)
		(end 154.449272 -55.797196)
		(width 0.1397)
		(layer "In5.Cu")
		(net "PCIE_COMP_TO_IOM_12_DN")
	)
	(segment
		(start 154.449272 -55.797196)
		(end 150.10257 -34.066988)
		(width 0.1397)
		(layer "In5.Cu")
		(net "PCIE_COMP_TO_IOM_12_DN")
	)
	(segment
		(start 182.999888 -90.57005)
		(end 176.400968 -89.26957)
		(width 0.1397)
		(layer "In5.Cu")
		(net "PCIE_COMP_TO_IOM_12_DN")
	)
	(segment
		(start 148.176996 -31.179008)
		(end 148.176996 -31.178754)
		(width 0.1397)
		(layer "In5.Cu")
		(net "PCIE_COMP_TO_IOM_12_DN")
	)
	(segment
		(start 176.400968 -89.26957)
		(end 172.679614 -86.759288)
		(width 0.1397)
		(layer "In5.Cu")
		(net "PCIE_COMP_TO_IOM_12_DN")
	)
	(segment
		(start 194.437 -89.229946)
		(end 194.437 -89.601802)
		(width 0.1397)
		(layer "In5.Cu")
		(net "PCIE_COMP_TO_IOM_12_DN")
	)
	(segment
		(start 194.437 -89.601802)
		(end 193.893186 -90.145616)
		(width 0.1397)
		(layer "In5.Cu")
		(net "PCIE_COMP_TO_IOM_12_DN")
	)
	(arc
		(start 133.03504 -32.242252)
		(mid 133.218349 -32.684799)
		(end 133.660896 -32.868108)
		(width 0.1397)
		(layer "In5.Cu")
		(net "PCIE_COMP_TO_IOM_12_DN")
	)
	(arc
		(start 193.822574 -89.010998)
		(mid 194.020186 -88.929144)
		(end 194.217798 -89.010998)
		(width 0.1397)
		(layer "In5.Cu")
		(net "PCIE_COMP_TO_IOM_12_DN")
	)
	(arc
		(start 133.884162 -32.868108)
		(mid 134.036826 -32.931344)
		(end 134.100062 -33.084008)
		(width 0.1397)
		(layer "In5.Cu")
		(net "PCIE_COMP_TO_IOM_12_DN")
	)
	(segment
		(start 197.504304 -84.18195)
		(end 197.504304 -80.625442)
		(width 0.14605)
		(layer "F.Cu")
		(net "PCIE_COMP_TO_IOM_11_DP")
	)
	(segment
		(start 196.85 -84.836)
		(end 197.504304 -84.18195)
		(width 0.14605)
		(layer "F.Cu")
		(net "PCIE_COMP_TO_IOM_11_DP")
	)
	(segment
		(start 197.115938 -85.334602)
		(end 196.85 -85.068664)
		(width 0.14605)
		(layer "F.Cu")
		(net "PCIE_COMP_TO_IOM_11_DP")
	)
	(segment
		(start 196.329808 -79.450946)
		(end 196.329808 -76.769976)
		(width 0.14605)
		(layer "F.Cu")
		(net "PCIE_COMP_TO_IOM_11_DP")
	)
	(segment
		(start 197.504304 -80.625442)
		(end 196.329808 -79.450946)
		(width 0.14605)
		(layer "F.Cu")
		(net "PCIE_COMP_TO_IOM_11_DP")
	)
	(segment
		(start 196.85 -85.068664)
		(end 196.85 -84.836)
		(width 0.14605)
		(layer "F.Cu")
		(net "PCIE_COMP_TO_IOM_11_DP")
	)
	(segment
		(start 196.329808 -76.769976)
		(end 196.399912 -76.699872)
		(width 0.14605)
		(layer "F.Cu")
		(net "PCIE_COMP_TO_IOM_11_DP")
	)
	(arc
		(start 197.52437 -85.334602)
		(mid 197.320154 -85.419191)
		(end 197.115938 -85.334602)
		(width 0.14605)
		(layer "F.Cu")
		(net "PCIE_COMP_TO_IOM_11_DP")
	)
	(segment
		(start 152.224994 -51.474624)
		(end 152.085548 -51.68392)
		(width 0.1397)
		(layer "In5.Cu")
		(net "PCIE_COMP_TO_IOM_11_DP")
	)
	(segment
		(start 148.77415 -34.220404)
		(end 148.856446 -34.631376)
		(width 0.1397)
		(layer "In5.Cu")
		(net "PCIE_COMP_TO_IOM_11_DP")
	)
	(segment
		(start 170.12031 -87.493094)
		(end 171.05757 -87.674958)
		(width 0.1397)
		(layer "In5.Cu")
		(net "PCIE_COMP_TO_IOM_11_DP")
	)
	(segment
		(start 152.16759 -52.094892)
		(end 152.376886 -52.234338)
		(width 0.1397)
		(layer "In5.Cu")
		(net "PCIE_COMP_TO_IOM_11_DP")
	)
	(segment
		(start 149.47646 -37.732208)
		(end 149.558756 -38.14318)
		(width 0.1397)
		(layer "In5.Cu")
		(net "PCIE_COMP_TO_IOM_11_DP")
	)
	(segment
		(start 143.87195 -27.669236)
		(end 145.475452 -29.272738)
		(width 0.1397)
		(layer "In5.Cu")
		(net "PCIE_COMP_TO_IOM_11_DP")
	)
	(segment
		(start 136.99744 -27.669236)
		(end 143.87195 -27.669236)
		(width 0.1397)
		(layer "In5.Cu")
		(net "PCIE_COMP_TO_IOM_11_DP")
	)
	(segment
		(start 152.55367 -54.025038)
		(end 152.635966 -54.43601)
		(width 0.1397)
		(layer "In5.Cu")
		(net "PCIE_COMP_TO_IOM_11_DP")
	)
	(segment
		(start 170.12031 -87.49284)
		(end 170.12031 -87.493094)
		(width 0.1397)
		(layer "In5.Cu")
		(net "PCIE_COMP_TO_IOM_11_DP")
	)
	(segment
		(start 194.507612 -91.156282)
		(end 194.507612 -91.156536)
		(width 0.1397)
		(layer "In5.Cu")
		(net "PCIE_COMP_TO_IOM_11_DP")
	)
	(segment
		(start 172.35043 -88.761316)
		(end 172.597318 -88.713564)
		(width 0.1397)
		(layer "In5.Cu")
		(net "PCIE_COMP_TO_IOM_11_DP")
	)
	(segment
		(start 148.856446 -34.631376)
		(end 148.716746 -34.840672)
		(width 0.1397)
		(layer "In5.Cu")
		(net "PCIE_COMP_TO_IOM_11_DP")
	)
	(segment
		(start 152.459182 -52.64531)
		(end 152.319736 -52.854606)
		(width 0.1397)
		(layer "In5.Cu")
		(net "PCIE_COMP_TO_IOM_11_DP")
	)
	(segment
		(start 152.927304 -54.986428)
		(end 152.787858 -55.195724)
		(width 0.1397)
		(layer "In5.Cu")
		(net "PCIE_COMP_TO_IOM_11_DP")
	)
	(segment
		(start 169.182542 -87.310468)
		(end 170.12031 -87.49284)
		(width 0.1397)
		(layer "In5.Cu")
		(net "PCIE_COMP_TO_IOM_11_DP")
	)
	(segment
		(start 149.267418 -37.592762)
		(end 149.47646 -37.732208)
		(width 0.1397)
		(layer "In5.Cu")
		(net "PCIE_COMP_TO_IOM_11_DP")
	)
	(segment
		(start 152.693116 -53.815996)
		(end 152.55367 -54.025038)
		(width 0.1397)
		(layer "In5.Cu")
		(net "PCIE_COMP_TO_IOM_11_DP")
	)
	(segment
		(start 157.325314 -79.406242)
		(end 169.182542 -87.310468)
		(width 0.1397)
		(layer "In5.Cu")
		(net "PCIE_COMP_TO_IOM_11_DP")
	)
	(segment
		(start 171.05757 -87.674958)
		(end 171.954952 -88.28024)
		(width 0.1397)
		(layer "In5.Cu")
		(net "PCIE_COMP_TO_IOM_11_DP")
	)
	(segment
		(start 172.992542 -89.19464)
		(end 173.340014 -89.429082)
		(width 0.1397)
		(layer "In5.Cu")
		(net "PCIE_COMP_TO_IOM_11_DP")
	)
	(segment
		(start 173.586902 -89.381076)
		(end 174.645574 -90.09507)
		(width 0.1397)
		(layer "In5.Cu")
		(net "PCIE_COMP_TO_IOM_11_DP")
	)
	(segment
		(start 149.242526 -36.561522)
		(end 149.324568 -36.972494)
		(width 0.1397)
		(layer "In5.Cu")
		(net "PCIE_COMP_TO_IOM_11_DP")
	)
	(segment
		(start 152.376886 -52.234338)
		(end 152.459182 -52.64531)
		(width 0.1397)
		(layer "In5.Cu")
		(net "PCIE_COMP_TO_IOM_11_DP")
	)
	(segment
		(start 135.899906 -33.200086)
		(end 135.899906 -33.522158)
		(width 0.1397)
		(layer "In5.Cu")
		(net "PCIE_COMP_TO_IOM_11_DP")
	)
	(segment
		(start 194.47764 -91.186)
		(end 194.507612 -91.156282)
		(width 0.1397)
		(layer "In5.Cu")
		(net "PCIE_COMP_TO_IOM_11_DP")
	)
	(segment
		(start 173.340014 -89.429082)
		(end 173.586902 -89.381076)
		(width 0.1397)
		(layer "In5.Cu")
		(net "PCIE_COMP_TO_IOM_11_DP")
	)
	(segment
		(start 172.002958 -88.527128)
		(end 172.35043 -88.761316)
		(width 0.1397)
		(layer "In5.Cu")
		(net "PCIE_COMP_TO_IOM_11_DP")
	)
	(segment
		(start 153.161492 -56.157114)
		(end 151.705564 -63.437516)
		(width 0.1397)
		(layer "In5.Cu")
		(net "PCIE_COMP_TO_IOM_11_DP")
	)
	(segment
		(start 135.165084 -29.501592)
		(end 136.99744 -27.669236)
		(width 0.1397)
		(layer "In5.Cu")
		(net "PCIE_COMP_TO_IOM_11_DP")
	)
	(segment
		(start 172.94479 -88.947752)
		(end 172.992542 -89.19464)
		(width 0.1397)
		(layer "In5.Cu")
		(net "PCIE_COMP_TO_IOM_11_DP")
	)
	(segment
		(start 152.845262 -54.575456)
		(end 152.927304 -54.986428)
		(width 0.1397)
		(layer "In5.Cu")
		(net "PCIE_COMP_TO_IOM_11_DP")
	)
	(segment
		(start 135.165084 -33.442402)
		(end 135.165084 -29.501592)
		(width 0.1397)
		(layer "In5.Cu")
		(net "PCIE_COMP_TO_IOM_11_DP")
	)
	(segment
		(start 152.319736 -52.854606)
		(end 152.401778 -53.265324)
		(width 0.1397)
		(layer "In5.Cu")
		(net "PCIE_COMP_TO_IOM_11_DP")
	)
	(segment
		(start 149.558756 -38.14318)
		(end 149.41931 -38.352476)
		(width 0.1397)
		(layer "In5.Cu")
		(net "PCIE_COMP_TO_IOM_11_DP")
	)
	(segment
		(start 174.645574 -90.09507)
		(end 183.051704 -91.760294)
		(width 0.1397)
		(layer "In5.Cu")
		(net "PCIE_COMP_TO_IOM_11_DP")
	)
	(segment
		(start 194.507612 -91.156536)
		(end 198.12 -87.544402)
		(width 0.1397)
		(layer "In5.Cu")
		(net "PCIE_COMP_TO_IOM_11_DP")
	)
	(segment
		(start 148.716746 -34.840672)
		(end 148.799042 -35.251644)
		(width 0.1397)
		(layer "In5.Cu")
		(net "PCIE_COMP_TO_IOM_11_DP")
	)
	(segment
		(start 190.445644 -91.99245)
		(end 194.47764 -91.186)
		(width 0.1397)
		(layer "In5.Cu")
		(net "PCIE_COMP_TO_IOM_11_DP")
	)
	(segment
		(start 152.787858 -55.195724)
		(end 152.870154 -55.606696)
		(width 0.1397)
		(layer "In5.Cu")
		(net "PCIE_COMP_TO_IOM_11_DP")
	)
	(segment
		(start 149.710648 -38.902894)
		(end 152.224994 -51.474624)
		(width 0.1397)
		(layer "In5.Cu")
		(net "PCIE_COMP_TO_IOM_11_DP")
	)
	(segment
		(start 186.168792 -91.136724)
		(end 190.445644 -91.99245)
		(width 0.1397)
		(layer "In5.Cu")
		(net "PCIE_COMP_TO_IOM_11_DP")
	)
	(segment
		(start 149.03323 -36.422076)
		(end 149.242526 -36.561522)
		(width 0.1397)
		(layer "In5.Cu")
		(net "PCIE_COMP_TO_IOM_11_DP")
	)
	(segment
		(start 152.611074 -53.405024)
		(end 152.693116 -53.815996)
		(width 0.1397)
		(layer "In5.Cu")
		(net "PCIE_COMP_TO_IOM_11_DP")
	)
	(segment
		(start 145.475452 -29.272738)
		(end 148.77415 -34.220404)
		(width 0.1397)
		(layer "In5.Cu")
		(net "PCIE_COMP_TO_IOM_11_DP")
	)
	(segment
		(start 198.12 -87.544402)
		(end 198.12 -86.325456)
		(width 0.1397)
		(layer "In5.Cu")
		(net "PCIE_COMP_TO_IOM_11_DP")
	)
	(segment
		(start 172.597318 -88.713564)
		(end 172.94479 -88.947752)
		(width 0.1397)
		(layer "In5.Cu")
		(net "PCIE_COMP_TO_IOM_11_DP")
	)
	(segment
		(start 152.870154 -55.606696)
		(end 153.079196 -55.746142)
		(width 0.1397)
		(layer "In5.Cu")
		(net "PCIE_COMP_TO_IOM_11_DP")
	)
	(segment
		(start 171.954952 -88.28024)
		(end 172.002958 -88.527128)
		(width 0.1397)
		(layer "In5.Cu")
		(net "PCIE_COMP_TO_IOM_11_DP")
	)
	(segment
		(start 149.41931 -38.352476)
		(end 149.501352 -38.763448)
		(width 0.1397)
		(layer "In5.Cu")
		(net "PCIE_COMP_TO_IOM_11_DP")
	)
	(segment
		(start 153.858468 -74.205084)
		(end 157.325314 -79.406242)
		(width 0.1397)
		(layer "In5.Cu")
		(net "PCIE_COMP_TO_IOM_11_DP")
	)
	(segment
		(start 151.705564 -63.437516)
		(end 153.858468 -74.205084)
		(width 0.1397)
		(layer "In5.Cu")
		(net "PCIE_COMP_TO_IOM_11_DP")
	)
	(segment
		(start 149.008338 -35.39109)
		(end 149.09038 -35.802062)
		(width 0.1397)
		(layer "In5.Cu")
		(net "PCIE_COMP_TO_IOM_11_DP")
	)
	(segment
		(start 152.401778 -53.265324)
		(end 152.611074 -53.405024)
		(width 0.1397)
		(layer "In5.Cu")
		(net "PCIE_COMP_TO_IOM_11_DP")
	)
	(segment
		(start 183.051704 -91.760294)
		(end 186.168792 -91.136724)
		(width 0.1397)
		(layer "In5.Cu")
		(net "PCIE_COMP_TO_IOM_11_DP")
	)
	(segment
		(start 148.950934 -36.011104)
		(end 149.03323 -36.422076)
		(width 0.1397)
		(layer "In5.Cu")
		(net "PCIE_COMP_TO_IOM_11_DP")
	)
	(segment
		(start 152.085548 -51.68392)
		(end 152.16759 -52.094892)
		(width 0.1397)
		(layer "In5.Cu")
		(net "PCIE_COMP_TO_IOM_11_DP")
	)
	(segment
		(start 149.501352 -38.763448)
		(end 149.710648 -38.902894)
		(width 0.1397)
		(layer "In5.Cu")
		(net "PCIE_COMP_TO_IOM_11_DP")
	)
	(segment
		(start 198.12 -86.325456)
		(end 197.523862 -85.729318)
		(width 0.1397)
		(layer "In5.Cu")
		(net "PCIE_COMP_TO_IOM_11_DP")
	)
	(segment
		(start 149.09038 -35.802062)
		(end 148.950934 -36.011104)
		(width 0.1397)
		(layer "In5.Cu")
		(net "PCIE_COMP_TO_IOM_11_DP")
	)
	(segment
		(start 148.799042 -35.251644)
		(end 149.008338 -35.39109)
		(width 0.1397)
		(layer "In5.Cu")
		(net "PCIE_COMP_TO_IOM_11_DP")
	)
	(segment
		(start 152.635966 -54.43601)
		(end 152.845262 -54.575456)
		(width 0.1397)
		(layer "In5.Cu")
		(net "PCIE_COMP_TO_IOM_11_DP")
	)
	(segment
		(start 149.324568 -36.972494)
		(end 149.185122 -37.18179)
		(width 0.1397)
		(layer "In5.Cu")
		(net "PCIE_COMP_TO_IOM_11_DP")
	)
	(segment
		(start 149.185122 -37.18179)
		(end 149.267418 -37.592762)
		(width 0.1397)
		(layer "In5.Cu")
		(net "PCIE_COMP_TO_IOM_11_DP")
	)
	(segment
		(start 135.684006 -33.738058)
		(end 135.46074 -33.738058)
		(width 0.1397)
		(layer "In5.Cu")
		(net "PCIE_COMP_TO_IOM_11_DP")
	)
	(segment
		(start 153.079196 -55.746142)
		(end 153.161492 -56.157114)
		(width 0.1397)
		(layer "In5.Cu")
		(net "PCIE_COMP_TO_IOM_11_DP")
	)
	(arc
		(start 197.523862 -85.729318)
		(mid 197.44259 -85.531855)
		(end 197.52437 -85.334602)
		(width 0.1397)
		(layer "In5.Cu")
		(net "PCIE_COMP_TO_IOM_11_DP")
	)
	(arc
		(start 135.899906 -33.522158)
		(mid 135.83667 -33.674822)
		(end 135.684006 -33.738058)
		(width 0.1397)
		(layer "In5.Cu")
		(net "PCIE_COMP_TO_IOM_11_DP")
	)
	(arc
		(start 135.46074 -33.738058)
		(mid 135.25168 -33.651462)
		(end 135.165084 -33.442402)
		(width 0.1397)
		(layer "In5.Cu")
		(net "PCIE_COMP_TO_IOM_11_DP")
	)
	(segment
		(start 196.318632 -75.900026)
		(end 196.399912 -75.900026)
		(width 0.14605)
		(layer "F.Cu")
		(net "PCIE_COMP_TO_IOM_11_DN")
	)
	(segment
		(start 197.025768 -84.22005)
		(end 197.193154 -84.052918)
		(width 0.14605)
		(layer "F.Cu")
		(net "PCIE_COMP_TO_IOM_11_DN")
	)
	(segment
		(start 197.193154 -80.754474)
		(end 196.018658 -79.579978)
		(width 0.14605)
		(layer "F.Cu")
		(net "PCIE_COMP_TO_IOM_11_DN")
	)
	(segment
		(start 196.53885 -84.706968)
		(end 197.025768 -84.22005)
		(width 0.14605)
		(layer "F.Cu")
		(net "PCIE_COMP_TO_IOM_11_DN")
	)
	(segment
		(start 196.018658 -79.579978)
		(end 196.018658 -76.2)
		(width 0.14605)
		(layer "F.Cu")
		(net "PCIE_COMP_TO_IOM_11_DN")
	)
	(segment
		(start 196.018658 -76.2)
		(end 196.318632 -75.900026)
		(width 0.14605)
		(layer "F.Cu")
		(net "PCIE_COMP_TO_IOM_11_DN")
	)
	(segment
		(start 197.193154 -84.052918)
		(end 197.193154 -80.754474)
		(width 0.14605)
		(layer "F.Cu")
		(net "PCIE_COMP_TO_IOM_11_DN")
	)
	(segment
		(start 196.895974 -85.55482)
		(end 196.53885 -85.197696)
		(width 0.14605)
		(layer "F.Cu")
		(net "PCIE_COMP_TO_IOM_11_DN")
	)
	(segment
		(start 196.53885 -85.197696)
		(end 196.53885 -84.706968)
		(width 0.14605)
		(layer "F.Cu")
		(net "PCIE_COMP_TO_IOM_11_DN")
	)
	(arc
		(start 196.895974 -85.962998)
		(mid 196.980458 -85.758946)
		(end 196.895974 -85.55482)
		(width 0.14605)
		(layer "F.Cu")
		(net "PCIE_COMP_TO_IOM_11_DN")
	)
	(segment
		(start 135.899906 -34.284158)
		(end 135.899906 -34.600134)
		(width 0.1397)
		(layer "In5.Cu")
		(net "PCIE_COMP_TO_IOM_11_DN")
	)
	(segment
		(start 135.46074 -34.068258)
		(end 135.684006 -34.068258)
		(width 0.1397)
		(layer "In5.Cu")
		(net "PCIE_COMP_TO_IOM_11_DN")
	)
	(segment
		(start 154.169618 -74.076306)
		(end 152.042368 -63.437516)
		(width 0.1397)
		(layer "In5.Cu")
		(net "PCIE_COMP_TO_IOM_11_DN")
	)
	(segment
		(start 194.31508 -90.881708)
		(end 194.314826 -90.881708)
		(width 0.1397)
		(layer "In5.Cu")
		(net "PCIE_COMP_TO_IOM_11_DN")
	)
	(segment
		(start 197.522592 -86.195154)
		(end 197.7898 -86.462362)
		(width 0.1397)
		(layer "In5.Cu")
		(net "PCIE_COMP_TO_IOM_11_DN")
	)
	(segment
		(start 174.775114 -89.78392)
		(end 171.186602 -87.363554)
		(width 0.1397)
		(layer "In5.Cu")
		(net "PCIE_COMP_TO_IOM_11_DN")
	)
	(segment
		(start 152.042368 -63.437516)
		(end 153.498296 -56.157114)
		(width 0.1397)
		(layer "In5.Cu")
		(net "PCIE_COMP_TO_IOM_11_DN")
	)
	(segment
		(start 134.834884 -29.364686)
		(end 134.834884 -33.442402)
		(width 0.1397)
		(layer "In5.Cu")
		(net "PCIE_COMP_TO_IOM_11_DN")
	)
	(segment
		(start 197.7898 -87.407496)
		(end 194.31508 -90.881708)
		(width 0.1397)
		(layer "In5.Cu")
		(net "PCIE_COMP_TO_IOM_11_DN")
	)
	(segment
		(start 149.0853 -34.091372)
		(end 145.732246 -29.062172)
		(width 0.1397)
		(layer "In5.Cu")
		(net "PCIE_COMP_TO_IOM_11_DN")
	)
	(segment
		(start 194.314826 -90.881708)
		(end 190.445644 -91.655646)
		(width 0.1397)
		(layer "In5.Cu")
		(net "PCIE_COMP_TO_IOM_11_DN")
	)
	(segment
		(start 197.290182 -85.962998)
		(end 197.522592 -86.195408)
		(width 0.1397)
		(layer "In5.Cu")
		(net "PCIE_COMP_TO_IOM_11_DN")
	)
	(segment
		(start 169.310558 -86.99881)
		(end 157.563566 -79.16799)
		(width 0.1397)
		(layer "In5.Cu")
		(net "PCIE_COMP_TO_IOM_11_DN")
	)
	(segment
		(start 145.732246 -29.062172)
		(end 144.008856 -27.339036)
		(width 0.1397)
		(layer "In5.Cu")
		(net "PCIE_COMP_TO_IOM_11_DN")
	)
	(segment
		(start 171.186602 -87.363554)
		(end 169.310558 -86.99881)
		(width 0.1397)
		(layer "In5.Cu")
		(net "PCIE_COMP_TO_IOM_11_DN")
	)
	(segment
		(start 183.05145 -91.42349)
		(end 174.775114 -89.78392)
		(width 0.1397)
		(layer "In5.Cu")
		(net "PCIE_COMP_TO_IOM_11_DN")
	)
	(segment
		(start 186.168792 -90.79992)
		(end 183.05145 -91.42349)
		(width 0.1397)
		(layer "In5.Cu")
		(net "PCIE_COMP_TO_IOM_11_DN")
	)
	(segment
		(start 144.008856 -27.339036)
		(end 136.860534 -27.339036)
		(width 0.1397)
		(layer "In5.Cu")
		(net "PCIE_COMP_TO_IOM_11_DN")
	)
	(segment
		(start 197.522592 -86.195408)
		(end 197.522592 -86.195154)
		(width 0.1397)
		(layer "In5.Cu")
		(net "PCIE_COMP_TO_IOM_11_DN")
	)
	(segment
		(start 197.7898 -86.462362)
		(end 197.7898 -87.407496)
		(width 0.1397)
		(layer "In5.Cu")
		(net "PCIE_COMP_TO_IOM_11_DN")
	)
	(segment
		(start 190.445644 -91.655646)
		(end 186.168792 -90.79992)
		(width 0.1397)
		(layer "In5.Cu")
		(net "PCIE_COMP_TO_IOM_11_DN")
	)
	(segment
		(start 153.498296 -56.157114)
		(end 149.0853 -34.091372)
		(width 0.1397)
		(layer "In5.Cu")
		(net "PCIE_COMP_TO_IOM_11_DN")
	)
	(segment
		(start 136.860534 -27.339036)
		(end 134.834884 -29.364686)
		(width 0.1397)
		(layer "In5.Cu")
		(net "PCIE_COMP_TO_IOM_11_DN")
	)
	(segment
		(start 157.563566 -79.16799)
		(end 154.169618 -74.076306)
		(width 0.1397)
		(layer "In5.Cu")
		(net "PCIE_COMP_TO_IOM_11_DN")
	)
	(arc
		(start 196.895974 -85.962998)
		(mid 197.093078 -85.88128)
		(end 197.290182 -85.962998)
		(width 0.1397)
		(layer "In5.Cu")
		(net "PCIE_COMP_TO_IOM_11_DN")
	)
	(arc
		(start 135.684006 -34.068258)
		(mid 135.83667 -34.131494)
		(end 135.899906 -34.284158)
		(width 0.1397)
		(layer "In5.Cu")
		(net "PCIE_COMP_TO_IOM_11_DN")
	)
	(arc
		(start 134.834884 -33.442402)
		(mid 135.018193 -33.884949)
		(end 135.46074 -34.068258)
		(width 0.1397)
		(layer "In5.Cu")
		(net "PCIE_COMP_TO_IOM_11_DN")
	)
	(segment
		(start 199.161654 -80.513682)
		(end 197.129908 -78.481936)
		(width 0.14605)
		(layer "F.Cu")
		(net "PCIE_COMP_TO_IOM_10_DP")
	)
	(segment
		(start 197.7644 -87.816436)
		(end 197.7644 -86.818978)
		(width 0.14605)
		(layer "F.Cu")
		(net "PCIE_COMP_TO_IOM_10_DP")
	)
	(segment
		(start 198.407782 -88.459818)
		(end 197.7644 -87.816436)
		(width 0.14605)
		(layer "F.Cu")
		(net "PCIE_COMP_TO_IOM_10_DP")
	)
	(segment
		(start 197.129908 -78.481936)
		(end 197.129908 -76.769976)
		(width 0.14605)
		(layer "F.Cu")
		(net "PCIE_COMP_TO_IOM_10_DP")
	)
	(segment
		(start 197.129908 -76.769976)
		(end 197.200012 -76.699872)
		(width 0.14605)
		(layer "F.Cu")
		(net "PCIE_COMP_TO_IOM_10_DP")
	)
	(segment
		(start 198.815198 -88.458802)
		(end 198.814182 -88.459818)
		(width 0.14605)
		(layer "F.Cu")
		(net "PCIE_COMP_TO_IOM_10_DP")
	)
	(segment
		(start 197.7644 -86.818978)
		(end 199.161654 -85.421724)
		(width 0.14605)
		(layer "F.Cu")
		(net "PCIE_COMP_TO_IOM_10_DP")
	)
	(segment
		(start 199.161654 -85.421724)
		(end 199.161654 -80.513682)
		(width 0.14605)
		(layer "F.Cu")
		(net "PCIE_COMP_TO_IOM_10_DP")
	)
	(arc
		(start 198.814182 -88.459818)
		(mid 198.610982 -88.543986)
		(end 198.407782 -88.459818)
		(width 0.14605)
		(layer "F.Cu")
		(net "PCIE_COMP_TO_IOM_10_DP")
	)
	(segment
		(start 172.928026 -90.459814)
		(end 172.681138 -90.50782)
		(width 0.1397)
		(layer "In5.Cu")
		(net "PCIE_COMP_TO_IOM_10_DP")
	)
	(segment
		(start 151.648414 -55.009542)
		(end 151.566118 -54.59857)
		(width 0.1397)
		(layer "In5.Cu")
		(net "PCIE_COMP_TO_IOM_10_DP")
	)
	(segment
		(start 137.260838 -32.537908)
		(end 137.484104 -32.537908)
		(width 0.1397)
		(layer "In5.Cu")
		(net "PCIE_COMP_TO_IOM_10_DP")
	)
	(segment
		(start 147.632166 -34.022792)
		(end 144.690084 -29.609796)
		(width 0.1397)
		(layer "In5.Cu")
		(net "PCIE_COMP_TO_IOM_10_DP")
	)
	(segment
		(start 148.334476 -37.534596)
		(end 148.125434 -37.39515)
		(width 0.1397)
		(layer "In5.Cu")
		(net "PCIE_COMP_TO_IOM_10_DP")
	)
	(segment
		(start 151.85771 -55.148988)
		(end 151.648414 -55.009542)
		(width 0.1397)
		(layer "In5.Cu")
		(net "PCIE_COMP_TO_IOM_10_DP")
	)
	(segment
		(start 151.800306 -55.769256)
		(end 151.939752 -55.55996)
		(width 0.1397)
		(layer "In5.Cu")
		(net "PCIE_COMP_TO_IOM_10_DP")
	)
	(segment
		(start 148.182584 -36.774882)
		(end 148.100542 -36.36391)
		(width 0.1397)
		(layer "In5.Cu")
		(net "PCIE_COMP_TO_IOM_10_DP")
	)
	(segment
		(start 147.948396 -35.60445)
		(end 147.866354 -35.193478)
		(width 0.1397)
		(layer "In5.Cu")
		(net "PCIE_COMP_TO_IOM_10_DP")
	)
	(segment
		(start 199.077072 -89.115138)
		(end 199.077072 -89.898728)
		(width 0.1397)
		(layer "In5.Cu")
		(net "PCIE_COMP_TO_IOM_10_DP")
	)
	(segment
		(start 151.705564 -54.389528)
		(end 151.623522 -53.978556)
		(width 0.1397)
		(layer "In5.Cu")
		(net "PCIE_COMP_TO_IOM_10_DP")
	)
	(segment
		(start 151.237442 -52.048156)
		(end 148.568664 -38.705282)
		(width 0.1397)
		(layer "In5.Cu")
		(net "PCIE_COMP_TO_IOM_10_DP")
	)
	(segment
		(start 196.79285 -91.547442)
		(end 185.21299 -93.863668)
		(width 0.1397)
		(layer "In5.Cu")
		(net "PCIE_COMP_TO_IOM_10_DP")
	)
	(segment
		(start 147.891246 -36.224464)
		(end 147.80895 -35.813492)
		(width 0.1397)
		(layer "In5.Cu")
		(net "PCIE_COMP_TO_IOM_10_DP")
	)
	(segment
		(start 148.277326 -38.154864)
		(end 148.416772 -37.945568)
		(width 0.1397)
		(layer "In5.Cu")
		(net "PCIE_COMP_TO_IOM_10_DP")
	)
	(segment
		(start 144.690084 -29.609796)
		(end 143.557244 -28.476956)
		(width 0.1397)
		(layer "In5.Cu")
		(net "PCIE_COMP_TO_IOM_10_DP")
	)
	(segment
		(start 151.566118 -54.59857)
		(end 151.705564 -54.389528)
		(width 0.1397)
		(layer "In5.Cu")
		(net "PCIE_COMP_TO_IOM_10_DP")
	)
	(segment
		(start 147.714462 -34.433764)
		(end 147.632166 -34.022792)
		(width 0.1397)
		(layer "In5.Cu")
		(net "PCIE_COMP_TO_IOM_10_DP")
	)
	(segment
		(start 148.100542 -36.36391)
		(end 147.891246 -36.224464)
		(width 0.1397)
		(layer "In5.Cu")
		(net "PCIE_COMP_TO_IOM_10_DP")
	)
	(segment
		(start 169.817542 -88.361774)
		(end 169.817542 -88.362028)
		(width 0.1397)
		(layer "In5.Cu")
		(net "PCIE_COMP_TO_IOM_10_DP")
	)
	(segment
		(start 151.180038 -52.668424)
		(end 151.097996 -52.257452)
		(width 0.1397)
		(layer "In5.Cu")
		(net "PCIE_COMP_TO_IOM_10_DP")
	)
	(segment
		(start 143.557244 -28.476956)
		(end 139.083796 -28.476956)
		(width 0.1397)
		(layer "In5.Cu")
		(net "PCIE_COMP_TO_IOM_10_DP")
	)
	(segment
		(start 185.21299 -93.863668)
		(end 174.978314 -91.842844)
		(width 0.1397)
		(layer "In5.Cu")
		(net "PCIE_COMP_TO_IOM_10_DP")
	)
	(segment
		(start 199.077072 -89.898728)
		(end 198.698866 -90.276934)
		(width 0.1397)
		(layer "In5.Cu")
		(net "PCIE_COMP_TO_IOM_10_DP")
	)
	(segment
		(start 148.568664 -38.705282)
		(end 148.359368 -38.565836)
		(width 0.1397)
		(layer "In5.Cu")
		(net "PCIE_COMP_TO_IOM_10_DP")
	)
	(segment
		(start 156.532072 -80.01254)
		(end 153.142188 -74.938382)
		(width 0.1397)
		(layer "In5.Cu")
		(net "PCIE_COMP_TO_IOM_10_DP")
	)
	(segment
		(start 151.47163 -53.218842)
		(end 151.389334 -52.80787)
		(width 0.1397)
		(layer "In5.Cu")
		(net "PCIE_COMP_TO_IOM_10_DP")
	)
	(segment
		(start 198.939404 -88.977216)
		(end 198.93915 -88.977216)
		(width 0.1397)
		(layer "In5.Cu")
		(net "PCIE_COMP_TO_IOM_10_DP")
	)
	(segment
		(start 152.091644 -56.319674)
		(end 151.882602 -56.180228)
		(width 0.1397)
		(layer "In5.Cu")
		(net "PCIE_COMP_TO_IOM_10_DP")
	)
	(segment
		(start 151.389334 -52.80787)
		(end 151.180038 -52.668424)
		(width 0.1397)
		(layer "In5.Cu")
		(net "PCIE_COMP_TO_IOM_10_DP")
	)
	(segment
		(start 171.296076 -89.358978)
		(end 169.817542 -88.361774)
		(width 0.1397)
		(layer "In5.Cu")
		(net "PCIE_COMP_TO_IOM_10_DP")
	)
	(segment
		(start 136.965182 -30.59557)
		(end 136.965182 -32.242252)
		(width 0.1397)
		(layer "In5.Cu")
		(net "PCIE_COMP_TO_IOM_10_DP")
	)
	(segment
		(start 171.344082 -89.605866)
		(end 171.296076 -89.358978)
		(width 0.1397)
		(layer "In5.Cu")
		(net "PCIE_COMP_TO_IOM_10_DP")
	)
	(segment
		(start 171.938442 -89.792302)
		(end 171.691554 -89.840308)
		(width 0.1397)
		(layer "In5.Cu")
		(net "PCIE_COMP_TO_IOM_10_DP")
	)
	(segment
		(start 198.698866 -90.276934)
		(end 196.79285 -91.547442)
		(width 0.1397)
		(layer "In5.Cu")
		(net "PCIE_COMP_TO_IOM_10_DP")
	)
	(segment
		(start 148.416772 -37.945568)
		(end 148.334476 -37.534596)
		(width 0.1397)
		(layer "In5.Cu")
		(net "PCIE_COMP_TO_IOM_10_DP")
	)
	(segment
		(start 150.83663 -63.415672)
		(end 152.17394 -56.730646)
		(width 0.1397)
		(layer "In5.Cu")
		(net "PCIE_COMP_TO_IOM_10_DP")
	)
	(segment
		(start 147.866354 -35.193478)
		(end 147.657058 -35.054032)
		(width 0.1397)
		(layer "In5.Cu")
		(net "PCIE_COMP_TO_IOM_10_DP")
	)
	(segment
		(start 151.097996 -52.257452)
		(end 151.237442 -52.048156)
		(width 0.1397)
		(layer "In5.Cu")
		(net "PCIE_COMP_TO_IOM_10_DP")
	)
	(segment
		(start 198.93915 -88.977216)
		(end 199.077072 -89.115138)
		(width 0.1397)
		(layer "In5.Cu")
		(net "PCIE_COMP_TO_IOM_10_DP")
	)
	(segment
		(start 174.978314 -91.842844)
		(end 172.928026 -90.459814)
		(width 0.1397)
		(layer "In5.Cu")
		(net "PCIE_COMP_TO_IOM_10_DP")
	)
	(segment
		(start 169.817542 -88.362028)
		(end 168.74236 -88.152986)
		(width 0.1397)
		(layer "In5.Cu")
		(net "PCIE_COMP_TO_IOM_10_DP")
	)
	(segment
		(start 147.80895 -35.813492)
		(end 147.948396 -35.60445)
		(width 0.1397)
		(layer "In5.Cu")
		(net "PCIE_COMP_TO_IOM_10_DP")
	)
	(segment
		(start 147.657058 -35.054032)
		(end 147.574762 -34.64306)
		(width 0.1397)
		(layer "In5.Cu")
		(net "PCIE_COMP_TO_IOM_10_DP")
	)
	(segment
		(start 148.043138 -36.984178)
		(end 148.182584 -36.774882)
		(width 0.1397)
		(layer "In5.Cu")
		(net "PCIE_COMP_TO_IOM_10_DP")
	)
	(segment
		(start 153.142188 -74.938382)
		(end 150.83663 -63.415672)
		(width 0.1397)
		(layer "In5.Cu")
		(net "PCIE_COMP_TO_IOM_10_DP")
	)
	(segment
		(start 148.125434 -37.39515)
		(end 148.043138 -36.984178)
		(width 0.1397)
		(layer "In5.Cu")
		(net "PCIE_COMP_TO_IOM_10_DP")
	)
	(segment
		(start 172.28566 -90.026744)
		(end 171.938442 -89.792302)
		(width 0.1397)
		(layer "In5.Cu")
		(net "PCIE_COMP_TO_IOM_10_DP")
	)
	(segment
		(start 148.359368 -38.565836)
		(end 148.277326 -38.154864)
		(width 0.1397)
		(layer "In5.Cu")
		(net "PCIE_COMP_TO_IOM_10_DP")
	)
	(segment
		(start 171.691554 -89.840308)
		(end 171.344082 -89.605866)
		(width 0.1397)
		(layer "In5.Cu")
		(net "PCIE_COMP_TO_IOM_10_DP")
	)
	(segment
		(start 168.74236 -88.152986)
		(end 156.532072 -80.01254)
		(width 0.1397)
		(layer "In5.Cu")
		(net "PCIE_COMP_TO_IOM_10_DP")
	)
	(segment
		(start 152.17394 -56.730646)
		(end 152.091644 -56.319674)
		(width 0.1397)
		(layer "In5.Cu")
		(net "PCIE_COMP_TO_IOM_10_DP")
	)
	(segment
		(start 151.414226 -53.83911)
		(end 151.33193 -53.428138)
		(width 0.1397)
		(layer "In5.Cu")
		(net "PCIE_COMP_TO_IOM_10_DP")
	)
	(segment
		(start 137.700004 -32.322008)
		(end 137.700004 -32.00019)
		(width 0.1397)
		(layer "In5.Cu")
		(net "PCIE_COMP_TO_IOM_10_DP")
	)
	(segment
		(start 151.623522 -53.978556)
		(end 151.414226 -53.83911)
		(width 0.1397)
		(layer "In5.Cu")
		(net "PCIE_COMP_TO_IOM_10_DP")
	)
	(segment
		(start 151.939752 -55.55996)
		(end 151.85771 -55.148988)
		(width 0.1397)
		(layer "In5.Cu")
		(net "PCIE_COMP_TO_IOM_10_DP")
	)
	(segment
		(start 172.681138 -90.50782)
		(end 172.333666 -90.273378)
		(width 0.1397)
		(layer "In5.Cu")
		(net "PCIE_COMP_TO_IOM_10_DP")
	)
	(segment
		(start 147.574762 -34.64306)
		(end 147.714462 -34.433764)
		(width 0.1397)
		(layer "In5.Cu")
		(net "PCIE_COMP_TO_IOM_10_DP")
	)
	(segment
		(start 139.083796 -28.476956)
		(end 136.965182 -30.59557)
		(width 0.1397)
		(layer "In5.Cu")
		(net "PCIE_COMP_TO_IOM_10_DP")
	)
	(segment
		(start 151.882602 -56.180228)
		(end 151.800306 -55.769256)
		(width 0.1397)
		(layer "In5.Cu")
		(net "PCIE_COMP_TO_IOM_10_DP")
	)
	(segment
		(start 198.815198 -88.85301)
		(end 198.939404 -88.977216)
		(width 0.1397)
		(layer "In5.Cu")
		(net "PCIE_COMP_TO_IOM_10_DP")
	)
	(segment
		(start 151.33193 -53.428138)
		(end 151.47163 -53.218842)
		(width 0.1397)
		(layer "In5.Cu")
		(net "PCIE_COMP_TO_IOM_10_DP")
	)
	(segment
		(start 172.333666 -90.273378)
		(end 172.28566 -90.026744)
		(width 0.1397)
		(layer "In5.Cu")
		(net "PCIE_COMP_TO_IOM_10_DP")
	)
	(arc
		(start 137.484104 -32.537908)
		(mid 137.636768 -32.474672)
		(end 137.700004 -32.322008)
		(width 0.1397)
		(layer "In5.Cu")
		(net "PCIE_COMP_TO_IOM_10_DP")
	)
	(arc
		(start 136.965182 -32.242252)
		(mid 137.051778 -32.451312)
		(end 137.260838 -32.537908)
		(width 0.1397)
		(layer "In5.Cu")
		(net "PCIE_COMP_TO_IOM_10_DP")
	)
	(arc
		(start 198.815198 -88.458802)
		(mid 198.733555 -88.655906)
		(end 198.815198 -88.85301)
		(width 0.1397)
		(layer "In5.Cu")
		(net "PCIE_COMP_TO_IOM_10_DP")
	)
	(segment
		(start 196.818758 -76.2)
		(end 196.818758 -78.610968)
		(width 0.14605)
		(layer "F.Cu")
		(net "PCIE_COMP_TO_IOM_10_DN")
	)
	(segment
		(start 196.818758 -78.610968)
		(end 198.850504 -80.642714)
		(width 0.14605)
		(layer "F.Cu")
		(net "PCIE_COMP_TO_IOM_10_DN")
	)
	(segment
		(start 197.118732 -75.900026)
		(end 196.818758 -76.2)
		(width 0.14605)
		(layer "F.Cu")
		(net "PCIE_COMP_TO_IOM_10_DN")
	)
	(segment
		(start 198.850504 -85.292692)
		(end 197.45325 -86.689946)
		(width 0.14605)
		(layer "F.Cu")
		(net "PCIE_COMP_TO_IOM_10_DN")
	)
	(segment
		(start 198.187564 -89.086436)
		(end 198.186802 -89.087198)
		(width 0.14605)
		(layer "F.Cu")
		(net "PCIE_COMP_TO_IOM_10_DN")
	)
	(segment
		(start 197.45325 -87.945468)
		(end 198.187564 -88.679782)
		(width 0.14605)
		(layer "F.Cu")
		(net "PCIE_COMP_TO_IOM_10_DN")
	)
	(segment
		(start 198.850504 -80.642714)
		(end 198.850504 -85.292692)
		(width 0.14605)
		(layer "F.Cu")
		(net "PCIE_COMP_TO_IOM_10_DN")
	)
	(segment
		(start 197.45325 -86.689946)
		(end 197.45325 -87.945468)
		(width 0.14605)
		(layer "F.Cu")
		(net "PCIE_COMP_TO_IOM_10_DN")
	)
	(segment
		(start 197.200012 -75.900026)
		(end 197.118732 -75.900026)
		(width 0.14605)
		(layer "F.Cu")
		(net "PCIE_COMP_TO_IOM_10_DN")
	)
	(arc
		(start 198.187564 -88.679782)
		(mid 198.271912 -88.883146)
		(end 198.187564 -89.086436)
		(width 0.14605)
		(layer "F.Cu")
		(net "PCIE_COMP_TO_IOM_10_DN")
	)
	(segment
		(start 144.946878 -29.39923)
		(end 143.69415 -28.146756)
		(width 0.1397)
		(layer "In5.Cu")
		(net "PCIE_COMP_TO_IOM_10_DN")
	)
	(segment
		(start 185.212482 -93.526864)
		(end 175.1076 -91.531694)
		(width 0.1397)
		(layer "In5.Cu")
		(net "PCIE_COMP_TO_IOM_10_DN")
	)
	(segment
		(start 196.664072 -91.236292)
		(end 185.212482 -93.526864)
		(width 0.1397)
		(layer "In5.Cu")
		(net "PCIE_COMP_TO_IOM_10_DN")
	)
	(segment
		(start 136.634982 -30.458664)
		(end 136.634982 -32.242252)
		(width 0.1397)
		(layer "In5.Cu")
		(net "PCIE_COMP_TO_IOM_10_DN")
	)
	(segment
		(start 137.260838 -32.868108)
		(end 137.484104 -32.868108)
		(width 0.1397)
		(layer "In5.Cu")
		(net "PCIE_COMP_TO_IOM_10_DN")
	)
	(segment
		(start 198.746872 -89.252044)
		(end 198.746872 -89.761822)
		(width 0.1397)
		(layer "In5.Cu")
		(net "PCIE_COMP_TO_IOM_10_DN")
	)
	(segment
		(start 153.453338 -74.80935)
		(end 151.173434 -63.415672)
		(width 0.1397)
		(layer "In5.Cu")
		(net "PCIE_COMP_TO_IOM_10_DN")
	)
	(segment
		(start 169.946574 -88.05037)
		(end 168.87063 -87.841328)
		(width 0.1397)
		(layer "In5.Cu")
		(net "PCIE_COMP_TO_IOM_10_DN")
	)
	(segment
		(start 198.582026 -89.087198)
		(end 198.746872 -89.252044)
		(width 0.1397)
		(layer "In5.Cu")
		(net "PCIE_COMP_TO_IOM_10_DN")
	)
	(segment
		(start 198.4883 -90.02014)
		(end 196.664072 -91.236292)
		(width 0.1397)
		(layer "In5.Cu")
		(net "PCIE_COMP_TO_IOM_10_DN")
	)
	(segment
		(start 175.1076 -91.531694)
		(end 169.946574 -88.05037)
		(width 0.1397)
		(layer "In5.Cu")
		(net "PCIE_COMP_TO_IOM_10_DN")
	)
	(segment
		(start 143.69415 -28.146756)
		(end 138.94689 -28.146756)
		(width 0.1397)
		(layer "In5.Cu")
		(net "PCIE_COMP_TO_IOM_10_DN")
	)
	(segment
		(start 156.77007 -79.774288)
		(end 153.453338 -74.80935)
		(width 0.1397)
		(layer "In5.Cu")
		(net "PCIE_COMP_TO_IOM_10_DN")
	)
	(segment
		(start 168.87063 -87.841328)
		(end 156.77007 -79.774288)
		(width 0.1397)
		(layer "In5.Cu")
		(net "PCIE_COMP_TO_IOM_10_DN")
	)
	(segment
		(start 147.943316 -33.89376)
		(end 144.946878 -29.39923)
		(width 0.1397)
		(layer "In5.Cu")
		(net "PCIE_COMP_TO_IOM_10_DN")
	)
	(segment
		(start 198.746872 -89.761822)
		(end 198.4883 -90.02014)
		(width 0.1397)
		(layer "In5.Cu")
		(net "PCIE_COMP_TO_IOM_10_DN")
	)
	(segment
		(start 138.94689 -28.146756)
		(end 136.634982 -30.458664)
		(width 0.1397)
		(layer "In5.Cu")
		(net "PCIE_COMP_TO_IOM_10_DN")
	)
	(segment
		(start 151.173434 -63.415672)
		(end 152.510744 -56.730646)
		(width 0.1397)
		(layer "In5.Cu")
		(net "PCIE_COMP_TO_IOM_10_DN")
	)
	(segment
		(start 137.700004 -33.084008)
		(end 137.700004 -33.399984)
		(width 0.1397)
		(layer "In5.Cu")
		(net "PCIE_COMP_TO_IOM_10_DN")
	)
	(segment
		(start 152.510744 -56.730646)
		(end 147.943316 -33.89376)
		(width 0.1397)
		(layer "In5.Cu")
		(net "PCIE_COMP_TO_IOM_10_DN")
	)
	(arc
		(start 198.186802 -89.087198)
		(mid 198.384414 -89.005344)
		(end 198.582026 -89.087198)
		(width 0.1397)
		(layer "In5.Cu")
		(net "PCIE_COMP_TO_IOM_10_DN")
	)
	(arc
		(start 137.484104 -32.868108)
		(mid 137.636768 -32.931344)
		(end 137.700004 -33.084008)
		(width 0.1397)
		(layer "In5.Cu")
		(net "PCIE_COMP_TO_IOM_10_DN")
	)
	(arc
		(start 136.634982 -32.242252)
		(mid 136.818291 -32.684799)
		(end 137.260838 -32.868108)
		(width 0.1397)
		(layer "In5.Cu")
		(net "PCIE_COMP_TO_IOM_10_DN")
	)
	(segment
		(start 176.8094 -126.7714)
		(end 176.8094 -124.387864)
		(width 0.254)
		(layer "F.Cu")
		(net "P3V3_PG")
	)
	(segment
		(start 178.40706 -125.04674)
		(end 179.1081 -125.04674)
		(width 0.254)
		(layer "F.Cu")
		(net "P3V3_PG")
	)
	(segment
		(start 179.1081 -125.04674)
		(end 180.42382 -126.36246)
		(width 0.254)
		(layer "F.Cu")
		(net "P3V3_PG")
	)
	(segment
		(start 177.6603 -128.016)
		(end 177.6603 -127.821944)
		(width 0.254)
		(layer "F.Cu")
		(net "P3V3_PG")
	)
	(segment
		(start 177.468276 -125.04674)
		(end 176.8094 -124.387864)
		(width 0.254)
		(layer "F.Cu")
		(net "P3V3_PG")
	)
	(segment
		(start 176.8094 -126.971044)
		(end 176.8094 -126.7714)
		(width 0.254)
		(layer "F.Cu")
		(net "P3V3_PG")
	)
	(segment
		(start 177.6603 -127.821944)
		(end 176.8094 -126.971044)
		(width 0.254)
		(layer "F.Cu")
		(net "P3V3_PG")
	)
	(segment
		(start 178.40706 -125.04674)
		(end 177.468276 -125.04674)
		(width 0.254)
		(layer "F.Cu")
		(net "P3V3_PG")
	)
	(via
		(at 176.8094 -126.7714)
		(size 0.6604)
		(drill 0.3302)
		(layers "F.Cu" "B.Cu")
		(net "P3V3_PG")
	)
	(segment
		(start 94.054168 -56.947816)
		(end 94.054168 -57.133236)
		(width 0.127)
		(layer "F.Cu")
		(net "P3V3_EN")
	)
	(segment
		(start 93.576648 -57.610756)
		(end 93.576648 -59.111896)
		(width 0.127)
		(layer "F.Cu")
		(net "P3V3_EN")
	)
	(segment
		(start 91.528138 -56.60009)
		(end 91.878404 -56.950356)
		(width 0.127)
		(layer "F.Cu")
		(net "P3V3_EN")
	)
	(segment
		(start 93.640148 -56.533796)
		(end 94.054168 -56.947816)
		(width 0.127)
		(layer "F.Cu")
		(net "P3V3_EN")
	)
	(segment
		(start 92.44965 -53.701442)
		(end 91.905074 -53.701442)
		(width 0.127)
		(layer "F.Cu")
		(net "P3V3_EN")
	)
	(segment
		(start 94.054168 -57.133236)
		(end 93.576648 -57.610756)
		(width 0.127)
		(layer "F.Cu")
		(net "P3V3_EN")
	)
	(segment
		(start 91.528138 -54.078378)
		(end 91.528138 -56.60009)
		(width 0.127)
		(layer "F.Cu")
		(net "P3V3_EN")
	)
	(segment
		(start 92.761308 -56.533796)
		(end 93.640148 -56.533796)
		(width 0.127)
		(layer "F.Cu")
		(net "P3V3_EN")
	)
	(segment
		(start 91.878404 -56.950356)
		(end 92.344748 -56.950356)
		(width 0.127)
		(layer "F.Cu")
		(net "P3V3_EN")
	)
	(segment
		(start 91.905074 -53.701442)
		(end 91.528138 -54.078378)
		(width 0.127)
		(layer "F.Cu")
		(net "P3V3_EN")
	)
	(segment
		(start 92.344748 -56.950356)
		(end 92.761308 -56.533796)
		(width 0.127)
		(layer "F.Cu")
		(net "P3V3_EN")
	)
	(segment
		(start 160.57372 -102.0572)
		(end 160.57372 -101.083872)
		(width 0.508)
		(layer "F.Cu")
		(net "P3V3")
	)
	(segment
		(start 51.0159 -164.1983)
		(end 51.0159 -164.2872)
		(width 0.508)
		(layer "F.Cu")
		(net "P3V3")
	)
	(segment
		(start 162.037014 -106.917744)
		(end 160.57372 -105.45445)
		(width 0.508)
		(layer "F.Cu")
		(net "P3V3")
	)
	(segment
		(start 160.57372 -105.45445)
		(end 160.57372 -102.0572)
		(width 0.508)
		(layer "F.Cu")
		(net "P3V3")
	)
	(segment
		(start 156.660596 -94.235778)
		(end 156.642562 -94.217744)
		(width 0.3048)
		(layer "F.Cu")
		(net "P3V3")
	)
	(segment
		(start 51.0159 -164.2872)
		(end 51.663092 -164.934392)
		(width 0.508)
		(layer "F.Cu")
		(net "P3V3")
	)
	(segment
		(start 156.2481 -92.5068)
		(end 156.2481 -92.51442)
		(width 0.3048)
		(layer "F.Cu")
		(net "P3V3")
	)
	(segment
		(start 156.642562 -92.901262)
		(end 156.2481 -92.5068)
		(width 0.3048)
		(layer "F.Cu")
		(net "P3V3")
	)
	(segment
		(start 156.2481 -92.51442)
		(end 156.224478 -92.490798)
		(width 0.3048)
		(layer "F.Cu")
		(net "P3V3")
	)
	(segment
		(start 51.663092 -164.934392)
		(end 51.663092 -164.997892)
		(width 0.508)
		(layer "F.Cu")
		(net "P3V3")
	)
	(segment
		(start 164.203126 -106.917744)
		(end 162.037014 -106.917744)
		(width 0.508)
		(layer "F.Cu")
		(net "P3V3")
	)
	(segment
		(start 224.936558 -81.8134)
		(end 225.721672 -81.8134)
		(width 0.508)
		(layer "F.Cu")
		(net "P3V3")
	)
	(segment
		(start 51.663092 -164.997892)
		(end 51.6636 -164.9984)
		(width 0.508)
		(layer "F.Cu")
		(net "P3V3")
	)
	(segment
		(start 176.7713 -129.1209)
		(end 176.784 -129.1336)
		(width 0.508)
		(layer "F.Cu")
		(net "P3V3")
	)
	(segment
		(start 170.815 -128.0033)
		(end 170.815 -128.8034)
		(width 0.508)
		(layer "F.Cu")
		(net "P3V3")
	)
	(segment
		(start 224.934272 -81.811114)
		(end 224.936558 -81.8134)
		(width 0.508)
		(layer "F.Cu")
		(net "P3V3")
	)
	(segment
		(start 156.660596 -94.530164)
		(end 156.660596 -94.235778)
		(width 0.3048)
		(layer "F.Cu")
		(net "P3V3")
	)
	(segment
		(start 170.8023 -127.9906)
		(end 170.815 -128.0033)
		(width 0.508)
		(layer "F.Cu")
		(net "P3V3")
	)
	(segment
		(start 156.224478 -92.490798)
		(end 156.224478 -91.190064)
		(width 0.3048)
		(layer "F.Cu")
		(net "P3V3")
	)
	(segment
		(start 156.723842 -94.59341)
		(end 156.660596 -94.530164)
		(width 0.3048)
		(layer "F.Cu")
		(net "P3V3")
	)
	(segment
		(start 156.642562 -94.217744)
		(end 156.642562 -92.901262)
		(width 0.3048)
		(layer "F.Cu")
		(net "P3V3")
	)
	(segment
		(start 176.7713 -128.016)
		(end 176.7713 -129.1209)
		(width 0.508)
		(layer "F.Cu")
		(net "P3V3")
	)
	(via
		(at 203.962 -29.7434)
		(size 0.508)
		(drill 0.254)
		(layers "F.Cu" "B.Cu")
		(net "P3V3")
	)
	(via
		(at 160.57372 -102.0572)
		(size 0.6604)
		(drill 0.3302)
		(layers "F.Cu" "B.Cu")
		(net "P3V3")
	)
	(via
		(at 77.668628 -56.051196)
		(size 0.508)
		(drill 0.254)
		(layers "F.Cu" "B.Cu")
		(net "P3V3")
	)
	(via
		(at 110.0836 -16.096742)
		(size 0.508)
		(drill 0.254)
		(layers "F.Cu" "B.Cu")
		(net "P3V3")
	)
	(via
		(at 160.57372 -101.083872)
		(size 0.508)
		(drill 0.254)
		(layers "F.Cu" "B.Cu")
		(net "P3V3")
	)
	(via
		(at 123.5456 -18.9738)
		(size 0.508)
		(drill 0.254)
		(layers "F.Cu" "B.Cu")
		(net "P3V3")
	)
	(via
		(at 189.611 -11.9888)
		(size 0.508)
		(drill 0.254)
		(layers "F.Cu" "B.Cu")
		(net "P3V3")
	)
	(via
		(at 156.2481 -92.5068)
		(size 0.508)
		(drill 0.254)
		(layers "F.Cu" "B.Cu")
		(net "P3V3")
	)
	(via
		(at 170.815 -128.8034)
		(size 0.508)
		(drill 0.254)
		(layers "F.Cu" "B.Cu")
		(net "P3V3")
	)
	(via
		(at 225.721672 -81.8134)
		(size 0.508)
		(drill 0.254)
		(layers "F.Cu" "B.Cu")
		(net "P3V3")
	)
	(via
		(at 6.750304 -116.181124)
		(size 0.508)
		(drill 0.254)
		(layers "F.Cu" "B.Cu")
		(net "P3V3")
	)
	(via
		(at 176.784 -129.1336)
		(size 0.508)
		(drill 0.254)
		(layers "F.Cu" "B.Cu")
		(net "P3V3")
	)
	(via
		(at 146.1897 -10.8712)
		(size 0.508)
		(drill 0.254)
		(layers "F.Cu" "B.Cu")
		(net "P3V3")
	)
	(via
		(at 77.643228 -56.914796)
		(size 0.508)
		(drill 0.254)
		(layers "F.Cu" "B.Cu")
		(net "P3V3")
	)
	(via
		(at 63.9318 -112.6744)
		(size 0.508)
		(drill 0.254)
		(layers "F.Cu" "B.Cu")
		(net "P3V3")
	)
	(via
		(at 85.123528 -52.317396)
		(size 0.7112)
		(drill 0.4064)
		(layers "F.Cu" "B.Cu")
		(net "P3V3")
	)
	(via
		(at 52.4002 -167.9194)
		(size 0.508)
		(drill 0.254)
		(layers "F.Cu" "B.Cu")
		(net "P3V3")
	)
	(via
		(at 85.123528 -49.751996)
		(size 0.7112)
		(drill 0.4064)
		(layers "F.Cu" "B.Cu")
		(net "P3V3")
	)
	(via
		(at 51.6636 -164.9984)
		(size 0.508)
		(drill 0.254)
		(layers "F.Cu" "B.Cu")
		(net "P3V3")
	)
	(via
		(at 77.668628 -55.187596)
		(size 0.508)
		(drill 0.254)
		(layers "F.Cu" "B.Cu")
		(net "P3V3")
	)
	(segment
		(start 123.5456 -18.9738)
		(end 123.528074 -18.956274)
		(width 0.508)
		(layer "B.Cu")
		(net "P3V3")
	)
	(segment
		(start 121.623074 -18.956274)
		(end 121.13514 -18.46834)
		(width 0.508)
		(layer "B.Cu")
		(net "P3V3")
	)
	(segment
		(start 123.528074 -18.956274)
		(end 121.623074 -18.956274)
		(width 0.508)
		(layer "B.Cu")
		(net "P3V3")
	)
	(segment
		(start 6.750304 -116.181124)
		(end 10.790428 -112.141)
		(width 0.508)
		(layer "B.Cu")
		(net "P3V3")
	)
	(segment
		(start 121.13514 -18.46834)
		(end 112.455198 -18.46834)
		(width 0.508)
		(layer "B.Cu")
		(net "P3V3")
	)
	(segment
		(start 30.4927 -112.141)
		(end 31.434024 -111.199676)
		(width 0.508)
		(layer "B.Cu")
		(net "P3V3")
	)
	(segment
		(start 54.681628 -111.199676)
		(end 55.076852 -111.5949)
		(width 0.508)
		(layer "B.Cu")
		(net "P3V3")
	)
	(segment
		(start 62.8523 -111.5949)
		(end 63.9318 -112.6744)
		(width 0.508)
		(layer "B.Cu")
		(net "P3V3")
	)
	(segment
		(start 112.455198 -18.46834)
		(end 110.0836 -16.096742)
		(width 0.508)
		(layer "B.Cu")
		(net "P3V3")
	)
	(segment
		(start 31.434024 -111.199676)
		(end 54.681628 -111.199676)
		(width 0.508)
		(layer "B.Cu")
		(net "P3V3")
	)
	(segment
		(start 10.790428 -112.141)
		(end 30.4927 -112.141)
		(width 0.508)
		(layer "B.Cu")
		(net "P3V3")
	)
	(segment
		(start 55.076852 -111.5949)
		(end 62.8523 -111.5949)
		(width 0.508)
		(layer "B.Cu")
		(net "P3V3")
	)
	(segment
		(start 192.6844 -15.5702)
		(end 193.185034 -15.069566)
		(width 0.508)
		(layer "In2.Cu")
		(net "P3V3")
	)
	(segment
		(start 157.8864 -90.667332)
		(end 157.8864 -86.792816)
		(width 0.508)
		(layer "In2.Cu")
		(net "P3V3")
	)
	(segment
		(start 189.62116 -11.97864)
		(end 189.611 -11.9888)
		(width 0.508)
		(layer "In2.Cu")
		(net "P3V3")
	)
	(segment
		(start 151.694642 -46.912022)
		(end 149.5298 -44.74718)
		(width 0.508)
		(layer "In2.Cu")
		(net "P3V3")
	)
	(segment
		(start 149.5298 -44.74718)
		(end 149.5298 -24.5237)
		(width 0.508)
		(layer "In2.Cu")
		(net "P3V3")
	)
	(segment
		(start 157.8864 -86.792816)
		(end 156.973778 -85.880194)
		(width 0.508)
		(layer "In2.Cu")
		(net "P3V3")
	)
	(segment
		(start 158.189676 -95.985076)
		(end 156.2481 -94.0435)
		(width 0.508)
		(layer "In2.Cu")
		(net "P3V3")
	)
	(segment
		(start 193.0908 -13.3604)
		(end 191.70904 -11.97864)
		(width 0.508)
		(layer "In2.Cu")
		(net "P3V3")
	)
	(segment
		(start 203.962 -29.7434)
		(end 198.0692 -23.8506)
		(width 0.508)
		(layer "In2.Cu")
		(net "P3V3")
	)
	(segment
		(start 193.7766 -23.8506)
		(end 192.6844 -22.7584)
		(width 0.508)
		(layer "In2.Cu")
		(net "P3V3")
	)
	(segment
		(start 156.973778 -85.880194)
		(end 155.226004 -85.880194)
		(width 0.508)
		(layer "In2.Cu")
		(net "P3V3")
	)
	(segment
		(start 158.189676 -98.372676)
		(end 158.189676 -95.985076)
		(width 0.508)
		(layer "In2.Cu")
		(net "P3V3")
	)
	(segment
		(start 170.053 -114.7826)
		(end 170.053 -128.0414)
		(width 0.508)
		(layer "In2.Cu")
		(net "P3V3")
	)
	(segment
		(start 160.57372 -101.083872)
		(end 167.095932 -101.083872)
		(width 0.508)
		(layer "In2.Cu")
		(net "P3V3")
	)
	(segment
		(start 198.0692 -23.8506)
		(end 193.7766 -23.8506)
		(width 0.508)
		(layer "In2.Cu")
		(net "P3V3")
	)
	(segment
		(start 156.2481 -94.0435)
		(end 156.2481 -92.5068)
		(width 0.508)
		(layer "In2.Cu")
		(net "P3V3")
	)
	(segment
		(start 51.6636 -165.8112)
		(end 52.324 -166.4716)
		(width 0.508)
		(layer "In2.Cu")
		(net "P3V3")
	)
	(segment
		(start 146.3675 -11.049)
		(end 146.1897 -10.8712)
		(width 0.508)
		(layer "In2.Cu")
		(net "P3V3")
	)
	(segment
		(start 151.694642 -82.348832)
		(end 151.694642 -46.912022)
		(width 0.508)
		(layer "In2.Cu")
		(net "P3V3")
	)
	(segment
		(start 170.053 -128.0414)
		(end 170.815 -128.8034)
		(width 0.508)
		(layer "In2.Cu")
		(net "P3V3")
	)
	(segment
		(start 160.57372 -100.75672)
		(end 158.189676 -98.372676)
		(width 0.508)
		(layer "In2.Cu")
		(net "P3V3")
	)
	(segment
		(start 52.324 -166.4716)
		(end 52.324 -167.8432)
		(width 0.508)
		(layer "In2.Cu")
		(net "P3V3")
	)
	(segment
		(start 145.923 -20.9169)
		(end 145.923 -18.8214)
		(width 0.508)
		(layer "In2.Cu")
		(net "P3V3")
	)
	(segment
		(start 172.466 -106.45394)
		(end 172.466 -112.3696)
		(width 0.508)
		(layer "In2.Cu")
		(net "P3V3")
	)
	(segment
		(start 52.324 -167.8432)
		(end 52.4002 -167.9194)
		(width 0.508)
		(layer "In2.Cu")
		(net "P3V3")
	)
	(segment
		(start 145.923 -18.8214)
		(end 146.3675 -18.3769)
		(width 0.508)
		(layer "In2.Cu")
		(net "P3V3")
	)
	(segment
		(start 193.0908 -13.42644)
		(end 193.0908 -13.3604)
		(width 0.508)
		(layer "In2.Cu")
		(net "P3V3")
	)
	(segment
		(start 146.3675 -18.3769)
		(end 146.3675 -11.049)
		(width 0.508)
		(layer "In2.Cu")
		(net "P3V3")
	)
	(segment
		(start 193.185034 -13.520674)
		(end 193.0908 -13.42644)
		(width 0.508)
		(layer "In2.Cu")
		(net "P3V3")
	)
	(segment
		(start 193.185034 -15.069566)
		(end 193.185034 -13.520674)
		(width 0.508)
		(layer "In2.Cu")
		(net "P3V3")
	)
	(segment
		(start 156.2481 -92.5068)
		(end 156.2481 -92.305632)
		(width 0.508)
		(layer "In2.Cu")
		(net "P3V3")
	)
	(segment
		(start 155.226004 -85.880194)
		(end 151.694642 -82.348832)
		(width 0.508)
		(layer "In2.Cu")
		(net "P3V3")
	)
	(segment
		(start 160.57372 -101.083872)
		(end 160.57372 -100.75672)
		(width 0.508)
		(layer "In2.Cu")
		(net "P3V3")
	)
	(segment
		(start 156.2481 -92.305632)
		(end 157.8864 -90.667332)
		(width 0.508)
		(layer "In2.Cu")
		(net "P3V3")
	)
	(segment
		(start 191.70904 -11.97864)
		(end 189.62116 -11.97864)
		(width 0.508)
		(layer "In2.Cu")
		(net "P3V3")
	)
	(segment
		(start 149.5298 -24.5237)
		(end 145.923 -20.9169)
		(width 0.508)
		(layer "In2.Cu")
		(net "P3V3")
	)
	(segment
		(start 172.466 -112.3696)
		(end 170.053 -114.7826)
		(width 0.508)
		(layer "In2.Cu")
		(net "P3V3")
	)
	(segment
		(start 51.6636 -164.9984)
		(end 51.6636 -165.8112)
		(width 0.508)
		(layer "In2.Cu")
		(net "P3V3")
	)
	(segment
		(start 167.095932 -101.083872)
		(end 172.466 -106.45394)
		(width 0.508)
		(layer "In2.Cu")
		(net "P3V3")
	)
	(segment
		(start 192.6844 -22.7584)
		(end 192.6844 -15.5702)
		(width 0.508)
		(layer "In2.Cu")
		(net "P3V3")
	)
	(segment
		(start 5.607304 -117.324124)
		(end 6.750304 -116.181124)
		(width 0.508)
		(layer "In5.Cu")
		(net "P3V3")
	)
	(segment
		(start 67.8815 -112.3569)
		(end 67.0306 -113.2078)
		(width 0.508)
		(layer "In5.Cu")
		(net "P3V3")
	)
	(segment
		(start 77.30109 -101.698552)
		(end 81.477612 -101.698552)
		(width 0.508)
		(layer "In5.Cu")
		(net "P3V3")
	)
	(segment
		(start 131.454906 -22.772878)
		(end 132.50799 -21.719794)
		(width 0.508)
		(layer "In5.Cu")
		(net "P3V3")
	)
	(segment
		(start 33.439354 -165.982142)
		(end 30.690312 -163.2331)
		(width 0.508)
		(layer "In5.Cu")
		(net "P3V3")
	)
	(segment
		(start 123.5456 -19.10969)
		(end 127.208788 -22.772878)
		(width 0.508)
		(layer "In5.Cu")
		(net "P3V3")
	)
	(segment
		(start 127.208788 -22.772878)
		(end 131.454906 -22.772878)
		(width 0.508)
		(layer "In5.Cu")
		(net "P3V3")
	)
	(segment
		(start 74.09942 -112.3569)
		(end 67.8815 -112.3569)
		(width 0.508)
		(layer "In5.Cu")
		(net "P3V3")
	)
	(segment
		(start 89.41308 -31.196026)
		(end 95.782384 -24.826722)
		(width 0.508)
		(layer "In5.Cu")
		(net "P3V3")
	)
	(segment
		(start 227.965 -51.198018)
		(end 206.510382 -29.7434)
		(width 0.508)
		(layer "In5.Cu")
		(net "P3V3")
	)
	(segment
		(start 86.28634 -32.692848)
		(end 87.783162 -31.196026)
		(width 0.508)
		(layer "In5.Cu")
		(net "P3V3")
	)
	(segment
		(start 183.698896 -9.62787)
		(end 155.114498 -9.62787)
		(width 0.508)
		(layer "In5.Cu")
		(net "P3V3")
	)
	(segment
		(start 46.609 -169.418)
		(end 43.173142 -165.982142)
		(width 0.508)
		(layer "In5.Cu")
		(net "P3V3")
	)
	(segment
		(start 86.28634 -41.62806)
		(end 86.28634 -32.692848)
		(width 0.508)
		(layer "In5.Cu")
		(net "P3V3")
	)
	(segment
		(start 227.965 -77.380338)
		(end 228.490526 -76.854812)
		(width 0.508)
		(layer "In5.Cu")
		(net "P3V3")
	)
	(segment
		(start 30.690312 -163.2331)
		(end 29.5529 -163.2331)
		(width 0.508)
		(layer "In5.Cu")
		(net "P3V3")
	)
	(segment
		(start 27.5336 -161.2138)
		(end 19.0754 -161.2138)
		(width 0.508)
		(layer "In5.Cu")
		(net "P3V3")
	)
	(segment
		(start 7.27075 -149.409404)
		(end 5.607304 -147.745958)
		(width 0.508)
		(layer "In5.Cu")
		(net "P3V3")
	)
	(segment
		(start 75.319128 -99.71659)
		(end 77.30109 -101.698552)
		(width 0.508)
		(layer "In5.Cu")
		(net "P3V3")
	)
	(segment
		(start 77.646022 -108.810298)
		(end 74.09942 -112.3569)
		(width 0.508)
		(layer "In5.Cu")
		(net "P3V3")
	)
	(segment
		(start 81.68767 -108.810298)
		(end 77.646022 -108.810298)
		(width 0.508)
		(layer "In5.Cu")
		(net "P3V3")
	)
	(segment
		(start 75.319128 -58.843672)
		(end 75.319128 -99.71659)
		(width 0.508)
		(layer "In5.Cu")
		(net "P3V3")
	)
	(segment
		(start 123.5456 -18.9738)
		(end 123.5456 -19.10969)
		(width 0.508)
		(layer "In5.Cu")
		(net "P3V3")
	)
	(segment
		(start 137.107676 -20.255738)
		(end 137.107676 -15.823946)
		(width 0.508)
		(layer "In5.Cu")
		(net "P3V3")
	)
	(segment
		(start 227.965 -79.570072)
		(end 227.965 -77.380338)
		(width 0.508)
		(layer "In5.Cu")
		(net "P3V3")
	)
	(segment
		(start 206.510382 -29.7434)
		(end 203.962 -29.7434)
		(width 0.508)
		(layer "In5.Cu")
		(net "P3V3")
	)
	(segment
		(start 132.50799 -21.719794)
		(end 135.64362 -21.719794)
		(width 0.508)
		(layer "In5.Cu")
		(net "P3V3")
	)
	(segment
		(start 228.490526 -76.307188)
		(end 227.965 -75.781662)
		(width 0.508)
		(layer "In5.Cu")
		(net "P3V3")
	)
	(segment
		(start 52.4002 -167.9194)
		(end 50.9016 -169.418)
		(width 0.508)
		(layer "In5.Cu")
		(net "P3V3")
	)
	(segment
		(start 95.782384 -24.826722)
		(end 97.803462 -24.826722)
		(width 0.508)
		(layer "In5.Cu")
		(net "P3V3")
	)
	(segment
		(start 146.188938 -10.871962)
		(end 146.1897 -10.8712)
		(width 0.508)
		(layer "In5.Cu")
		(net "P3V3")
	)
	(segment
		(start 85.060028 -49.688496)
		(end 85.060028 -42.854372)
		(width 0.508)
		(layer "In5.Cu")
		(net "P3V3")
	)
	(segment
		(start 87.783162 -31.196026)
		(end 89.41308 -31.196026)
		(width 0.508)
		(layer "In5.Cu")
		(net "P3V3")
	)
	(segment
		(start 81.477612 -101.698552)
		(end 83.501738 -103.722678)
		(width 0.508)
		(layer "In5.Cu")
		(net "P3V3")
	)
	(segment
		(start 85.060028 -42.854372)
		(end 86.28634 -41.62806)
		(width 0.508)
		(layer "In5.Cu")
		(net "P3V3")
	)
	(segment
		(start 67.0306 -113.2078)
		(end 64.4652 -113.2078)
		(width 0.508)
		(layer "In5.Cu")
		(net "P3V3")
	)
	(segment
		(start 189.611 -11.9888)
		(end 186.059826 -11.9888)
		(width 0.508)
		(layer "In5.Cu")
		(net "P3V3")
	)
	(segment
		(start 83.501738 -106.99623)
		(end 81.68767 -108.810298)
		(width 0.508)
		(layer "In5.Cu")
		(net "P3V3")
	)
	(segment
		(start 135.64362 -21.719794)
		(end 137.107676 -20.255738)
		(width 0.508)
		(layer "In5.Cu")
		(net "P3V3")
	)
	(segment
		(start 137.107676 -15.823946)
		(end 142.05966 -10.871962)
		(width 0.508)
		(layer "In5.Cu")
		(net "P3V3")
	)
	(segment
		(start 171.3484 -128.27)
		(end 170.815 -128.8034)
		(width 0.508)
		(layer "In5.Cu")
		(net "P3V3")
	)
	(segment
		(start 225.721672 -81.8134)
		(end 227.965 -79.570072)
		(width 0.508)
		(layer "In5.Cu")
		(net "P3V3")
	)
	(segment
		(start 64.4652 -113.2078)
		(end 63.9318 -112.6744)
		(width 0.508)
		(layer "In5.Cu")
		(net "P3V3")
	)
	(segment
		(start 77.643228 -56.914796)
		(end 77.248004 -56.914796)
		(width 0.508)
		(layer "In5.Cu")
		(net "P3V3")
	)
	(segment
		(start 29.5529 -163.2331)
		(end 27.5336 -161.2138)
		(width 0.508)
		(layer "In5.Cu")
		(net "P3V3")
	)
	(segment
		(start 83.501738 -103.722678)
		(end 83.501738 -106.99623)
		(width 0.508)
		(layer "In5.Cu")
		(net "P3V3")
	)
	(segment
		(start 50.9016 -169.418)
		(end 46.609 -169.418)
		(width 0.508)
		(layer "In5.Cu")
		(net "P3V3")
	)
	(segment
		(start 153.871168 -10.8712)
		(end 146.1897 -10.8712)
		(width 0.508)
		(layer "In5.Cu")
		(net "P3V3")
	)
	(segment
		(start 175.9204 -128.27)
		(end 171.3484 -128.27)
		(width 0.508)
		(layer "In5.Cu")
		(net "P3V3")
	)
	(segment
		(start 19.0754 -161.2138)
		(end 7.271004 -149.409404)
		(width 0.508)
		(layer "In5.Cu")
		(net "P3V3")
	)
	(segment
		(start 97.803462 -24.826722)
		(end 106.533442 -16.096742)
		(width 0.508)
		(layer "In5.Cu")
		(net "P3V3")
	)
	(segment
		(start 186.059826 -11.9888)
		(end 183.698896 -9.62787)
		(width 0.508)
		(layer "In5.Cu")
		(net "P3V3")
	)
	(segment
		(start 227.965 -75.781662)
		(end 227.965 -51.198018)
		(width 0.508)
		(layer "In5.Cu")
		(net "P3V3")
	)
	(segment
		(start 43.173142 -165.982142)
		(end 33.439354 -165.982142)
		(width 0.508)
		(layer "In5.Cu")
		(net "P3V3")
	)
	(segment
		(start 5.607304 -147.745958)
		(end 5.607304 -117.324124)
		(width 0.508)
		(layer "In5.Cu")
		(net "P3V3")
	)
	(segment
		(start 155.114498 -9.62787)
		(end 153.871168 -10.8712)
		(width 0.508)
		(layer "In5.Cu")
		(net "P3V3")
	)
	(segment
		(start 228.490526 -76.854812)
		(end 228.490526 -76.307188)
		(width 0.508)
		(layer "In5.Cu")
		(net "P3V3")
	)
	(segment
		(start 176.784 -129.1336)
		(end 175.9204 -128.27)
		(width 0.508)
		(layer "In5.Cu")
		(net "P3V3")
	)
	(segment
		(start 77.248004 -56.914796)
		(end 75.319128 -58.843672)
		(width 0.508)
		(layer "In5.Cu")
		(net "P3V3")
	)
	(segment
		(start 7.271004 -149.409404)
		(end 7.27075 -149.409404)
		(width 0.508)
		(layer "In5.Cu")
		(net "P3V3")
	)
	(segment
		(start 85.123528 -49.751996)
		(end 85.060028 -49.688496)
		(width 0.508)
		(layer "In5.Cu")
		(net "P3V3")
	)
	(segment
		(start 106.533442 -16.096742)
		(end 110.0836 -16.096742)
		(width 0.508)
		(layer "In5.Cu")
		(net "P3V3")
	)
	(segment
		(start 142.05966 -10.871962)
		(end 146.188938 -10.871962)
		(width 0.508)
		(layer "In5.Cu")
		(net "P3V3")
	)
	(segment
		(start 50.0126 -167.8178)
		(end 49.948592 -167.753792)
		(width 0.508)
		(layer "F.Cu")
		(net "P2V5_STBY")
	)
	(segment
		(start 24.478234 -136.117838)
		(end 24.478234 -135.667496)
		(width 0.3048)
		(layer "F.Cu")
		(net "P2V5_STBY")
	)
	(segment
		(start 49.948592 -167.753792)
		(end 49.948592 -166.896034)
		(width 0.508)
		(layer "F.Cu")
		(net "P2V5_STBY")
	)
	(segment
		(start 23.234396 -137.361676)
		(end 24.478234 -136.117838)
		(width 0.3048)
		(layer "F.Cu")
		(net "P2V5_STBY")
	)
	(segment
		(start 50.0126 -167.9829)
		(end 50.0126 -167.8178)
		(width 0.508)
		(layer "F.Cu")
		(net "P2V5_STBY")
	)
	(via
		(at 77.2541 -171.3738)
		(size 0.7112)
		(drill 0.4064)
		(layers "F.Cu" "B.Cu")
		(net "P2V5_STBY")
	)
	(via
		(at 31.09849 -169.362628)
		(size 0.7112)
		(drill 0.4064)
		(layers "F.Cu" "B.Cu")
		(net "P2V5_STBY")
	)
	(via
		(at 15.0368 -147.8788)
		(size 0.508)
		(drill 0.254)
		(layers "F.Cu" "B.Cu")
		(net "P2V5_STBY")
	)
	(via
		(at 76.0349 -171.3738)
		(size 0.7112)
		(drill 0.4064)
		(layers "F.Cu" "B.Cu")
		(net "P2V5_STBY")
	)
	(via
		(at 28.6639 -162.937952)
		(size 0.6604)
		(drill 0.3302)
		(layers "F.Cu" "B.Cu")
		(net "P2V5_STBY")
	)
	(via
		(at 24.478234 -135.667496)
		(size 0.508)
		(drill 0.254)
		(layers "F.Cu" "B.Cu")
		(net "P2V5_STBY")
	)
	(via
		(at 31.09849 -168.143428)
		(size 0.7112)
		(drill 0.4064)
		(layers "F.Cu" "B.Cu")
		(net "P2V5_STBY")
	)
	(via
		(at 50.0126 -167.9829)
		(size 0.508)
		(drill 0.254)
		(layers "F.Cu" "B.Cu")
		(net "P2V5_STBY")
	)
	(via
		(at 13.538708 -144.098518)
		(size 0.508)
		(drill 0.254)
		(layers "F.Cu" "B.Cu")
		(net "P2V5_STBY")
	)
	(segment
		(start 13.538708 -144.098518)
		(end 13.538454 -144.098264)
		(width 0.762)
		(layer "B.Cu")
		(net "P2V5_STBY")
	)
	(segment
		(start 24.910034 -136.099296)
		(end 24.478234 -135.667496)
		(width 0.508)
		(layer "B.Cu")
		(net "P2V5_STBY")
	)
	(segment
		(start 25.317196 -136.099296)
		(end 24.910034 -136.099296)
		(width 0.508)
		(layer "B.Cu")
		(net "P2V5_STBY")
	)
	(segment
		(start 13.538454 -144.098264)
		(end 12.107672 -144.098264)
		(width 0.762)
		(layer "B.Cu")
		(net "P2V5_STBY")
	)
	(segment
		(start 25.4635 -134.8613)
		(end 26.269188 -134.055612)
		(width 1.016)
		(layer "In2.Cu")
		(net "P2V5_STBY")
	)
	(segment
		(start 26.269188 -134.055612)
		(end 26.269188 -132.060188)
		(width 1.016)
		(layer "In2.Cu")
		(net "P2V5_STBY")
	)
	(segment
		(start 13.5255 -131.0132)
		(end 12.2428 -132.2959)
		(width 1.016)
		(layer "In2.Cu")
		(net "P2V5_STBY")
	)
	(segment
		(start 26.269188 -132.060188)
		(end 25.2222 -131.0132)
		(width 1.016)
		(layer "In2.Cu")
		(net "P2V5_STBY")
	)
	(segment
		(start 15.0368 -145.59661)
		(end 13.538708 -144.098518)
		(width 1.016)
		(layer "In2.Cu")
		(net "P2V5_STBY")
	)
	(segment
		(start 12.2428 -142.80261)
		(end 13.538708 -144.098518)
		(width 1.016)
		(layer "In2.Cu")
		(net "P2V5_STBY")
	)
	(segment
		(start 12.2428 -132.2959)
		(end 12.2428 -142.80261)
		(width 1.016)
		(layer "In2.Cu")
		(net "P2V5_STBY")
	)
	(segment
		(start 15.0368 -147.8788)
		(end 15.0368 -145.59661)
		(width 1.016)
		(layer "In2.Cu")
		(net "P2V5_STBY")
	)
	(segment
		(start 25.2222 -131.0132)
		(end 13.5255 -131.0132)
		(width 1.016)
		(layer "In2.Cu")
		(net "P2V5_STBY")
	)
	(segment
		(start 155.956 -86.5759)
		(end 156.1465 -86.5759)
		(width 0.508)
		(layer "F.Cu")
		(net "P1V8")
	)
	(segment
		(start 184.399936 -60.700158)
		(end 184.399936 -60.699904)
		(width 0.3048)
		(layer "F.Cu")
		(net "P1V8")
	)
	(segment
		(start 156.1465 -86.5759)
		(end 156.6926 -87.122)
		(width 0.508)
		(layer "F.Cu")
		(net "P1V8")
	)
	(segment
		(start 184.00014 -59.500008)
		(end 184.399936 -59.100212)
		(width 0.3048)
		(layer "F.Cu")
		(net "P1V8")
	)
	(segment
		(start 176.2379 -58.0136)
		(end 175.9966 -58.0136)
		(width 0.508)
		(layer "F.Cu")
		(net "P1V8")
	)
	(segment
		(start 207.767936 -98.039936)
		(end 207.6958 -97.9678)
		(width 0.508)
		(layer "F.Cu")
		(net "P1V8")
	)
	(segment
		(start 92.234258 -86.951058)
		(end 92.7608 -87.4776)
		(width 0.254)
		(layer "F.Cu")
		(net "P1V8")
	)
	(segment
		(start 193.60007 -56.300116)
		(end 193.200274 -56.699912)
		(width 0.3048)
		(layer "F.Cu")
		(net "P1V8")
	)
	(segment
		(start 186.399678 -73.899776)
		(end 186.799728 -74.299826)
		(width 0.3048)
		(layer "F.Cu")
		(net "P1V8")
	)
	(segment
		(start 141.64564 -13.62202)
		(end 141.64564 -12.58316)
		(width 0.4064)
		(layer "F.Cu")
		(net "P1V8")
	)
	(segment
		(start 185.928 -47.9933)
		(end 185.928 -47.2186)
		(width 0.508)
		(layer "F.Cu")
		(net "P1V8")
	)
	(segment
		(start 183.600344 -64.699896)
		(end 184.00014 -64.3001)
		(width 0.3048)
		(layer "F.Cu")
		(net "P1V8")
	)
	(segment
		(start 86.838028 -63.770256)
		(end 88.654128 -63.770256)
		(width 0.254)
		(layer "F.Cu")
		(net "P1V8")
	)
	(segment
		(start 186.799728 -56.699912)
		(end 186.799982 -56.699912)
		(width 0.3048)
		(layer "F.Cu")
		(net "P1V8")
	)
	(segment
		(start 207.776064 -98.97618)
		(end 209.6262 -98.97618)
		(width 0.508)
		(layer "F.Cu")
		(net "P1V8")
	)
	(segment
		(start 183.60009 -58.299858)
		(end 183.600344 -58.299858)
		(width 0.3048)
		(layer "F.Cu")
		(net "P1V8")
	)
	(segment
		(start 183.600344 -58.299858)
		(end 184.00014 -57.900062)
		(width 0.3048)
		(layer "F.Cu")
		(net "P1V8")
	)
	(segment
		(start 154.708098 -94.065598)
		(end 154.708098 -94.190058)
		(width 0.508)
		(layer "F.Cu")
		(net "P1V8")
	)
	(segment
		(start 184.00014 -67.499992)
		(end 184.399936 -67.100196)
		(width 0.3556)
		(layer "F.Cu")
		(net "P1V8")
	)
	(segment
		(start 184.399936 -63.900304)
		(end 184.399936 -63.90005)
		(width 0.3048)
		(layer "F.Cu")
		(net "P1V8")
	)
	(segment
		(start 185.600086 -56.300116)
		(end 185.999882 -55.90032)
		(width 0.3048)
		(layer "F.Cu")
		(net "P1V8")
	)
	(segment
		(start 183.600344 -66.299842)
		(end 184.00014 -65.900046)
		(width 0.3556)
		(layer "F.Cu")
		(net "P1V8")
	)
	(segment
		(start 201.99985 -59.10072)
		(end 201.600054 -59.500516)
		(width 0.254)
		(layer "F.Cu")
		(net "P1V8")
	)
	(segment
		(start 183.60009 -64.699896)
		(end 183.600344 -64.699896)
		(width 0.3048)
		(layer "F.Cu")
		(net "P1V8")
	)
	(segment
		(start 184.399936 -55.90032)
		(end 184.399936 -55.900066)
		(width 0.3048)
		(layer "F.Cu")
		(net "P1V8")
	)
	(segment
		(start 201.99985 -57.50052)
		(end 201.99985 -57.500012)
		(width 0.3048)
		(layer "F.Cu")
		(net "P1V8")
	)
	(segment
		(start 184.00014 -61.099954)
		(end 184.399936 -60.700158)
		(width 0.3048)
		(layer "F.Cu")
		(net "P1V8")
	)
	(segment
		(start 192.39992 -55.90032)
		(end 192.39992 -55.900066)
		(width 0.3048)
		(layer "F.Cu")
		(net "P1V8")
	)
	(segment
		(start 173.124368 -61.11875)
		(end 173.124368 -62.114938)
		(width 0.508)
		(layer "F.Cu")
		(net "P1V8")
	)
	(segment
		(start 185.199782 -74.299826)
		(end 185.200036 -74.299826)
		(width 0.3048)
		(layer "F.Cu")
		(net "P1V8")
	)
	(segment
		(start 173.23562 -64.42202)
		(end 173.2153 -64.4017)
		(width 0.508)
		(layer "F.Cu")
		(net "P1V8")
	)
	(segment
		(start 174.0281 -65.913)
		(end 174.0281 -64.897)
		(width 0.508)
		(layer "F.Cu")
		(net "P1V8")
	)
	(segment
		(start 185.200036 -56.699912)
		(end 185.20029 -56.699912)
		(width 0.3048)
		(layer "F.Cu")
		(net "P1V8")
	)
	(segment
		(start 82.662268 -30.948884)
		(end 82.662268 -9.092692)
		(width 0.254)
		(layer "F.Cu")
		(net "P1V8")
	)
	(segment
		(start 173.074838 -61.06922)
		(end 173.124368 -61.11875)
		(width 0.508)
		(layer "F.Cu")
		(net "P1V8")
	)
	(segment
		(start 186.399932 -56.300116)
		(end 186.799728 -56.699912)
		(width 0.3048)
		(layer "F.Cu")
		(net "P1V8")
	)
	(segment
		(start 174.0789 -72.6186)
		(end 174.116238 -72.581262)
		(width 0.508)
		(layer "F.Cu")
		(net "P1V8")
	)
	(segment
		(start 88.654128 -63.770256)
		(end 88.672924 -63.789052)
		(width 0.254)
		(layer "F.Cu")
		(net "P1V8")
	)
	(segment
		(start 184.001664 -74.7014)
		(end 184.798462 -74.7014)
		(width 0.2032)
		(layer "F.Cu")
		(net "P1V8")
	)
	(segment
		(start 176.2252 -50.62728)
		(end 175.9712 -50.88128)
		(width 0.508)
		(layer "F.Cu")
		(net "P1V8")
	)
	(segment
		(start 175.9966 -58.0136)
		(end 175.4124 -58.5978)
		(width 0.508)
		(layer "F.Cu")
		(net "P1V8")
	)
	(segment
		(start 184.798462 -74.7014)
		(end 185.200036 -74.299826)
		(width 0.2032)
		(layer "F.Cu")
		(net "P1V8")
	)
	(segment
		(start 200.799954 -56.300116)
		(end 201.19975 -56.699912)
		(width 0.3556)
		(layer "F.Cu")
		(net "P1V8")
	)
	(segment
		(start 173.124368 -62.114938)
		(end 173.124368 -63.180468)
		(width 0.508)
		(layer "F.Cu")
		(net "P1V8")
	)
	(segment
		(start 159.627316 -87.603584)
		(end 159.627316 -88.3412)
		(width 0.254)
		(layer "F.Cu")
		(net "P1V8")
	)
	(segment
		(start 181.37886 -83.38566)
		(end 181.37886 -83.72856)
		(width 0.508)
		(layer "F.Cu")
		(net "P1V8")
	)
	(segment
		(start 201.99985 -55.900066)
		(end 202.3999 -56.300116)
		(width 0.3556)
		(layer "F.Cu")
		(net "P1V8")
	)
	(segment
		(start 141.64564 -12.58316)
		(end 142.1384 -12.0904)
		(width 0.4064)
		(layer "F.Cu")
		(net "P1V8")
	)
	(segment
		(start 184.00014 -57.900062)
		(end 184.399936 -57.500266)
		(width 0.3048)
		(layer "F.Cu")
		(net "P1V8")
	)
	(segment
		(start 176.2379 -60.1599)
		(end 176.2379 -59.0296)
		(width 0.508)
		(layer "F.Cu")
		(net "P1V8")
	)
	(segment
		(start 176.49444 -51.70424)
		(end 175.9204 -51.1302)
		(width 0.508)
		(layer "F.Cu")
		(net "P1V8")
	)
	(segment
		(start 156.724858 -87.154258)
		(end 156.724858 -88.853264)
		(width 0.3048)
		(layer "F.Cu")
		(net "P1V8")
	)
	(segment
		(start 184.00014 -64.3001)
		(end 184.399936 -63.900304)
		(width 0.3048)
		(layer "F.Cu")
		(net "P1V8")
	)
	(segment
		(start 183.60009 -63.09995)
		(end 183.60009 -63.05677)
		(width 0.3048)
		(layer "F.Cu")
		(net "P1V8")
	)
	(segment
		(start 186.443112 -45.439584)
		(end 185.598816 -45.439584)
		(width 0.508)
		(layer "F.Cu")
		(net "P1V8")
	)
	(segment
		(start 194.5513 -28.702)
		(end 193.548 -28.702)
		(width 0.508)
		(layer "F.Cu")
		(net "P1V8")
	)
	(segment
		(start 207.767936 -98.984308)
		(end 207.776064 -98.97618)
		(width 0.508)
		(layer "F.Cu")
		(net "P1V8")
	)
	(segment
		(start 217.678 -103.3399)
		(end 217.678 -104.2924)
		(width 0.508)
		(layer "F.Cu")
		(net "P1V8")
	)
	(segment
		(start 174.0281 -64.897)
		(end 174.0027 -64.8716)
		(width 0.508)
		(layer "F.Cu")
		(net "P1V8")
	)
	(segment
		(start 189.610238 -55.489856)
		(end 190.389764 -55.489856)
		(width 0.2032)
		(layer "F.Cu")
		(net "P1V8")
	)
	(segment
		(start 193.73596 -26.9875)
		(end 193.73596 -28.51404)
		(width 0.3556)
		(layer "F.Cu")
		(net "P1V8")
	)
	(segment
		(start 187.999878 -73.899776)
		(end 188.399928 -74.299826)
		(width 0.3048)
		(layer "F.Cu")
		(net "P1V8")
	)
	(segment
		(start 184.399936 -68.700142)
		(end 184.399936 -68.699888)
		(width 0.3556)
		(layer "F.Cu")
		(net "P1V8")
	)
	(segment
		(start 187.600082 -73.49998)
		(end 187.999878 -73.899776)
		(width 0.3048)
		(layer "F.Cu")
		(net "P1V8")
	)
	(segment
		(start 209.6262 -98.97618)
		(end 209.84718 -98.7552)
		(width 0.508)
		(layer "F.Cu")
		(net "P1V8")
	)
	(segment
		(start 184.00014 -69.099938)
		(end 184.399936 -68.700142)
		(width 0.3556)
		(layer "F.Cu")
		(net "P1V8")
	)
	(segment
		(start 189.200028 -55.900066)
		(end 189.610238 -55.489856)
		(width 0.2032)
		(layer "F.Cu")
		(net "P1V8")
	)
	(segment
		(start 142.0368 -11.9888)
		(end 142.1384 -12.0904)
		(width 0.508)
		(layer "F.Cu")
		(net "P1V8")
	)
	(segment
		(start 183.60009 -72.69988)
		(end 184.00014 -72.29983)
		(width 0.254)
		(layer "F.Cu")
		(net "P1V8")
	)
	(segment
		(start 183.60009 -71.099934)
		(end 184.00014 -70.699884)
		(width 0.3556)
		(layer "F.Cu")
		(net "P1V8")
	)
	(segment
		(start 165.0111 -86.7283)
		(end 160.9852 -86.7283)
		(width 0.508)
		(layer "F.Cu")
		(net "P1V8")
	)
	(segment
		(start 142.0368 -11.1887)
		(end 142.0368 -11.9888)
		(width 0.508)
		(layer "F.Cu")
		(net "P1V8")
	)
	(segment
		(start 179.324 -83.3755)
		(end 178.7271 -83.3755)
		(width 0.508)
		(layer "F.Cu")
		(net "P1V8")
	)
	(segment
		(start 174.116238 -67.348862)
		(end 174.1297 -67.3354)
		(width 0.508)
		(layer "F.Cu")
		(net "P1V8")
	)
	(segment
		(start 160.9852 -86.7283)
		(end 160.530032 -87.183468)
		(width 0.3048)
		(layer "F.Cu")
		(net "P1V8")
	)
	(segment
		(start 175.9712 -50.88128)
		(end 175.9712 -51.0794)
		(width 0.508)
		(layer "F.Cu")
		(net "P1V8")
	)
	(segment
		(start 183.60009 -61.500004)
		(end 184.00014 -61.099954)
		(width 0.3556)
		(layer "F.Cu")
		(net "P1V8")
	)
	(segment
		(start 183.95696 -62.6999)
		(end 184.00014 -62.6999)
		(width 0.3048)
		(layer "F.Cu")
		(net "P1V8")
	)
	(segment
		(start 197.379336 -132.842)
		(end 197.379336 -131.741164)
		(width 0.508)
		(layer "F.Cu")
		(net "P1V8")
	)
	(segment
		(start 198.002906 -62.29985)
		(end 198.406258 -62.703202)
		(width 0.3048)
		(layer "F.Cu")
		(net "P1V8")
	)
	(segment
		(start 189.4078 -47.9933)
		(end 189.4078 -47.2186)
		(width 0.508)
		(layer "F.Cu")
		(net "P1V8")
	)
	(segment
		(start 182.0291 -45.0977)
		(end 182.0291 -44.2976)
		(width 0.508)
		(layer "F.Cu")
		(net "P1V8")
	)
	(segment
		(start 198.798688 -13.9065)
		(end 197.9676 -13.9065)
		(width 0.3556)
		(layer "F.Cu")
		(net "P1V8")
	)
	(segment
		(start 183.600344 -56.699912)
		(end 184.00014 -56.300116)
		(width 0.3048)
		(layer "F.Cu")
		(net "P1V8")
	)
	(segment
		(start 187.600082 -55.900066)
		(end 188.000132 -56.300116)
		(width 0.3556)
		(layer "F.Cu")
		(net "P1V8")
	)
	(segment
		(start 188.399928 -56.699912)
		(end 188.000132 -56.300116)
		(width 0.3556)
		(layer "F.Cu")
		(net "P1V8")
	)
	(segment
		(start 201.995024 -60.699904)
		(end 201.99985 -60.699904)
		(width 0.3048)
		(layer "F.Cu")
		(net "P1V8")
	)
	(segment
		(start 190.4746 -47.9171)
		(end 190.4746 -47.0408)
		(width 0.508)
		(layer "F.Cu")
		(net "P1V8")
	)
	(segment
		(start 161.835338 -103.07701)
		(end 161.788602 -103.123746)
		(width 0.508)
		(layer "F.Cu")
		(net "P1V8")
	)
	(segment
		(start 201.200512 -58.299858)
		(end 201.600054 -57.900316)
		(width 0.3048)
		(layer "F.Cu")
		(net "P1V8")
	)
	(segment
		(start 176.90338 -50.22596)
		(end 176.50206 -50.62728)
		(width 0.508)
		(layer "F.Cu")
		(net "P1V8")
	)
	(segment
		(start 198.799958 -55.900066)
		(end 199.200008 -56.300116)
		(width 0.3048)
		(layer "F.Cu")
		(net "P1V8")
	)
	(segment
		(start 169.5196 -91.2368)
		(end 165.0111 -86.7283)
		(width 0.508)
		(layer "F.Cu")
		(net "P1V8")
	)
	(segment
		(start 201.200004 -61.494924)
		(end 201.592688 -61.10224)
		(width 0.3048)
		(layer "F.Cu")
		(net "P1V8")
	)
	(segment
		(start 154.370532 -94.527624)
		(end 154.370532 -94.852998)
		(width 0.508)
		(layer "F.Cu")
		(net "P1V8")
	)
	(segment
		(start 183.60009 -56.699912)
		(end 183.600344 -56.699912)
		(width 0.3048)
		(layer "F.Cu")
		(net "P1V8")
	)
	(segment
		(start 183.60009 -59.900058)
		(end 184.00014 -59.500008)
		(width 0.3556)
		(layer "F.Cu")
		(net "P1V8")
	)
	(segment
		(start 173.2153 -64.4017)
		(end 173.2153 -63.2714)
		(width 0.508)
		(layer "F.Cu")
		(net "P1V8")
	)
	(segment
		(start 185.999882 -73.49998)
		(end 186.399678 -73.899776)
		(width 0.3048)
		(layer "F.Cu")
		(net "P1V8")
	)
	(segment
		(start 174.116238 -68.38442)
		(end 174.116238 -67.348862)
		(width 0.508)
		(layer "F.Cu")
		(net "P1V8")
	)
	(segment
		(start 184.00014 -56.300116)
		(end 184.399936 -55.90032)
		(width 0.3048)
		(layer "F.Cu")
		(net "P1V8")
	)
	(segment
		(start 197.999858 -62.29985)
		(end 198.002906 -62.29985)
		(width 0.3048)
		(layer "F.Cu")
		(net "P1V8")
	)
	(segment
		(start 184.00014 -65.900046)
		(end 184.399936 -65.50025)
		(width 0.3556)
		(layer "F.Cu")
		(net "P1V8")
	)
	(segment
		(start 190.389764 -55.489856)
		(end 190.799974 -55.900066)
		(width 0.2032)
		(layer "F.Cu")
		(net "P1V8")
	)
	(segment
		(start 92.234258 -66.860166)
		(end 92.234258 -86.951058)
		(width 0.254)
		(layer "F.Cu")
		(net "P1V8")
	)
	(segment
		(start 183.60009 -66.299842)
		(end 183.600344 -66.299842)
		(width 0.3556)
		(layer "F.Cu")
		(net "P1V8")
	)
	(segment
		(start 201.19975 -56.699912)
		(end 201.200004 -56.699912)
		(width 0.3556)
		(layer "F.Cu")
		(net "P1V8")
	)
	(segment
		(start 173.5836 -72.6186)
		(end 173.1772 -73.025)
		(width 0.508)
		(layer "F.Cu")
		(net "P1V8")
	)
	(segment
		(start 184.399936 -67.100196)
		(end 184.399936 -67.099942)
		(width 0.3556)
		(layer "F.Cu")
		(net "P1V8")
	)
	(segment
		(start 200.399904 -55.900066)
		(end 200.799954 -56.300116)
		(width 0.3556)
		(layer "F.Cu")
		(net "P1V8")
	)
	(segment
		(start 186.799728 -74.299826)
		(end 186.799982 -74.299826)
		(width 0.3048)
		(layer "F.Cu")
		(net "P1V8")
	)
	(segment
		(start 184.00014 -72.29983)
		(end 184.399936 -71.900034)
		(width 0.254)
		(layer "F.Cu")
		(net "P1V8")
	)
	(segment
		(start 181.37886 -83.72856)
		(end 180.95214 -84.15528)
		(width 0.508)
		(layer "F.Cu")
		(net "P1V8")
	)
	(segment
		(start 196.977 -47.2694)
		(end 196.2658 -46.5582)
		(width 0.508)
		(layer "F.Cu")
		(net "P1V8")
	)
	(segment
		(start 88.672924 -63.789052)
		(end 89.163144 -63.789052)
		(width 0.254)
		(layer "F.Cu")
		(net "P1V8")
	)
	(segment
		(start 154.74696 -94.065598)
		(end 154.708098 -94.065598)
		(width 0.508)
		(layer "F.Cu")
		(net "P1V8")
	)
	(segment
		(start 176.772062 -53.782722)
		(end 175.575722 -53.782722)
		(width 0.508)
		(layer "F.Cu")
		(net "P1V8")
	)
	(segment
		(start 201.592688 -61.10224)
		(end 201.995024 -60.699904)
		(width 0.3048)
		(layer "F.Cu")
		(net "P1V8")
	)
	(segment
		(start 201.200512 -59.900058)
		(end 201.600054 -59.500516)
		(width 0.3048)
		(layer "F.Cu")
		(net "P1V8")
	)
	(segment
		(start 174.116238 -68.38442)
		(end 174.116238 -69.45122)
		(width 0.508)
		(layer "F.Cu")
		(net "P1V8")
	)
	(segment
		(start 173.1772 -73.025)
		(end 173.1772 -73.1393)
		(width 0.508)
		(layer "F.Cu")
		(net "P1V8")
	)
	(segment
		(start 175.8442 -59.0296)
		(end 176.2379 -59.0296)
		(width 0.508)
		(layer "F.Cu")
		(net "P1V8")
	)
	(segment
		(start 183.60009 -63.05677)
		(end 183.95696 -62.6999)
		(width 0.3048)
		(layer "F.Cu")
		(net "P1V8")
	)
	(segment
		(start 189.999874 -56.699912)
		(end 189.600078 -56.300116)
		(width 0.3048)
		(layer "F.Cu")
		(net "P1V8")
	)
	(segment
		(start 193.73596 -28.51404)
		(end 193.548 -28.702)
		(width 0.3556)
		(layer "F.Cu")
		(net "P1V8")
	)
	(segment
		(start 197.4215 -131.699)
		(end 197.4215 -130.1877)
		(width 0.508)
		(layer "F.Cu")
		(net "P1V8")
	)
	(segment
		(start 175.9712 -51.0794)
		(end 175.9204 -51.1302)
		(width 0.508)
		(layer "F.Cu")
		(net "P1V8")
	)
	(segment
		(start 197.999858 -56.699912)
		(end 197.600062 -56.300116)
		(width 0.3048)
		(layer "F.Cu")
		(net "P1V8")
	)
	(segment
		(start 184.399936 -73.49998)
		(end 184.799732 -73.899776)
		(width 0.3048)
		(layer "F.Cu")
		(net "P1V8")
	)
	(segment
		(start 184.399936 -57.500266)
		(end 184.399936 -57.500012)
		(width 0.3048)
		(layer "F.Cu")
		(net "P1V8")
	)
	(segment
		(start 184.399936 -65.50025)
		(end 184.399936 -65.499996)
		(width 0.3556)
		(layer "F.Cu")
		(net "P1V8")
	)
	(segment
		(start 193.200274 -56.699912)
		(end 193.20002 -56.699912)
		(width 0.3048)
		(layer "F.Cu")
		(net "P1V8")
	)
	(segment
		(start 182.372 -88.8365)
		(end 182.372 -89.662)
		(width 0.508)
		(layer "F.Cu")
		(net "P1V8")
	)
	(segment
		(start 176.8094 -51.70424)
		(end 176.49444 -51.70424)
		(width 0.508)
		(layer "F.Cu")
		(net "P1V8")
	)
	(segment
		(start 82.662268 -9.092692)
		(end 82.944462 -8.810498)
		(width 0.254)
		(layer "F.Cu")
		(net "P1V8")
	)
	(segment
		(start 156.6926 -87.122)
		(end 156.724858 -87.154258)
		(width 0.3048)
		(layer "F.Cu")
		(net "P1V8")
	)
	(segment
		(start 175.4124 -58.5978)
		(end 175.8442 -59.0296)
		(width 0.508)
		(layer "F.Cu")
		(net "P1V8")
	)
	(segment
		(start 196.977 -47.8155)
		(end 196.977 -47.2694)
		(width 0.508)
		(layer "F.Cu")
		(net "P1V8")
	)
	(segment
		(start 183.60009 -74.299826)
		(end 184.001664 -74.7014)
		(width 0.2032)
		(layer "F.Cu")
		(net "P1V8")
	)
	(segment
		(start 178.7271 -83.3755)
		(end 178.3715 -83.7311)
		(width 0.508)
		(layer "F.Cu")
		(net "P1V8")
	)
	(segment
		(start 185.999882 -55.90032)
		(end 185.999882 -55.900066)
		(width 0.3048)
		(layer "F.Cu")
		(net "P1V8")
	)
	(segment
		(start 192.000124 -56.300116)
		(end 192.39992 -55.90032)
		(width 0.3048)
		(layer "F.Cu")
		(net "P1V8")
	)
	(segment
		(start 201.200004 -59.900058)
		(end 201.200512 -59.900058)
		(width 0.3048)
		(layer "F.Cu")
		(net "P1V8")
	)
	(segment
		(start 201.600054 -57.900316)
		(end 201.99985 -57.50052)
		(width 0.3048)
		(layer "F.Cu")
		(net "P1V8")
	)
	(segment
		(start 174.0027 -64.8716)
		(end 173.6852 -64.8716)
		(width 0.508)
		(layer "F.Cu")
		(net "P1V8")
	)
	(segment
		(start 174.116238 -69.45122)
		(end 174.116238 -70.49262)
		(width 0.508)
		(layer "F.Cu")
		(net "P1V8")
	)
	(segment
		(start 191.600074 -56.699912)
		(end 191.600328 -56.699912)
		(width 0.3048)
		(layer "F.Cu")
		(net "P1V8")
	)
	(segment
		(start 189.200028 -73.49998)
		(end 189.599824 -73.899776)
		(width 0.3048)
		(layer "F.Cu")
		(net "P1V8")
	)
	(segment
		(start 185.598816 -45.439584)
		(end 185.5597 -45.4787)
		(width 0.508)
		(layer "F.Cu")
		(net "P1V8")
	)
	(segment
		(start 160.047432 -87.183468)
		(end 159.627316 -87.603584)
		(width 0.254)
		(layer "F.Cu")
		(net "P1V8")
	)
	(segment
		(start 160.530032 -87.183468)
		(end 160.047432 -87.183468)
		(width 0.3048)
		(layer "F.Cu")
		(net "P1V8")
	)
	(segment
		(start 183.60009 -67.900042)
		(end 184.00014 -67.499992)
		(width 0.3556)
		(layer "F.Cu")
		(net "P1V8")
	)
	(segment
		(start 189.599824 -73.899776)
		(end 189.999874 -74.299826)
		(width 0.3048)
		(layer "F.Cu")
		(net "P1V8")
	)
	(segment
		(start 154.708098 -94.190058)
		(end 154.370532 -94.527624)
		(width 0.508)
		(layer "F.Cu")
		(net "P1V8")
	)
	(segment
		(start 184.399936 -59.100212)
		(end 184.399936 -59.099958)
		(width 0.3048)
		(layer "F.Cu")
		(net "P1V8")
	)
	(segment
		(start 185.20029 -56.699912)
		(end 185.600086 -56.300116)
		(width 0.3048)
		(layer "F.Cu")
		(net "P1V8")
	)
	(segment
		(start 174.0789 -72.6186)
		(end 173.5836 -72.6186)
		(width 0.508)
		(layer "F.Cu")
		(net "P1V8")
	)
	(segment
		(start 187.198 -47.9933)
		(end 187.198 -47.2186)
		(width 0.508)
		(layer "F.Cu")
		(net "P1V8")
	)
	(segment
		(start 199.10044 -13.604748)
		(end 198.798688 -13.9065)
		(width 0.3556)
		(layer "F.Cu")
		(net "P1V8")
	)
	(segment
		(start 197.9676 -13.9065)
		(end 197.1548 -13.9065)
		(width 0.508)
		(layer "F.Cu")
		(net "P1V8")
	)
	(segment
		(start 193.5988 -47.9425)
		(end 195.1101 -47.9425)
		(width 0.508)
		(layer "F.Cu")
		(net "P1V8")
	)
	(segment
		(start 191.600328 -56.699912)
		(end 192.000124 -56.300116)
		(width 0.3048)
		(layer "F.Cu")
		(net "P1V8")
	)
	(segment
		(start 84.720176 -33.006792)
		(end 82.662268 -30.948884)
		(width 0.254)
		(layer "F.Cu")
		(net "P1V8")
	)
	(segment
		(start 199.200008 -56.300116)
		(end 199.599804 -56.699912)
		(width 0.3048)
		(layer "F.Cu")
		(net "P1V8")
	)
	(segment
		(start 197.600062 -56.300116)
		(end 197.200012 -55.900066)
		(width 0.3048)
		(layer "F.Cu")
		(net "P1V8")
	)
	(segment
		(start 197.379336 -131.741164)
		(end 197.4215 -131.699)
		(width 0.508)
		(layer "F.Cu")
		(net "P1V8")
	)
	(segment
		(start 197.4215 -130.1877)
		(end 197.5104 -130.0988)
		(width 0.508)
		(layer "F.Cu")
		(net "P1V8")
	)
	(segment
		(start 176.50206 -50.62728)
		(end 176.2252 -50.62728)
		(width 0.508)
		(layer "F.Cu")
		(net "P1V8")
	)
	(segment
		(start 173.6852 -64.8716)
		(end 173.23562 -64.42202)
		(width 0.508)
		(layer "F.Cu")
		(net "P1V8")
	)
	(segment
		(start 171.1706 -77.978)
		(end 170.1673 -78.9813)
		(width 0.508)
		(layer "F.Cu")
		(net "P1V8")
	)
	(segment
		(start 89.163144 -63.789052)
		(end 92.234258 -66.860166)
		(width 0.254)
		(layer "F.Cu")
		(net "P1V8")
	)
	(segment
		(start 207.767936 -98.984308)
		(end 207.767936 -98.039936)
		(width 0.508)
		(layer "F.Cu")
		(net "P1V8")
	)
	(segment
		(start 189.600078 -56.300116)
		(end 189.200028 -55.900066)
		(width 0.3048)
		(layer "F.Cu")
		(net "P1V8")
	)
	(segment
		(start 201.200004 -61.500004)
		(end 201.200004 -61.494924)
		(width 0.3048)
		(layer "F.Cu")
		(net "P1V8")
	)
	(segment
		(start 174.116238 -72.581262)
		(end 174.116238 -71.55942)
		(width 0.508)
		(layer "F.Cu")
		(net "P1V8")
	)
	(segment
		(start 201.200004 -58.299858)
		(end 201.200512 -58.299858)
		(width 0.3048)
		(layer "F.Cu")
		(net "P1V8")
	)
	(segment
		(start 88.698324 -33.006792)
		(end 84.720176 -33.006792)
		(width 0.254)
		(layer "F.Cu")
		(net "P1V8")
	)
	(segment
		(start 184.799732 -73.899776)
		(end 185.199782 -74.299826)
		(width 0.3048)
		(layer "F.Cu")
		(net "P1V8")
	)
	(segment
		(start 195.1101 -47.9425)
		(end 195.3514 -47.7012)
		(width 0.508)
		(layer "F.Cu")
		(net "P1V8")
	)
	(segment
		(start 184.399936 -70.300088)
		(end 184.399936 -70.299834)
		(width 0.3556)
		(layer "F.Cu")
		(net "P1V8")
	)
	(segment
		(start 185.999882 -55.900066)
		(end 186.399932 -56.300116)
		(width 0.3048)
		(layer "F.Cu")
		(net "P1V8")
	)
	(segment
		(start 173.124368 -63.180468)
		(end 173.2153 -63.2714)
		(width 0.508)
		(layer "F.Cu")
		(net "P1V8")
	)
	(segment
		(start 174.116238 -71.55942)
		(end 174.116238 -70.49262)
		(width 0.508)
		(layer "F.Cu")
		(net "P1V8")
	)
	(segment
		(start 201.99985 -59.099958)
		(end 201.99985 -59.10072)
		(width 0.254)
		(layer "F.Cu")
		(net "P1V8")
	)
	(segment
		(start 183.60009 -69.499988)
		(end 184.00014 -69.099938)
		(width 0.3556)
		(layer "F.Cu")
		(net "P1V8")
	)
	(segment
		(start 199.599804 -56.699912)
		(end 199.600058 -56.699912)
		(width 0.3048)
		(layer "F.Cu")
		(net "P1V8")
	)
	(segment
		(start 184.00014 -70.699884)
		(end 184.399936 -70.300088)
		(width 0.3556)
		(layer "F.Cu")
		(net "P1V8")
	)
	(segment
		(start 209.84718 -98.7552)
		(end 210.8962 -98.7552)
		(width 0.508)
		(layer "F.Cu")
		(net "P1V8")
	)
	(segment
		(start 173.4185 -77.978)
		(end 171.1706 -77.978)
		(width 0.508)
		(layer "F.Cu")
		(net "P1V8")
	)
	(segment
		(start 161.835338 -101.662738)
		(end 161.835338 -103.07701)
		(width 0.508)
		(layer "F.Cu")
		(net "P1V8")
	)
	(via
		(at 185.3946 -99.8728)
		(size 0.508)
		(drill 0.254)
		(layers "F.Cu" "B.Cu")
		(net "P1V8")
	)
	(via
		(at 197.600062 -56.300116)
		(size 0.508)
		(drill 0.254)
		(layers "F.Cu" "B.Cu")
		(net "P1V8")
	)
	(via
		(at 182.0291 -44.2976)
		(size 0.508)
		(drill 0.254)
		(layers "F.Cu" "B.Cu")
		(net "P1V8")
	)
	(via
		(at 214.0966 -88.1888)
		(size 0.7112)
		(drill 0.4064)
		(layers "F.Cu" "B.Cu")
		(net "P1V8")
	)
	(via
		(at 171.704 -106.934)
		(size 0.7112)
		(drill 0.4064)
		(layers "F.Cu" "B.Cu")
		(net "P1V8")
	)
	(via
		(at 199.742552 -46.590966)
		(size 0.508)
		(drill 0.254)
		(layers "F.Cu" "B.Cu")
		(net "P1V8")
	)
	(via
		(at 184.00014 -72.29983)
		(size 0.508)
		(drill 0.254)
		(layers "F.Cu" "B.Cu")
		(net "P1V8")
	)
	(via
		(at 88.698324 -33.006792)
		(size 0.508)
		(drill 0.254)
		(layers "F.Cu" "B.Cu")
		(net "P1V8")
	)
	(via
		(at 200.799954 -56.300116)
		(size 0.508)
		(drill 0.254)
		(layers "F.Cu" "B.Cu")
		(net "P1V8")
	)
	(via
		(at 184.00014 -61.099954)
		(size 0.508)
		(drill 0.254)
		(layers "F.Cu" "B.Cu")
		(net "P1V8")
	)
	(via
		(at 157.1244 -92.55125)
		(size 0.508)
		(drill 0.254)
		(layers "F.Cu" "B.Cu")
		(net "P1V8")
	)
	(via
		(at 171.704 -108.204)
		(size 0.7112)
		(drill 0.4064)
		(layers "F.Cu" "B.Cu")
		(net "P1V8")
	)
	(via
		(at 82.944462 -8.810498)
		(size 0.508)
		(drill 0.254)
		(layers "F.Cu" "B.Cu")
		(net "P1V8")
	)
	(via
		(at 203.55179 -46.499018)
		(size 0.508)
		(drill 0.254)
		(layers "F.Cu" "B.Cu")
		(net "P1V8")
	)
	(via
		(at 195.3514 -47.7012)
		(size 0.508)
		(drill 0.254)
		(layers "F.Cu" "B.Cu")
		(net "P1V8")
	)
	(via
		(at 184.00014 -69.099938)
		(size 0.508)
		(drill 0.254)
		(layers "F.Cu" "B.Cu")
		(net "P1V8")
	)
	(via
		(at 178.3715 -83.7311)
		(size 0.508)
		(drill 0.254)
		(layers "F.Cu" "B.Cu")
		(net "P1V8")
	)
	(via
		(at 156.6926 -87.122)
		(size 0.508)
		(drill 0.254)
		(layers "F.Cu" "B.Cu")
		(net "P1V8")
	)
	(via
		(at 198.406258 -62.703202)
		(size 0.508)
		(drill 0.254)
		(layers "F.Cu" "B.Cu")
		(net "P1V8")
	)
	(via
		(at 184.00014 -57.900062)
		(size 0.508)
		(drill 0.254)
		(layers "F.Cu" "B.Cu")
		(net "P1V8")
	)
	(via
		(at 190.4746 -47.0408)
		(size 0.508)
		(drill 0.254)
		(layers "F.Cu" "B.Cu")
		(net "P1V8")
	)
	(via
		(at 161.788602 -103.123746)
		(size 0.508)
		(drill 0.254)
		(layers "F.Cu" "B.Cu")
		(net "P1V8")
	)
	(via
		(at 101.616256 -165.759892)
		(size 0.508)
		(drill 0.254)
		(layers "F.Cu" "B.Cu")
		(net "P1V8")
	)
	(via
		(at 188.000132 -56.300116)
		(size 0.508)
		(drill 0.254)
		(layers "F.Cu" "B.Cu")
		(net "P1V8")
	)
	(via
		(at 183.515 -89.662)
		(size 0.508)
		(drill 0.254)
		(layers "F.Cu" "B.Cu")
		(net "P1V8")
	)
	(via
		(at 201.600054 -59.500516)
		(size 0.508)
		(drill 0.254)
		(layers "F.Cu" "B.Cu")
		(net "P1V8")
	)
	(via
		(at 187.198 -47.2186)
		(size 0.508)
		(drill 0.254)
		(layers "F.Cu" "B.Cu")
		(net "P1V8")
	)
	(via
		(at 197.5104 -130.0988)
		(size 0.508)
		(drill 0.254)
		(layers "F.Cu" "B.Cu")
		(net "P1V8")
	)
	(via
		(at 186.399932 -56.300116)
		(size 0.508)
		(drill 0.254)
		(layers "F.Cu" "B.Cu")
		(net "P1V8")
	)
	(via
		(at 196.29374 -45.694854)
		(size 0.508)
		(drill 0.254)
		(layers "F.Cu" "B.Cu")
		(net "P1V8")
	)
	(via
		(at 186.399678 -73.899776)
		(size 0.508)
		(drill 0.254)
		(layers "F.Cu" "B.Cu")
		(net "P1V8")
	)
	(via
		(at 173.1772 -73.1393)
		(size 0.508)
		(drill 0.254)
		(layers "F.Cu" "B.Cu")
		(net "P1V8")
	)
	(via
		(at 184.00014 -56.300116)
		(size 0.508)
		(drill 0.254)
		(layers "F.Cu" "B.Cu")
		(net "P1V8")
	)
	(via
		(at 184.00014 -59.500008)
		(size 0.508)
		(drill 0.254)
		(layers "F.Cu" "B.Cu")
		(net "P1V8")
	)
	(via
		(at 166.8018 -77.624178)
		(size 0.508)
		(drill 0.254)
		(layers "F.Cu" "B.Cu")
		(net "P1V8")
	)
	(via
		(at 193.548 -28.702)
		(size 0.508)
		(drill 0.254)
		(layers "F.Cu" "B.Cu")
		(net "P1V8")
	)
	(via
		(at 203.54036 -45.617638)
		(size 0.508)
		(drill 0.254)
		(layers "F.Cu" "B.Cu")
		(net "P1V8")
	)
	(via
		(at 193.60007 -56.300116)
		(size 0.508)
		(drill 0.254)
		(layers "F.Cu" "B.Cu")
		(net "P1V8")
	)
	(via
		(at 142.1384 -12.0904)
		(size 0.508)
		(drill 0.254)
		(layers "F.Cu" "B.Cu")
		(net "P1V8")
	)
	(via
		(at 154.74696 -94.065598)
		(size 0.508)
		(drill 0.254)
		(layers "F.Cu" "B.Cu")
		(net "P1V8")
	)
	(via
		(at 185.5597 -45.4787)
		(size 0.508)
		(drill 0.254)
		(layers "F.Cu" "B.Cu")
		(net "P1V8")
	)
	(via
		(at 170.434 -106.934)
		(size 0.7112)
		(drill 0.4064)
		(layers "F.Cu" "B.Cu")
		(net "P1V8")
	)
	(via
		(at 184.00014 -67.499992)
		(size 0.508)
		(drill 0.254)
		(layers "F.Cu" "B.Cu")
		(net "P1V8")
	)
	(via
		(at 184.00014 -70.699884)
		(size 0.508)
		(drill 0.254)
		(layers "F.Cu" "B.Cu")
		(net "P1V8")
	)
	(via
		(at 191.516 -45.085)
		(size 0.7112)
		(drill 0.4064)
		(layers "F.Cu" "B.Cu")
		(net "P1V8")
	)
	(via
		(at 182.372 -89.662)
		(size 0.508)
		(drill 0.254)
		(layers "F.Cu" "B.Cu")
		(net "P1V8")
	)
	(via
		(at 201.600054 -57.900316)
		(size 0.508)
		(drill 0.254)
		(layers "F.Cu" "B.Cu")
		(net "P1V8")
	)
	(via
		(at 175.9204 -51.1302)
		(size 0.508)
		(drill 0.254)
		(layers "F.Cu" "B.Cu")
		(net "P1V8")
	)
	(via
		(at 171.704 -109.474)
		(size 0.7112)
		(drill 0.4064)
		(layers "F.Cu" "B.Cu")
		(net "P1V8")
	)
	(via
		(at 191.516 -43.8658)
		(size 0.7112)
		(drill 0.4064)
		(layers "F.Cu" "B.Cu")
		(net "P1V8")
	)
	(via
		(at 192.000124 -56.300116)
		(size 0.508)
		(drill 0.254)
		(layers "F.Cu" "B.Cu")
		(net "P1V8")
	)
	(via
		(at 201.592688 -61.10224)
		(size 0.508)
		(drill 0.254)
		(layers "F.Cu" "B.Cu")
		(net "P1V8")
	)
	(via
		(at 209.804 -59.2836)
		(size 0.508)
		(drill 0.254)
		(layers "F.Cu" "B.Cu")
		(net "P1V8")
	)
	(via
		(at 185.928 -47.2186)
		(size 0.508)
		(drill 0.254)
		(layers "F.Cu" "B.Cu")
		(net "P1V8")
	)
	(via
		(at 184.00014 -64.3001)
		(size 0.508)
		(drill 0.254)
		(layers "F.Cu" "B.Cu")
		(net "P1V8")
	)
	(via
		(at 184.00014 -62.6999)
		(size 0.508)
		(drill 0.254)
		(layers "F.Cu" "B.Cu")
		(net "P1V8")
	)
	(via
		(at 161.036 -47.625)
		(size 0.508)
		(drill 0.254)
		(layers "F.Cu" "B.Cu")
		(net "P1V8")
	)
	(via
		(at 199.731122 -45.709586)
		(size 0.508)
		(drill 0.254)
		(layers "F.Cu" "B.Cu")
		(net "P1V8")
	)
	(via
		(at 181.229 -92.1766)
		(size 0.508)
		(drill 0.254)
		(layers "F.Cu" "B.Cu")
		(net "P1V8")
	)
	(via
		(at 175.4124 -58.5978)
		(size 0.508)
		(drill 0.254)
		(layers "F.Cu" "B.Cu")
		(net "P1V8")
	)
	(via
		(at 173.23562 -64.42202)
		(size 0.508)
		(drill 0.254)
		(layers "F.Cu" "B.Cu")
		(net "P1V8")
	)
	(via
		(at 171.48302 -96.955102)
		(size 0.6604)
		(drill 0.3302)
		(layers "F.Cu" "B.Cu")
		(net "P1V8")
	)
	(via
		(at 184.799732 -73.899776)
		(size 0.508)
		(drill 0.254)
		(layers "F.Cu" "B.Cu")
		(net "P1V8")
	)
	(via
		(at 170.1673 -78.9813)
		(size 0.508)
		(drill 0.254)
		(layers "F.Cu" "B.Cu")
		(net "P1V8")
	)
	(via
		(at 165.735 -77.649578)
		(size 0.508)
		(drill 0.254)
		(layers "F.Cu" "B.Cu")
		(net "P1V8")
	)
	(via
		(at 217.678 -104.2924)
		(size 0.508)
		(drill 0.254)
		(layers "F.Cu" "B.Cu")
		(net "P1V8")
	)
	(via
		(at 196.2658 -46.5582)
		(size 0.508)
		(drill 0.254)
		(layers "F.Cu" "B.Cu")
		(net "P1V8")
	)
	(via
		(at 210.312 -61.7474)
		(size 0.508)
		(drill 0.254)
		(layers "F.Cu" "B.Cu")
		(net "P1V8")
	)
	(via
		(at 213.5632 -89.6112)
		(size 0.7112)
		(drill 0.4064)
		(layers "F.Cu" "B.Cu")
		(net "P1V8")
	)
	(via
		(at 187.999878 -73.899776)
		(size 0.508)
		(drill 0.254)
		(layers "F.Cu" "B.Cu")
		(net "P1V8")
	)
	(via
		(at 202.392534 -62.702186)
		(size 0.508)
		(drill 0.254)
		(layers "F.Cu" "B.Cu")
		(net "P1V8")
	)
	(via
		(at 180.95214 -84.15528)
		(size 0.508)
		(drill 0.254)
		(layers "F.Cu" "B.Cu")
		(net "P1V8")
	)
	(via
		(at 168.8084 -77.7494)
		(size 0.508)
		(drill 0.254)
		(layers "F.Cu" "B.Cu")
		(net "P1V8")
	)
	(via
		(at 189.600078 -56.300116)
		(size 0.508)
		(drill 0.254)
		(layers "F.Cu" "B.Cu")
		(net "P1V8")
	)
	(via
		(at 207.6958 -97.9678)
		(size 0.508)
		(drill 0.254)
		(layers "F.Cu" "B.Cu")
		(net "P1V8")
	)
	(via
		(at 170.434 -108.204)
		(size 0.7112)
		(drill 0.4064)
		(layers "F.Cu" "B.Cu")
		(net "P1V8")
	)
	(via
		(at 184.00014 -65.900046)
		(size 0.508)
		(drill 0.254)
		(layers "F.Cu" "B.Cu")
		(net "P1V8")
	)
	(via
		(at 189.599824 -73.899776)
		(size 0.508)
		(drill 0.254)
		(layers "F.Cu" "B.Cu")
		(net "P1V8")
	)
	(via
		(at 164.7698 -77.1144)
		(size 0.508)
		(drill 0.254)
		(layers "F.Cu" "B.Cu")
		(net "P1V8")
	)
	(via
		(at 86.838028 -63.770256)
		(size 0.508)
		(drill 0.254)
		(layers "F.Cu" "B.Cu")
		(net "P1V8")
	)
	(via
		(at 173.494192 -112.689132)
		(size 0.6604)
		(drill 0.3302)
		(layers "F.Cu" "B.Cu")
		(net "P1V8")
	)
	(via
		(at 179.3494 -63.5)
		(size 0.508)
		(drill 0.254)
		(layers "F.Cu" "B.Cu")
		(net "P1V8")
	)
	(via
		(at 172.1612 -54.8386)
		(size 0.508)
		(drill 0.254)
		(layers "F.Cu" "B.Cu")
		(net "P1V8")
	)
	(via
		(at 199.200008 -56.300116)
		(size 0.508)
		(drill 0.254)
		(layers "F.Cu" "B.Cu")
		(net "P1V8")
	)
	(via
		(at 175.3997 -115.2779)
		(size 0.508)
		(drill 0.254)
		(layers "F.Cu" "B.Cu")
		(net "P1V8")
	)
	(via
		(at 170.434 -109.474)
		(size 0.7112)
		(drill 0.4064)
		(layers "F.Cu" "B.Cu")
		(net "P1V8")
	)
	(via
		(at 189.4078 -47.2186)
		(size 0.508)
		(drill 0.254)
		(layers "F.Cu" "B.Cu")
		(net "P1V8")
	)
	(via
		(at 175.575722 -53.782722)
		(size 0.508)
		(drill 0.254)
		(layers "F.Cu" "B.Cu")
		(net "P1V8")
	)
	(via
		(at 178.963066 -66.538856)
		(size 0.508)
		(drill 0.254)
		(layers "F.Cu" "B.Cu")
		(net "P1V8")
	)
	(via
		(at 62.2554 -164.3888)
		(size 0.508)
		(drill 0.254)
		(layers "F.Cu" "B.Cu")
		(net "P1V8")
	)
	(via
		(at 185.4962 -79.9846)
		(size 0.508)
		(drill 0.254)
		(layers "F.Cu" "B.Cu")
		(net "P1V8")
	)
	(via
		(at 197.9676 -13.9065)
		(size 0.508)
		(drill 0.254)
		(layers "F.Cu" "B.Cu")
		(net "P1V8")
	)
	(via
		(at 92.7608 -87.4776)
		(size 0.508)
		(drill 0.254)
		(layers "F.Cu" "B.Cu")
		(net "P1V8")
	)
	(via
		(at 171.2722 -50.5206)
		(size 0.508)
		(drill 0.254)
		(layers "F.Cu" "B.Cu")
		(net "P1V8")
	)
	(via
		(at 185.600086 -56.300116)
		(size 0.508)
		(drill 0.254)
		(layers "F.Cu" "B.Cu")
		(net "P1V8")
	)
	(via
		(at 202.3999 -56.300116)
		(size 0.508)
		(drill 0.254)
		(layers "F.Cu" "B.Cu")
		(net "P1V8")
	)
	(segment
		(start 102.175056 -120.451118)
		(end 101.488748 -119.76481)
		(width 0.254)
		(layer "B.Cu")
		(net "P1V8")
	)
	(segment
		(start 170.1673 -78.0796)
		(end 170.1673 -78.9813)
		(width 0.508)
		(layer "B.Cu")
		(net "P1V8")
	)
	(segment
		(start 101.488748 -92.19819)
		(end 98.180398 -88.88984)
		(width 0.254)
		(layer "B.Cu")
		(net "P1V8")
	)
	(segment
		(start 199.382126 -55.616094)
		(end 199.200008 -55.798212)
		(width 0.508)
		(layer "B.Cu")
		(net "P1V8")
	)
	(segment
		(start 101.488748 -119.76481)
		(end 101.488748 -92.19819)
		(width 0.254)
		(layer "B.Cu")
		(net "P1V8")
	)
	(segment
		(start 172.1612 -54.8386)
		(end 171.7294 -54.8386)
		(width 0.3048)
		(layer "B.Cu")
		(net "P1V8")
	)
	(segment
		(start 183.6166 -65.1637)
		(end 183.6166 -64.74587)
		(width 0.508)
		(layer "B.Cu")
		(net "P1V8")
	)
	(segment
		(start 183.5785 -66.6242)
		(end 183.5785 -66.961258)
		(width 0.508)
		(layer "B.Cu")
		(net "P1V8")
	)
	(segment
		(start 185.6994 -48.5267)
		(end 185.6994 -47.4472)
		(width 0.508)
		(layer "B.Cu")
		(net "P1V8")
	)
	(segment
		(start 189.539372 -74.793856)
		(end 189.539372 -73.960228)
		(width 0.508)
		(layer "B.Cu")
		(net "P1V8")
	)
	(segment
		(start 192.000124 -56.300116)
		(end 192.786 -55.51424)
		(width 0.3556)
		(layer "B.Cu")
		(net "P1V8")
	)
	(segment
		(start 171.49445 -54.60365)
		(end 171.49445 -53.6575)
		(width 0.3048)
		(layer "B.Cu")
		(net "P1V8")
	)
	(segment
		(start 192.786 -55.51424)
		(end 192.786 -55.4609)
		(width 0.3556)
		(layer "B.Cu")
		(net "P1V8")
	)
	(segment
		(start 181.9529 -126.111)
		(end 180.8734 -125.0315)
		(width 0.508)
		(layer "B.Cu")
		(net "P1V8")
	)
	(segment
		(start 204.77734 -56.47436)
		(end 204.7494 -56.5023)
		(width 0.508)
		(layer "B.Cu")
		(net "P1V8")
	)
	(segment
		(start 203.86802 -55.3974)
		(end 203.8731 -55.39232)
		(width 0.508)
		(layer "B.Cu")
		(net "P1V8")
	)
	(segment
		(start 180.8734 -120.396)
		(end 175.7553 -115.2779)
		(width 0.508)
		(layer "B.Cu")
		(net "P1V8")
	)
	(segment
		(start 186.399678 -73.899776)
		(end 186.399678 -74.575162)
		(width 0.508)
		(layer "B.Cu")
		(net "P1V8")
	)
	(segment
		(start 183.2356 -70.6755)
		(end 183.975756 -70.6755)
		(width 0.508)
		(layer "B.Cu")
		(net "P1V8")
	)
	(segment
		(start 201.236326 -55.568596)
		(end 200.799954 -56.004968)
		(width 0.508)
		(layer "B.Cu")
		(net "P1V8")
	)
	(segment
		(start 156.650944 -93.038168)
		(end 156.650944 -93.286834)
		(width 0.508)
		(layer "B.Cu")
		(net "P1V8")
	)
	(segment
		(start 141.6685 -17.76476)
		(end 141.6685 -17.399)
		(width 0.254)
		(layer "B.Cu")
		(net "P1V8")
	)
	(segment
		(start 170.2308 -50.7619)
		(end 171.0309 -50.7619)
		(width 0.508)
		(layer "B.Cu")
		(net "P1V8")
	)
	(segment
		(start 183.69026 -63.09868)
		(end 184.00014 -62.7888)
		(width 0.508)
		(layer "B.Cu")
		(net "P1V8")
	)
	(segment
		(start 189.4459 -55.5752)
		(end 189.4459 -56.145938)
		(width 0.508)
		(layer "B.Cu")
		(net "P1V8")
	)
	(segment
		(start 184.00014 -59.64936)
		(end 184.00014 -59.500008)
		(width 0.508)
		(layer "B.Cu")
		(net "P1V8")
	)
	(segment
		(start 142.4305 -16.4338)
		(end 142.4305 -12.3825)
		(width 0.508)
		(layer "B.Cu")
		(net "P1V8")
	)
	(segment
		(start 197.4723 -56.172354)
		(end 197.600062 -56.300116)
		(width 0.508)
		(layer "B.Cu")
		(net "P1V8")
	)
	(segment
		(start 183.611266 -60.038234)
		(end 184.00014 -59.64936)
		(width 0.508)
		(layer "B.Cu")
		(net "P1V8")
	)
	(segment
		(start 183.77154 -67.728592)
		(end 183.77154 -68.14947)
		(width 0.508)
		(layer "B.Cu")
		(net "P1V8")
	)
	(segment
		(start 184.00014 -69.71284)
		(end 184.1881 -69.9008)
		(width 0.508)
		(layer "B.Cu")
		(net "P1V8")
	)
	(segment
		(start 168.8084 -76.5302)
		(end 168.8084 -77.7494)
		(width 0.508)
		(layer "B.Cu")
		(net "P1V8")
	)
	(segment
		(start 203.7334 -56.5023)
		(end 203.7334 -55.53202)
		(width 0.508)
		(layer "B.Cu")
		(net "P1V8")
	)
	(segment
		(start 202.209654 -56.10987)
		(end 202.3999 -56.300116)
		(width 0.508)
		(layer "B.Cu")
		(net "P1V8")
	)
	(segment
		(start 184.04332 -73.00722)
		(end 184.04332 -72.34301)
		(width 0.508)
		(layer "B.Cu")
		(net "P1V8")
	)
	(segment
		(start 201.400156 -60.909708)
		(end 201.592688 -61.10224)
		(width 0.508)
		(layer "B.Cu")
		(net "P1V8")
	)
	(segment
		(start 202.9968 -55.3974)
		(end 203.86802 -55.3974)
		(width 0.508)
		(layer "B.Cu")
		(net "P1V8")
	)
	(segment
		(start 183.80964 -64.55283)
		(end 183.80964 -64.4906)
		(width 0.508)
		(layer "B.Cu")
		(net "P1V8")
	)
	(segment
		(start 197.4723 -55.3974)
		(end 197.4723 -56.172354)
		(width 0.508)
		(layer "B.Cu")
		(net "P1V8")
	)
	(segment
		(start 156.9085 -92.77985)
		(end 156.9085 -92.780612)
		(width 0.508)
		(layer "B.Cu")
		(net "P1V8")
	)
	(segment
		(start 198.406258 -63.009018)
		(end 198.86676 -63.46952)
		(width 0.508)
		(layer "B.Cu")
		(net "P1V8")
	)
	(segment
		(start 183.77154 -68.14947)
		(end 183.670702 -68.250308)
		(width 0.508)
		(layer "B.Cu")
		(net "P1V8")
	)
	(segment
		(start 142.4305 -12.3825)
		(end 142.1384 -12.0904)
		(width 0.508)
		(layer "B.Cu")
		(net "P1V8")
	)
	(segment
		(start 209.4865 -59.942984)
		(end 209.4865 -61.0108)
		(width 0.508)
		(layer "B.Cu")
		(net "P1V8")
	)
	(segment
		(start 187.999878 -73.899776)
		(end 187.999878 -73.96226)
		(width 0.508)
		(layer "B.Cu")
		(net "P1V8")
	)
	(segment
		(start 98.180398 -88.88984)
		(end 94.17304 -88.88984)
		(width 0.254)
		(layer "B.Cu")
		(net "P1V8")
	)
	(segment
		(start 187.98794 -73.10374)
		(end 187.98794 -73.887838)
		(width 0.508)
		(layer "B.Cu")
		(net "P1V8")
	)
	(segment
		(start 201.64552 -59.45505)
		(end 201.600054 -59.500516)
		(width 0.508)
		(layer "B.Cu")
		(net "P1V8")
	)
	(segment
		(start 183.59374 -57.16524)
		(end 183.59374 -57.493662)
		(width 0.508)
		(layer "B.Cu")
		(net "P1V8")
	)
	(segment
		(start 210.5152 -60.7949)
		(end 209.7024 -60.7949)
		(width 0.508)
		(layer "B.Cu")
		(net "P1V8")
	)
	(segment
		(start 184.00014 -67.382898)
		(end 184.00014 -67.499992)
		(width 0.508)
		(layer "B.Cu")
		(net "P1V8")
	)
	(segment
		(start 206.7814 -56.5023)
		(end 205.7654 -56.5023)
		(width 0.508)
		(layer "B.Cu")
		(net "P1V8")
	)
	(segment
		(start 157.1371 -92.55125)
		(end 156.9085 -92.77985)
		(width 0.508)
		(layer "B.Cu")
		(net "P1V8")
	)
	(segment
		(start 201.236326 -55.383176)
		(end 201.236326 -55.568596)
		(width 0.508)
		(layer "B.Cu")
		(net "P1V8")
	)
	(segment
		(start 187.809632 -56.109616)
		(end 188.000132 -56.300116)
		(width 0.508)
		(layer "B.Cu")
		(net "P1V8")
	)
	(segment
		(start 203.400914 -62.702186)
		(end 203.4159 -62.6872)
		(width 0.508)
		(layer "B.Cu")
		(net "P1V8")
	)
	(segment
		(start 188.523372 -74.485754)
		(end 188.523372 -74.793856)
		(width 0.508)
		(layer "B.Cu")
		(net "P1V8")
	)
	(segment
		(start 194.2846 -54.8894)
		(end 193.60007 -55.57393)
		(width 0.508)
		(layer "B.Cu")
		(net "P1V8")
	)
	(segment
		(start 175.7553 -115.2779)
		(end 175.3997 -115.2779)
		(width 0.508)
		(layer "B.Cu")
		(net "P1V8")
	)
	(segment
		(start 198.406258 -62.703202)
		(end 198.406258 -63.009018)
		(width 0.508)
		(layer "B.Cu")
		(net "P1V8")
	)
	(segment
		(start 209.1817 -63.0428)
		(end 209.4865 -62.738)
		(width 0.508)
		(layer "B.Cu")
		(net "P1V8")
	)
	(segment
		(start 184.11063 -72.18934)
		(end 184.00014 -72.29983)
		(width 0.508)
		(layer "B.Cu")
		(net "P1V8")
	)
	(segment
		(start 197.2564 -129.8448)
		(end 188.2902 -129.8448)
		(width 0.508)
		(layer "B.Cu")
		(net "P1V8")
	)
	(segment
		(start 156.9085 -92.780612)
		(end 156.650944 -93.038168)
		(width 0.508)
		(layer "B.Cu")
		(net "P1V8")
	)
	(segment
		(start 202.394566 -59.45505)
		(end 201.64552 -59.45505)
		(width 0.508)
		(layer "B.Cu")
		(net "P1V8")
	)
	(segment
		(start 197.5104 -130.0988)
		(end 197.2564 -129.8448)
		(width 0.508)
		(layer "B.Cu")
		(net "P1V8")
	)
	(segment
		(start 184.00014 -67.499992)
		(end 183.77154 -67.728592)
		(width 0.508)
		(layer "B.Cu")
		(net "P1V8")
	)
	(segment
		(start 141.8717 -17.1958)
		(end 141.871954 -17.1958)
		(width 0.254)
		(layer "B.Cu")
		(net "P1V8")
	)
	(segment
		(start 183.611266 -60.379356)
		(end 183.611266 -60.038234)
		(width 0.508)
		(layer "B.Cu")
		(net "P1V8")
	)
	(segment
		(start 200.8759 -56.376062)
		(end 200.799954 -56.300116)
		(width 0.508)
		(layer "B.Cu")
		(net "P1V8")
	)
	(segment
		(start 180.8734 -125.0315)
		(end 180.8734 -120.396)
		(width 0.508)
		(layer "B.Cu")
		(net "P1V8")
	)
	(segment
		(start 187.809632 -56.047386)
		(end 187.809632 -56.109616)
		(width 0.508)
		(layer "B.Cu")
		(net "P1V8")
	)
	(segment
		(start 183.7817 -61.380878)
		(end 183.809894 -61.352684)
		(width 0.508)
		(layer "B.Cu")
		(net "P1V8")
	)
	(segment
		(start 197.4723 -54.5338)
		(end 197.4723 -55.3974)
		(width 0.508)
		(layer "B.Cu")
		(net "P1V8")
	)
	(segment
		(start 202.392534 -61.867542)
		(end 202.392534 -62.702186)
		(width 0.508)
		(layer "B.Cu")
		(net "P1V8")
	)
	(segment
		(start 101.616256 -165.759892)
		(end 102.175056 -165.201092)
		(width 0.254)
		(layer "B.Cu")
		(net "P1V8")
	)
	(segment
		(start 209.4865 -62.738)
		(end 209.4865 -62.0268)
		(width 0.508)
		(layer "B.Cu")
		(net "P1V8")
	)
	(segment
		(start 201.46899 -59.63158)
		(end 201.600054 -59.500516)
		(width 0.508)
		(layer "B.Cu")
		(net "P1V8")
	)
	(segment
		(start 209.4865 -62.0268)
		(end 210.0326 -62.0268)
		(width 0.508)
		(layer "B.Cu")
		(net "P1V8")
	)
	(segment
		(start 195.193666 -53.902356)
		(end 195.017644 -53.902356)
		(width 0.508)
		(layer "B.Cu")
		(net "P1V8")
	)
	(segment
		(start 201.600054 -57.304686)
		(end 202.3999 -56.50484)
		(width 0.508)
		(layer "B.Cu")
		(net "P1V8")
	)
	(segment
		(start 187.5409 -55.778654)
		(end 187.809632 -56.047386)
		(width 0.508)
		(layer "B.Cu")
		(net "P1V8")
	)
	(segment
		(start 201.586338 -57.8866)
		(end 201.600054 -57.900316)
		(width 0.508)
		(layer "B.Cu")
		(net "P1V8")
	)
	(segment
		(start 184.713372 -74.793856)
		(end 184.713372 -73.986136)
		(width 0.508)
		(layer "B.Cu")
		(net "P1V8")
	)
	(segment
		(start 183.5785 -66.961258)
		(end 184.00014 -67.382898)
		(width 0.508)
		(layer "B.Cu")
		(net "P1V8")
	)
	(segment
		(start 209.7024 -60.7949)
		(end 209.4865 -61.0108)
		(width 0.508)
		(layer "B.Cu")
		(net "P1V8")
	)
	(segment
		(start 202.112626 -55.390796)
		(end 202.112626 -55.950358)
		(width 0.508)
		(layer "B.Cu")
		(net "P1V8")
	)
	(segment
		(start 202.392534 -62.702186)
		(end 203.400914 -62.702186)
		(width 0.508)
		(layer "B.Cu")
		(net "P1V8")
	)
	(segment
		(start 201.600054 -57.900316)
		(end 201.600054 -57.304686)
		(width 0.508)
		(layer "B.Cu")
		(net "P1V8")
	)
	(segment
		(start 102.175056 -165.201092)
		(end 102.175056 -120.451118)
		(width 0.254)
		(layer "B.Cu")
		(net "P1V8")
	)
	(segment
		(start 186.0677 -73.19518)
		(end 186.0677 -73.567798)
		(width 0.381)
		(layer "B.Cu")
		(net "P1V8")
	)
	(segment
		(start 183.74868 -61.8998)
		(end 183.7817 -61.86678)
		(width 0.508)
		(layer "B.Cu")
		(net "P1V8")
	)
	(segment
		(start 209.478372 -59.609228)
		(end 209.804 -59.2836)
		(width 0.508)
		(layer "B.Cu")
		(net "P1V8")
	)
	(segment
		(start 161.036 -48.4505)
		(end 161.036 -47.625)
		(width 0.508)
		(layer "B.Cu")
		(net "P1V8")
	)
	(segment
		(start 171.7294 -54.8386)
		(end 171.49445 -54.60365)
		(width 0.3048)
		(layer "B.Cu")
		(net "P1V8")
	)
	(segment
		(start 195.017644 -53.902356)
		(end 194.6275 -54.2925)
		(width 0.508)
		(layer "B.Cu")
		(net "P1V8")
	)
	(segment
		(start 185.98642 -79.49438)
		(end 185.4962 -79.9846)
		(width 0.508)
		(layer "B.Cu")
		(net "P1V8")
	)
	(segment
		(start 184.5564 -126.111)
		(end 181.9529 -126.111)
		(width 0.508)
		(layer "B.Cu")
		(net "P1V8")
	)
	(segment
		(start 209.478372 -59.934856)
		(end 209.478372 -59.609228)
		(width 0.508)
		(layer "B.Cu")
		(net "P1V8")
	)
	(segment
		(start 200.8378 -58.7629)
		(end 200.8378 -57.8866)
		(width 0.508)
		(layer "B.Cu")
		(net "P1V8")
	)
	(segment
		(start 202.11923 -55.3974)
		(end 202.112626 -55.390796)
		(width 0.508)
		(layer "B.Cu")
		(net "P1V8")
	)
	(segment
		(start 199.382126 -55.390796)
		(end 199.382126 -55.616094)
		(width 0.508)
		(layer "B.Cu")
		(net "P1V8")
	)
	(segment
		(start 189.539372 -73.960228)
		(end 189.599824 -73.899776)
		(width 0.508)
		(layer "B.Cu")
		(net "P1V8")
	)
	(segment
		(start 194.2846 -54.2925)
		(end 194.2846 -54.8894)
		(width 0.508)
		(layer "B.Cu")
		(net "P1V8")
	)
	(segment
		(start 209.478372 -59.934856)
		(end 209.4865 -59.942984)
		(width 0.508)
		(layer "B.Cu")
		(net "P1V8")
	)
	(segment
		(start 185.98642 -79.075026)
		(end 185.98642 -79.49438)
		(width 0.508)
		(layer "B.Cu")
		(net "P1V8")
	)
	(segment
		(start 183.80964 -64.4906)
		(end 184.00014 -64.3001)
		(width 0.508)
		(layer "B.Cu")
		(net "P1V8")
	)
	(segment
		(start 186.0677 -73.567798)
		(end 186.399678 -73.899776)
		(width 0.381)
		(layer "B.Cu")
		(net "P1V8")
	)
	(segment
		(start 207.7974 -56.5023)
		(end 206.7814 -56.5023)
		(width 0.508)
		(layer "B.Cu")
		(net "P1V8")
	)
	(segment
		(start 185.6994 -47.4472)
		(end 185.928 -47.2186)
		(width 0.508)
		(layer "B.Cu")
		(net "P1V8")
	)
	(segment
		(start 183.69026 -63.4619)
		(end 183.69026 -63.09868)
		(width 0.508)
		(layer "B.Cu")
		(net "P1V8")
	)
	(segment
		(start 187.999878 -73.96226)
		(end 188.523372 -74.485754)
		(width 0.508)
		(layer "B.Cu")
		(net "P1V8")
	)
	(segment
		(start 183.809894 -61.2902)
		(end 184.00014 -61.099954)
		(width 0.508)
		(layer "B.Cu")
		(net "P1V8")
	)
	(segment
		(start 61.2521 -164.3888)
		(end 60.0075 -163.1442)
		(width 0.254)
		(layer "B.Cu")
		(net "P1V8")
	)
	(segment
		(start 204.77734 -55.39486)
		(end 204.77734 -56.47436)
		(width 0.508)
		(layer "B.Cu")
		(net "P1V8")
	)
	(segment
		(start 179.730908 -66.547746)
		(end 178.971956 -66.547746)
		(width 0.508)
		(layer "B.Cu")
		(net "P1V8")
	)
	(segment
		(start 199.200008 -55.798212)
		(end 199.200008 -56.300116)
		(width 0.508)
		(layer "B.Cu")
		(net "P1V8")
	)
	(segment
		(start 201.257916 -60.8203)
		(end 201.347324 -60.909708)
		(width 0.508)
		(layer "B.Cu")
		(net "P1V8")
	)
	(segment
		(start 202.3999 -56.50484)
		(end 202.3999 -56.300116)
		(width 0.508)
		(layer "B.Cu")
		(net "P1V8")
	)
	(segment
		(start 184.713372 -73.986136)
		(end 184.799732 -73.899776)
		(width 0.508)
		(layer "B.Cu")
		(net "P1V8")
	)
	(segment
		(start 184.17032 -73.13422)
		(end 184.04332 -73.00722)
		(width 0.508)
		(layer "B.Cu")
		(net "P1V8")
	)
	(segment
		(start 202.463146 -61.79693)
		(end 202.392534 -61.867542)
		(width 0.508)
		(layer "B.Cu")
		(net "P1V8")
	)
	(segment
		(start 203.7334 -55.53202)
		(end 203.86802 -55.3974)
		(width 0.508)
		(layer "B.Cu")
		(net "P1V8")
	)
	(segment
		(start 190.2841 -54.737)
		(end 189.4459 -55.5752)
		(width 0.254)
		(layer "B.Cu")
		(net "P1V8")
	)
	(segment
		(start 183.809894 -61.352684)
		(end 183.809894 -61.2902)
		(width 0.508)
		(layer "B.Cu")
		(net "P1V8")
	)
	(segment
		(start 184.04332 -72.34301)
		(end 184.00014 -72.29983)
		(width 0.508)
		(layer "B.Cu")
		(net "P1V8")
	)
	(segment
		(start 192.786 -55.4609)
		(end 192.786 -54.5211)
		(width 0.508)
		(layer "B.Cu")
		(net "P1V8")
	)
	(segment
		(start 186.399678 -74.575162)
		(end 186.618372 -74.793856)
		(width 0.508)
		(layer "B.Cu")
		(net "P1V8")
	)
	(segment
		(start 202.9968 -55.3974)
		(end 202.11923 -55.3974)
		(width 0.508)
		(layer "B.Cu")
		(net "P1V8")
	)
	(segment
		(start 184.7596 -72.18934)
		(end 184.11063 -72.18934)
		(width 0.508)
		(layer "B.Cu")
		(net "P1V8")
	)
	(segment
		(start 187.5409 -55.5752)
		(end 187.5409 -55.778654)
		(width 0.508)
		(layer "B.Cu")
		(net "P1V8")
	)
	(segment
		(start 157.1244 -92.55125)
		(end 157.1371 -92.55125)
		(width 0.508)
		(layer "B.Cu")
		(net "P1V8")
	)
	(segment
		(start 186.07278 -73.1901)
		(end 186.0677 -73.19518)
		(width 0.381)
		(layer "B.Cu")
		(net "P1V8")
	)
	(segment
		(start 200.8759 -56.9976)
		(end 200.8759 -56.376062)
		(width 0.508)
		(layer "B.Cu")
		(net "P1V8")
	)
	(segment
		(start 193.60007 -55.57393)
		(end 193.60007 -56.300116)
		(width 0.508)
		(layer "B.Cu")
		(net "P1V8")
	)
	(segment
		(start 183.5404 -58.79084)
		(end 183.5404 -58.359802)
		(width 0.508)
		(layer "B.Cu")
		(net "P1V8")
	)
	(segment
		(start 209.4865 -61.0108)
		(end 209.4865 -62.0268)
		(width 0.508)
		(layer "B.Cu")
		(net "P1V8")
	)
	(segment
		(start 202.209654 -56.047386)
		(end 202.209654 -56.10987)
		(width 0.508)
		(layer "B.Cu")
		(net "P1V8")
	)
	(segment
		(start 184.00014 -62.7888)
		(end 184.00014 -62.6999)
		(width 0.508)
		(layer "B.Cu")
		(net "P1V8")
	)
	(segment
		(start 200.8378 -57.8866)
		(end 201.586338 -57.8866)
		(width 0.508)
		(layer "B.Cu")
		(net "P1V8")
	)
	(segment
		(start 203.7334 -56.5023)
		(end 204.7494 -56.5023)
		(width 0.508)
		(layer "B.Cu")
		(net "P1V8")
	)
	(segment
		(start 184.00014 -69.099938)
		(end 184.00014 -69.71284)
		(width 0.508)
		(layer "B.Cu")
		(net "P1V8")
	)
	(segment
		(start 183.7817 -61.86678)
		(end 183.7817 -61.380878)
		(width 0.508)
		(layer "B.Cu")
		(net "P1V8")
	)
	(segment
		(start 183.5404 -58.359802)
		(end 184.00014 -57.900062)
		(width 0.508)
		(layer "B.Cu")
		(net "P1V8")
	)
	(segment
		(start 187.98794 -73.887838)
		(end 187.999878 -73.899776)
		(width 0.508)
		(layer "B.Cu")
		(net "P1V8")
	)
	(segment
		(start 200.75144 -60.8203)
		(end 201.257916 -60.8203)
		(width 0.508)
		(layer "B.Cu")
		(net "P1V8")
	)
	(segment
		(start 189.4459 -56.145938)
		(end 189.600078 -56.300116)
		(width 0.508)
		(layer "B.Cu")
		(net "P1V8")
	)
	(segment
		(start 183.59374 -57.493662)
		(end 184.00014 -57.900062)
		(width 0.508)
		(layer "B.Cu")
		(net "P1V8")
	)
	(segment
		(start 94.17304 -88.88984)
		(end 92.7608 -87.4776)
		(width 0.254)
		(layer "B.Cu")
		(net "P1V8")
	)
	(segment
		(start 194.6275 -54.2925)
		(end 194.2846 -54.2925)
		(width 0.508)
		(layer "B.Cu")
		(net "P1V8")
	)
	(segment
		(start 142.4305 -16.637254)
		(end 142.4305 -16.4338)
		(width 0.254)
		(layer "B.Cu")
		(net "P1V8")
	)
	(segment
		(start 183.975756 -70.6755)
		(end 184.00014 -70.699884)
		(width 0.508)
		(layer "B.Cu")
		(net "P1V8")
	)
	(segment
		(start 141.871954 -17.1958)
		(end 142.4305 -16.637254)
		(width 0.254)
		(layer "B.Cu")
		(net "P1V8")
	)
	(segment
		(start 190.2841 -52.959)
		(end 190.2841 -54.737)
		(width 0.254)
		(layer "B.Cu")
		(net "P1V8")
	)
	(segment
		(start 204.7494 -56.5023)
		(end 205.7654 -56.5023)
		(width 0.508)
		(layer "B.Cu")
		(net "P1V8")
	)
	(segment
		(start 178.971956 -66.547746)
		(end 178.963066 -66.538856)
		(width 0.508)
		(layer "B.Cu")
		(net "P1V8")
	)
	(segment
		(start 183.6166 -64.74587)
		(end 183.80964 -64.55283)
		(width 0.508)
		(layer "B.Cu")
		(net "P1V8")
	)
	(segment
		(start 201.347324 -60.909708)
		(end 201.400156 -60.909708)
		(width 0.508)
		(layer "B.Cu")
		(net "P1V8")
	)
	(segment
		(start 200.8378 -59.63158)
		(end 201.46899 -59.63158)
		(width 0.508)
		(layer "B.Cu")
		(net "P1V8")
	)
	(segment
		(start 200.799954 -56.004968)
		(end 200.799954 -56.300116)
		(width 0.508)
		(layer "B.Cu")
		(net "P1V8")
	)
	(segment
		(start 188.2902 -129.8448)
		(end 184.5564 -126.111)
		(width 0.508)
		(layer "B.Cu")
		(net "P1V8")
	)
	(segment
		(start 141.6685 -17.399)
		(end 141.8717 -17.1958)
		(width 0.254)
		(layer "B.Cu")
		(net "P1V8")
	)
	(segment
		(start 185.6486 -48.5775)
		(end 185.6994 -48.5267)
		(width 0.508)
		(layer "B.Cu")
		(net "P1V8")
	)
	(segment
		(start 62.2554 -164.3888)
		(end 61.2521 -164.3888)
		(width 0.254)
		(layer "B.Cu")
		(net "P1V8")
	)
	(segment
		(start 171.0309 -50.7619)
		(end 171.2722 -50.5206)
		(width 0.508)
		(layer "B.Cu")
		(net "P1V8")
	)
	(segment
		(start 210.0326 -62.0268)
		(end 210.312 -61.7474)
		(width 0.508)
		(layer "B.Cu")
		(net "P1V8")
	)
	(segment
		(start 202.112626 -55.950358)
		(end 202.209654 -56.047386)
		(width 0.508)
		(layer "B.Cu")
		(net "P1V8")
	)
	(segment
		(start 167.447722 -103.124)
		(end 161.789364 -103.124)
		(width 0.508)
		(layer "In2.Cu")
		(net "P1V8")
	)
	(segment
		(start 192.4812 -29.7688)
		(end 192.4812 -35.7505)
		(width 1.016)
		(layer "In2.Cu")
		(net "P1V8")
	)
	(segment
		(start 170.434 -106.110278)
		(end 167.447722 -103.124)
		(width 0.508)
		(layer "In2.Cu")
		(net "P1V8")
	)
	(segment
		(start 191.516 -36.7157)
		(end 191.516 -43.8658)
		(width 1.016)
		(layer "In2.Cu")
		(net "P1V8")
	)
	(segment
		(start 156.6418 -90.654632)
		(end 156.6418 -87.1728)
		(width 0.508)
		(layer "In2.Cu")
		(net "P1V8")
	)
	(segment
		(start 161.788602 -103.123746)
		(end 161.373058 -103.123746)
		(width 0.508)
		(layer "In2.Cu")
		(net "P1V8")
	)
	(segment
		(start 154.74696 -93.232986)
		(end 155.3591 -92.620846)
		(width 0.508)
		(layer "In2.Cu")
		(net "P1V8")
	)
	(segment
		(start 193.548 -28.702)
		(end 192.4812 -29.7688)
		(width 1.016)
		(layer "In2.Cu")
		(net "P1V8")
	)
	(segment
		(start 192.4812 -35.7505)
		(end 191.516 -36.7157)
		(width 1.016)
		(layer "In2.Cu")
		(net "P1V8")
	)
	(segment
		(start 161.789364 -103.124)
		(end 161.78911 -103.123746)
		(width 0.508)
		(layer "In2.Cu")
		(net "P1V8")
	)
	(segment
		(start 161.373058 -103.123746)
		(end 154.74696 -96.497648)
		(width 0.508)
		(layer "In2.Cu")
		(net "P1V8")
	)
	(segment
		(start 170.434 -106.934)
		(end 170.434 -106.110278)
		(width 0.508)
		(layer "In2.Cu")
		(net "P1V8")
	)
	(segment
		(start 154.74696 -94.065598)
		(end 154.74696 -93.232986)
		(width 0.508)
		(layer "In2.Cu")
		(net "P1V8")
	)
	(segment
		(start 155.3591 -91.937332)
		(end 156.6418 -90.654632)
		(width 0.508)
		(layer "In2.Cu")
		(net "P1V8")
	)
	(segment
		(start 155.3591 -92.620846)
		(end 155.3591 -91.937332)
		(width 0.508)
		(layer "In2.Cu")
		(net "P1V8")
	)
	(segment
		(start 154.74696 -96.497648)
		(end 154.74696 -94.065598)
		(width 0.508)
		(layer "In2.Cu")
		(net "P1V8")
	)
	(segment
		(start 161.78911 -103.123746)
		(end 161.788602 -103.123746)
		(width 0.508)
		(layer "In2.Cu")
		(net "P1V8")
	)
	(segment
		(start 156.6418 -87.1728)
		(end 156.6926 -87.122)
		(width 0.508)
		(layer "In2.Cu")
		(net "P1V8")
	)
	(segment
		(start 198.1581 -24.31796)
		(end 198.1581 -14.097)
		(width 0.508)
		(layer "In5.Cu")
		(net "P1V8")
	)
	(segment
		(start 193.548 -28.702)
		(end 194.2338 -28.702)
		(width 0.508)
		(layer "In5.Cu")
		(net "P1V8")
	)
	(segment
		(start 198.406258 -62.703202)
		(end 198.406258 -62.765432)
		(width 0.508)
		(layer "In5.Cu")
		(net "P1V8")
	)
	(segment
		(start 186.095386 -100.573586)
		(end 185.3946 -99.8728)
		(width 0.508)
		(layer "In5.Cu")
		(net "P1V8")
	)
	(segment
		(start 80.92821 -163.81349)
		(end 82.66049 -163.81349)
		(width 0.254)
		(layer "In5.Cu")
		(net "P1V8")
	)
	(segment
		(start 63.33236 -164.5412)
		(end 63.654432 -164.5412)
		(width 0.254)
		(layer "In5.Cu")
		(net "P1V8")
	)
	(segment
		(start 64.58331 -165.470078)
		(end 72.228202 -165.470078)
		(width 0.254)
		(layer "In5.Cu")
		(net "P1V8")
	)
	(segment
		(start 105.494836 -4.13512)
		(end 111.494316 -10.1346)
		(width 0.254)
		(layer "In5.Cu")
		(net "P1V8")
	)
	(segment
		(start 132.73532 -22.570186)
		(end 135.87095 -22.570186)
		(width 0.254)
		(layer "In5.Cu")
		(net "P1V8")
	)
	(segment
		(start 88.06434 -42.72026)
		(end 87.086186 -43.698414)
		(width 0.254)
		(layer "In5.Cu")
		(net "P1V8")
	)
	(segment
		(start 157.1371 -92.55125)
		(end 156.9085 -92.77985)
		(width 0.508)
		(layer "In5.Cu")
		(net "P1V8")
	)
	(segment
		(start 63.17996 -164.3888)
		(end 63.33236 -164.5412)
		(width 0.254)
		(layer "In5.Cu")
		(net "P1V8")
	)
	(segment
		(start 195.4149 -29.8831)
		(end 197.593458 -29.8831)
		(width 0.508)
		(layer "In5.Cu")
		(net "P1V8")
	)
	(segment
		(start 155.92298 -93.76537)
		(end 155.047188 -93.76537)
		(width 0.508)
		(layer "In5.Cu")
		(net "P1V8")
	)
	(segment
		(start 142.1384 -12.0904)
		(end 142.415514 -11.813286)
		(width 0.508)
		(layer "In5.Cu")
		(net "P1V8")
	)
	(segment
		(start 88.06434 -33.640776)
		(end 88.06434 -42.72026)
		(width 0.254)
		(layer "In5.Cu")
		(net "P1V8")
	)
	(segment
		(start 156.521912 -93.1672)
		(end 156.52115 -93.1672)
		(width 0.508)
		(layer "In5.Cu")
		(net "P1V8")
	)
	(segment
		(start 83.2739 -164.4269)
		(end 85.5853 -164.4269)
		(width 0.254)
		(layer "In5.Cu")
		(net "P1V8")
	)
	(segment
		(start 112.3442 -10.1346)
		(end 115.7478 -13.5382)
		(width 0.254)
		(layer "In5.Cu")
		(net "P1V8")
	)
	(segment
		(start 156.9085 -92.780612)
		(end 156.521912 -93.1672)
		(width 0.508)
		(layer "In5.Cu")
		(net "P1V8")
	)
	(segment
		(start 142.415514 -11.813286)
		(end 154.186382 -11.813286)
		(width 0.508)
		(layer "In5.Cu")
		(net "P1V8")
	)
	(segment
		(start 88.698324 -33.006792)
		(end 88.06434 -33.640776)
		(width 0.254)
		(layer "In5.Cu")
		(net "P1V8")
	)
	(segment
		(start 100.411788 -166.96436)
		(end 101.616256 -165.759892)
		(width 0.254)
		(layer "In5.Cu")
		(net "P1V8")
	)
	(segment
		(start 200.311258 -63.312802)
		(end 200.883774 -62.740286)
		(width 0.508)
		(layer "In5.Cu")
		(net "P1V8")
	)
	(segment
		(start 200.883774 -62.740286)
		(end 202.354434 -62.740286)
		(width 0.508)
		(layer "In5.Cu")
		(net "P1V8")
	)
	(segment
		(start 72.228202 -165.470078)
		(end 73.41362 -164.28466)
		(width 0.254)
		(layer "In5.Cu")
		(net "P1V8")
	)
	(segment
		(start 197.593458 -29.8831)
		(end 198.0184 -29.458158)
		(width 0.508)
		(layer "In5.Cu")
		(net "P1V8")
	)
	(segment
		(start 82.944462 -8.810498)
		(end 83.67776 -8.0772)
		(width 0.254)
		(layer "In5.Cu")
		(net "P1V8")
	)
	(segment
		(start 93.19768 -4.13512)
		(end 105.494836 -4.13512)
		(width 0.254)
		(layer "In5.Cu")
		(net "P1V8")
	)
	(segment
		(start 115.7478 -13.5382)
		(end 115.7478 -15.452344)
		(width 0.254)
		(layer "In5.Cu")
		(net "P1V8")
	)
	(segment
		(start 198.953628 -63.312802)
		(end 200.311258 -63.312802)
		(width 0.508)
		(layer "In5.Cu")
		(net "P1V8")
	)
	(segment
		(start 87.086186 -43.698414)
		(end 87.086186 -63.522098)
		(width 0.254)
		(layer "In5.Cu")
		(net "P1V8")
	)
	(segment
		(start 155.047188 -93.76537)
		(end 154.74696 -94.065598)
		(width 0.508)
		(layer "In5.Cu")
		(net "P1V8")
	)
	(segment
		(start 63.654432 -164.5412)
		(end 64.58331 -165.470078)
		(width 0.254)
		(layer "In5.Cu")
		(net "P1V8")
	)
	(segment
		(start 155.482798 -10.51687)
		(end 183.330596 -10.51687)
		(width 0.508)
		(layer "In5.Cu")
		(net "P1V8")
	)
	(segment
		(start 198.0184 -26.6827)
		(end 197.7771 -26.4414)
		(width 0.508)
		(layer "In5.Cu")
		(net "P1V8")
	)
	(segment
		(start 131.770628 -23.534878)
		(end 132.73532 -22.570186)
		(width 0.254)
		(layer "In5.Cu")
		(net "P1V8")
	)
	(segment
		(start 135.87095 -22.570186)
		(end 137.869676 -20.57146)
		(width 0.254)
		(layer "In5.Cu")
		(net "P1V8")
	)
	(segment
		(start 89.2556 -8.0772)
		(end 93.19768 -4.13512)
		(width 0.254)
		(layer "In5.Cu")
		(net "P1V8")
	)
	(segment
		(start 62.2554 -164.3888)
		(end 63.17996 -164.3888)
		(width 0.254)
		(layer "In5.Cu")
		(net "P1V8")
	)
	(segment
		(start 111.494316 -10.1346)
		(end 112.3442 -10.1346)
		(width 0.254)
		(layer "In5.Cu")
		(net "P1V8")
	)
	(segment
		(start 87.086186 -63.522098)
		(end 86.838028 -63.770256)
		(width 0.254)
		(layer "In5.Cu")
		(net "P1V8")
	)
	(segment
		(start 156.9085 -92.77985)
		(end 156.9085 -92.780612)
		(width 0.508)
		(layer "In5.Cu")
		(net "P1V8")
	)
	(segment
		(start 183.330596 -10.51687)
		(end 188.841126 -16.0274)
		(width 0.508)
		(layer "In5.Cu")
		(net "P1V8")
	)
	(segment
		(start 82.66049 -163.81349)
		(end 83.2739 -164.4269)
		(width 0.254)
		(layer "In5.Cu")
		(net "P1V8")
	)
	(segment
		(start 205.704186 -97.9678)
		(end 203.0984 -100.573586)
		(width 0.508)
		(layer "In5.Cu")
		(net "P1V8")
	)
	(segment
		(start 154.186382 -11.813286)
		(end 155.482798 -10.51687)
		(width 0.508)
		(layer "In5.Cu")
		(net "P1V8")
	)
	(segment
		(start 194.2338 -28.702)
		(end 195.4149 -29.8831)
		(width 0.508)
		(layer "In5.Cu")
		(net "P1V8")
	)
	(segment
		(start 88.12276 -166.96436)
		(end 100.411788 -166.96436)
		(width 0.254)
		(layer "In5.Cu")
		(net "P1V8")
	)
	(segment
		(start 217.678 -104.2924)
		(end 214.0204 -104.2924)
		(width 0.508)
		(layer "In5.Cu")
		(net "P1V8")
	)
	(segment
		(start 80.45704 -164.28466)
		(end 80.92821 -163.81349)
		(width 0.254)
		(layer "In5.Cu")
		(net "P1V8")
	)
	(segment
		(start 197.7771 -26.4414)
		(end 197.7771 -24.69896)
		(width 0.508)
		(layer "In5.Cu")
		(net "P1V8")
	)
	(segment
		(start 207.6958 -97.9678)
		(end 205.704186 -97.9678)
		(width 0.508)
		(layer "In5.Cu")
		(net "P1V8")
	)
	(segment
		(start 85.5853 -164.4269)
		(end 88.12276 -166.96436)
		(width 0.254)
		(layer "In5.Cu")
		(net "P1V8")
	)
	(segment
		(start 73.41362 -164.28466)
		(end 80.45704 -164.28466)
		(width 0.254)
		(layer "In5.Cu")
		(net "P1V8")
	)
	(segment
		(start 83.67776 -8.0772)
		(end 89.2556 -8.0772)
		(width 0.254)
		(layer "In5.Cu")
		(net "P1V8")
	)
	(segment
		(start 197.7771 -24.69896)
		(end 198.1581 -24.31796)
		(width 0.508)
		(layer "In5.Cu")
		(net "P1V8")
	)
	(segment
		(start 203.0984 -100.573586)
		(end 186.095386 -100.573586)
		(width 0.508)
		(layer "In5.Cu")
		(net "P1V8")
	)
	(segment
		(start 157.1244 -92.55125)
		(end 157.1371 -92.55125)
		(width 0.508)
		(layer "In5.Cu")
		(net "P1V8")
	)
	(segment
		(start 137.869676 -16.359124)
		(end 142.1384 -12.0904)
		(width 0.254)
		(layer "In5.Cu")
		(net "P1V8")
	)
	(segment
		(start 198.1581 -14.097)
		(end 197.9676 -13.9065)
		(width 0.508)
		(layer "In5.Cu")
		(net "P1V8")
	)
	(segment
		(start 202.354434 -62.740286)
		(end 202.392534 -62.702186)
		(width 0.508)
		(layer "In5.Cu")
		(net "P1V8")
	)
	(segment
		(start 195.8467 -16.0274)
		(end 197.9676 -13.9065)
		(width 0.508)
		(layer "In5.Cu")
		(net "P1V8")
	)
	(segment
		(start 188.841126 -16.0274)
		(end 195.8467 -16.0274)
		(width 0.508)
		(layer "In5.Cu")
		(net "P1V8")
	)
	(segment
		(start 214.0204 -104.2924)
		(end 207.6958 -97.9678)
		(width 0.508)
		(layer "In5.Cu")
		(net "P1V8")
	)
	(segment
		(start 137.869676 -20.57146)
		(end 137.869676 -16.359124)
		(width 0.254)
		(layer "In5.Cu")
		(net "P1V8")
	)
	(segment
		(start 198.406258 -62.765432)
		(end 198.953628 -63.312802)
		(width 0.508)
		(layer "In5.Cu")
		(net "P1V8")
	)
	(segment
		(start 198.0184 -29.458158)
		(end 198.0184 -26.6827)
		(width 0.508)
		(layer "In5.Cu")
		(net "P1V8")
	)
	(segment
		(start 156.52115 -93.1672)
		(end 155.92298 -93.76537)
		(width 0.508)
		(layer "In5.Cu")
		(net "P1V8")
	)
	(segment
		(start 123.830334 -23.534878)
		(end 131.770628 -23.534878)
		(width 0.254)
		(layer "In5.Cu")
		(net "P1V8")
	)
	(segment
		(start 115.7478 -15.452344)
		(end 123.830334 -23.534878)
		(width 0.254)
		(layer "In5.Cu")
		(net "P1V8")
	)
	(via
		(at 215.5698 -118.1608)
		(size 0.7112)
		(drill 0.4064)
		(layers "F.Cu" "B.Cu")
		(net "P1V5")
	)
	(via
		(at 206.906368 -95.077788)
		(size 0.7112)
		(drill 0.4064)
		(layers "F.Cu" "B.Cu")
		(net "P1V5")
	)
	(via
		(at 71.7042 -177.8254)
		(size 0.508)
		(drill 0.254)
		(layers "F.Cu" "B.Cu")
		(net "P1V5")
	)
	(via
		(at 50.9016 -176.4538)
		(size 0.508)
		(drill 0.254)
		(layers "F.Cu" "B.Cu")
		(net "P1V5")
	)
	(via
		(at 124.4854 -28.2702)
		(size 0.508)
		(drill 0.254)
		(layers "F.Cu" "B.Cu")
		(net "P1V5")
	)
	(via
		(at 49.7586 -164.9349)
		(size 0.508)
		(drill 0.254)
		(layers "F.Cu" "B.Cu")
		(net "P1V5")
	)
	(via
		(at 205.687168 -96.296988)
		(size 0.7112)
		(drill 0.4064)
		(layers "F.Cu" "B.Cu")
		(net "P1V5")
	)
	(via
		(at 205.687168 -95.077788)
		(size 0.7112)
		(drill 0.4064)
		(layers "F.Cu" "B.Cu")
		(net "P1V5")
	)
	(via
		(at 214.3506 -117.856)
		(size 0.7112)
		(drill 0.4064)
		(layers "F.Cu" "B.Cu")
		(net "P1V5")
	)
	(via
		(at 101.70922 -37.38626)
		(size 0.508)
		(drill 0.254)
		(layers "F.Cu" "B.Cu")
		(net "P1V5")
	)
	(via
		(at 117.280944 -28.2702)
		(size 0.508)
		(drill 0.254)
		(layers "F.Cu" "B.Cu")
		(net "P1V5")
	)
	(via
		(at 215.5698 -119.5324)
		(size 0.7112)
		(drill 0.4064)
		(layers "F.Cu" "B.Cu")
		(net "P1V5")
	)
	(via
		(at 206.906368 -96.296988)
		(size 0.7112)
		(drill 0.4064)
		(layers "F.Cu" "B.Cu")
		(net "P1V5")
	)
	(via
		(at 147.0406 -20.955)
		(size 0.508)
		(drill 0.254)
		(layers "F.Cu" "B.Cu")
		(net "P1V5")
	)
	(via
		(at 65.224152 -177.091848)
		(size 0.6096)
		(drill 0.3048)
		(layers "F.Cu" "B.Cu")
		(net "P1V5")
	)
	(via
		(at 208.778348 -48.076358)
		(size 0.508)
		(drill 0.254)
		(layers "F.Cu" "B.Cu")
		(net "P1V5")
	)
	(via
		(at 101.341682 -179.514246)
		(size 0.508)
		(drill 0.254)
		(layers "F.Cu" "B.Cu")
		(net "P1V5")
	)
	(segment
		(start 64.7446 -177.5714)
		(end 65.224152 -177.091848)
		(width 0.254)
		(layer "B.Cu")
		(net "P1V5")
	)
	(segment
		(start 103.658924 -43.510708)
		(end 103.658924 -39.335964)
		(width 0.254)
		(layer "B.Cu")
		(net "P1V5")
	)
	(segment
		(start 102.810056 -119.500142)
		(end 102.358952 -119.049038)
		(width 0.254)
		(layer "B.Cu")
		(net "P1V5")
	)
	(segment
		(start 52.0192 -177.5714)
		(end 64.7446 -177.5714)
		(width 0.254)
		(layer "B.Cu")
		(net "P1V5")
	)
	(segment
		(start 101.341682 -179.514246)
		(end 102.810056 -178.045872)
		(width 0.254)
		(layer "B.Cu")
		(net "P1V5")
	)
	(segment
		(start 103.658924 -39.335964)
		(end 101.70922 -37.38626)
		(width 0.254)
		(layer "B.Cu")
		(net "P1V5")
	)
	(segment
		(start 65.224152 -177.091848)
		(end 65.70345 -176.61255)
		(width 0.254)
		(layer "B.Cu")
		(net "P1V5")
	)
	(segment
		(start 139.29614 -20.871688)
		(end 135.020812 -20.871688)
		(width 0.254)
		(layer "B.Cu")
		(net "P1V5")
	)
	(segment
		(start 127.6223 -28.2702)
		(end 124.4854 -28.2702)
		(width 0.254)
		(layer "B.Cu")
		(net "P1V5")
	)
	(segment
		(start 65.70345 -176.61255)
		(end 70.59295 -176.61255)
		(width 0.254)
		(layer "B.Cu")
		(net "P1V5")
	)
	(segment
		(start 139.797028 -20.3708)
		(end 139.29614 -20.871688)
		(width 0.254)
		(layer "B.Cu")
		(net "P1V5")
	)
	(segment
		(start 70.59295 -176.61255)
		(end 71.7042 -177.7238)
		(width 0.254)
		(layer "B.Cu")
		(net "P1V5")
	)
	(segment
		(start 144.572228 -20.8026)
		(end 144.140428 -20.3708)
		(width 0.254)
		(layer "B.Cu")
		(net "P1V5")
	)
	(segment
		(start 50.9016 -176.4538)
		(end 52.0192 -177.5714)
		(width 0.254)
		(layer "B.Cu")
		(net "P1V5")
	)
	(segment
		(start 144.140428 -20.3708)
		(end 139.797028 -20.3708)
		(width 0.254)
		(layer "B.Cu")
		(net "P1V5")
	)
	(segment
		(start 102.810056 -178.045872)
		(end 102.810056 -119.500142)
		(width 0.254)
		(layer "B.Cu")
		(net "P1V5")
	)
	(segment
		(start 102.358952 -44.81068)
		(end 103.658924 -43.510708)
		(width 0.254)
		(layer "B.Cu")
		(net "P1V5")
	)
	(segment
		(start 146.8882 -20.8026)
		(end 144.572228 -20.8026)
		(width 0.254)
		(layer "B.Cu")
		(net "P1V5")
	)
	(segment
		(start 102.358952 -119.049038)
		(end 102.358952 -44.81068)
		(width 0.254)
		(layer "B.Cu")
		(net "P1V5")
	)
	(segment
		(start 135.020812 -20.871688)
		(end 127.6223 -28.2702)
		(width 0.254)
		(layer "B.Cu")
		(net "P1V5")
	)
	(segment
		(start 49.7586 -164.85108)
		(end 49.7586 -164.9349)
		(width 0.254)
		(layer "B.Cu")
		(net "P1V5")
	)
	(segment
		(start 147.0406 -20.955)
		(end 146.8882 -20.8026)
		(width 0.254)
		(layer "B.Cu")
		(net "P1V5")
	)
	(segment
		(start 51.7271 -162.88258)
		(end 49.7586 -164.85108)
		(width 0.254)
		(layer "B.Cu")
		(net "P1V5")
	)
	(segment
		(start 71.7042 -177.7238)
		(end 71.7042 -177.8254)
		(width 0.254)
		(layer "B.Cu")
		(net "P1V5")
	)
	(segment
		(start 117.104922 -28.1178)
		(end 115.696238 -26.709116)
		(width 0.254)
		(layer "In2.Cu")
		(net "P1V5")
	)
	(segment
		(start 52.451 -174.9044)
		(end 50.9016 -176.4538)
		(width 0.254)
		(layer "In2.Cu")
		(net "P1V5")
	)
	(segment
		(start 49.7586 -164.9349)
		(end 49.7586 -166.116)
		(width 0.254)
		(layer "In2.Cu")
		(net "P1V5")
	)
	(segment
		(start 117.128544 -28.1178)
		(end 117.104922 -28.1178)
		(width 0.254)
		(layer "In2.Cu")
		(net "P1V5")
	)
	(segment
		(start 101.57206 -30.249368)
		(end 101.57206 -37.2491)
		(width 0.254)
		(layer "In2.Cu")
		(net "P1V5")
	)
	(segment
		(start 208.778348 -48.076358)
		(end 208.98104 -48.27905)
		(width 0.254)
		(layer "In2.Cu")
		(net "P1V5")
	)
	(segment
		(start 210.77682 -95.000826)
		(end 206.98333 -95.000826)
		(width 0.254)
		(layer "In2.Cu")
		(net "P1V5")
	)
	(segment
		(start 215.862916 -89.91473)
		(end 210.77682 -95.000826)
		(width 0.254)
		(layer "In2.Cu")
		(net "P1V5")
	)
	(segment
		(start 50.9778 -167.3352)
		(end 50.9778 -169.366946)
		(width 0.254)
		(layer "In2.Cu")
		(net "P1V5")
	)
	(segment
		(start 218.962478 -61.558424)
		(end 218.962478 -77.51064)
		(width 0.254)
		(layer "In2.Cu")
		(net "P1V5")
	)
	(segment
		(start 105.112312 -26.709116)
		(end 101.57206 -30.249368)
		(width 0.254)
		(layer "In2.Cu")
		(net "P1V5")
	)
	(segment
		(start 50.9778 -169.366946)
		(end 52.451 -170.840146)
		(width 0.254)
		(layer "In2.Cu")
		(net "P1V5")
	)
	(segment
		(start 208.98104 -48.27905)
		(end 208.98104 -51.576986)
		(width 0.254)
		(layer "In2.Cu")
		(net "P1V5")
	)
	(segment
		(start 215.862916 -80.610202)
		(end 215.862916 -89.91473)
		(width 0.254)
		(layer "In2.Cu")
		(net "P1V5")
	)
	(segment
		(start 117.280944 -28.2702)
		(end 117.128544 -28.1178)
		(width 0.254)
		(layer "In2.Cu")
		(net "P1V5")
	)
	(segment
		(start 49.7586 -166.116)
		(end 50.9778 -167.3352)
		(width 0.254)
		(layer "In2.Cu")
		(net "P1V5")
	)
	(segment
		(start 218.962478 -77.51064)
		(end 215.862916 -80.610202)
		(width 0.254)
		(layer "In2.Cu")
		(net "P1V5")
	)
	(segment
		(start 115.696238 -26.709116)
		(end 105.112312 -26.709116)
		(width 0.254)
		(layer "In2.Cu")
		(net "P1V5")
	)
	(segment
		(start 208.98104 -51.576986)
		(end 218.962478 -61.558424)
		(width 0.254)
		(layer "In2.Cu")
		(net "P1V5")
	)
	(segment
		(start 206.98333 -95.000826)
		(end 206.906368 -95.077788)
		(width 0.254)
		(layer "In2.Cu")
		(net "P1V5")
	)
	(segment
		(start 52.451 -170.840146)
		(end 52.451 -174.9044)
		(width 0.254)
		(layer "In2.Cu")
		(net "P1V5")
	)
	(segment
		(start 101.57206 -37.2491)
		(end 101.70922 -37.38626)
		(width 0.254)
		(layer "In2.Cu")
		(net "P1V5")
	)
	(segment
		(start 82.28584 -178.8287)
		(end 80.72374 -177.2666)
		(width 0.254)
		(layer "In5.Cu")
		(net "P1V5")
	)
	(segment
		(start 73.93686 -177.2666)
		(end 73.37806 -177.8254)
		(width 0.254)
		(layer "In5.Cu")
		(net "P1V5")
	)
	(segment
		(start 166.5224 -40.5638)
		(end 171.650406 -40.5638)
		(width 0.254)
		(layer "In5.Cu")
		(net "P1V5")
	)
	(segment
		(start 200.166732 -48.478186)
		(end 208.412334 -48.478186)
		(width 0.254)
		(layer "In5.Cu")
		(net "P1V5")
	)
	(segment
		(start 160.782 -36.2966)
		(end 162.2552 -36.2966)
		(width 0.254)
		(layer "In5.Cu")
		(net "P1V5")
	)
	(segment
		(start 173.466506 -42.3799)
		(end 194.068446 -42.3799)
		(width 0.254)
		(layer "In5.Cu")
		(net "P1V5")
	)
	(segment
		(start 73.37806 -177.8254)
		(end 71.7042 -177.8254)
		(width 0.254)
		(layer "In5.Cu")
		(net "P1V5")
	)
	(segment
		(start 147.0406 -20.955)
		(end 147.1168 -21.0312)
		(width 0.254)
		(layer "In5.Cu")
		(net "P1V5")
	)
	(segment
		(start 147.1168 -21.0312)
		(end 147.1168 -22.6314)
		(width 0.254)
		(layer "In5.Cu")
		(net "P1V5")
	)
	(segment
		(start 85.214206 -179.2478)
		(end 82.6262 -179.2478)
		(width 0.254)
		(layer "In5.Cu")
		(net "P1V5")
	)
	(segment
		(start 80.72374 -177.2666)
		(end 73.93686 -177.2666)
		(width 0.254)
		(layer "In5.Cu")
		(net "P1V5")
	)
	(segment
		(start 89.03716 -179.8447)
		(end 85.811106 -179.8447)
		(width 0.254)
		(layer "In5.Cu")
		(net "P1V5")
	)
	(segment
		(start 147.1168 -22.6314)
		(end 160.782 -36.2966)
		(width 0.254)
		(layer "In5.Cu")
		(net "P1V5")
	)
	(segment
		(start 85.811106 -179.8447)
		(end 85.214206 -179.2478)
		(width 0.254)
		(layer "In5.Cu")
		(net "P1V5")
	)
	(segment
		(start 89.367614 -179.514246)
		(end 89.03716 -179.8447)
		(width 0.254)
		(layer "In5.Cu")
		(net "P1V5")
	)
	(segment
		(start 194.068446 -42.3799)
		(end 200.166732 -48.478186)
		(width 0.254)
		(layer "In5.Cu")
		(net "P1V5")
	)
	(segment
		(start 101.341682 -179.514246)
		(end 89.367614 -179.514246)
		(width 0.254)
		(layer "In5.Cu")
		(net "P1V5")
	)
	(segment
		(start 82.28584 -178.90744)
		(end 82.28584 -178.8287)
		(width 0.254)
		(layer "In5.Cu")
		(net "P1V5")
	)
	(segment
		(start 208.412334 -48.478186)
		(end 208.778348 -48.112172)
		(width 0.254)
		(layer "In5.Cu")
		(net "P1V5")
	)
	(segment
		(start 82.6262 -179.2478)
		(end 82.28584 -178.90744)
		(width 0.254)
		(layer "In5.Cu")
		(net "P1V5")
	)
	(segment
		(start 208.778348 -48.112172)
		(end 208.778348 -48.076358)
		(width 0.254)
		(layer "In5.Cu")
		(net "P1V5")
	)
	(segment
		(start 162.2552 -36.2966)
		(end 166.5224 -40.5638)
		(width 0.254)
		(layer "In5.Cu")
		(net "P1V5")
	)
	(segment
		(start 124.4854 -28.2702)
		(end 117.280944 -28.2702)
		(width 0.254)
		(layer "In5.Cu")
		(net "P1V5")
	)
	(segment
		(start 171.650406 -40.5638)
		(end 173.466506 -42.3799)
		(width 0.254)
		(layer "In5.Cu")
		(net "P1V5")
	)
	(segment
		(start 16.834612 -142.161514)
		(end 16.834104 -142.161514)
		(width 0.3048)
		(layer "F.Cu")
		(net "P1V2_STBY")
	)
	(segment
		(start 16.833342 -137.361676)
		(end 16.434054 -137.760964)
		(width 0.3048)
		(layer "F.Cu")
		(net "P1V2_STBY")
	)
	(segment
		(start 17.634458 -142.161768)
		(end 17.234662 -142.561564)
		(width 0.254)
		(layer "F.Cu")
		(net "P1V2_STBY")
	)
	(segment
		(start 23.234396 -147.761452)
		(end 23.634192 -147.361656)
		(width 0.3048)
		(layer "F.Cu")
		(net "P1V2_STBY")
	)
	(segment
		(start 52.963064 -167.548052)
		(end 52.963064 -166.865554)
		(width 0.508)
		(layer "F.Cu")
		(net "P1V2_STBY")
	)
	(segment
		(start 53.0606 -168.192958)
		(end 53.0606 -167.645588)
		(width 0.508)
		(layer "F.Cu")
		(net "P1V2_STBY")
	)
	(segment
		(start 44.72813 -147.438364)
		(end 44.366434 -147.80006)
		(width 0.3556)
		(layer "F.Cu")
		(net "P1V2_STBY")
	)
	(segment
		(start 44.099988 -143.800068)
		(end 44.099734 -143.800068)
		(width 0.3556)
		(layer "F.Cu")
		(net "P1V2_STBY")
	)
	(segment
		(start 49.4538 -168.7068)
		(end 52.546758 -168.7068)
		(width 0.508)
		(layer "F.Cu")
		(net "P1V2_STBY")
	)
	(segment
		(start 24.05888 -141.386052)
		(end 24.05888 -141.518132)
		(width 0.3048)
		(layer "F.Cu")
		(net "P1V2_STBY")
	)
	(segment
		(start 13.363702 -136.713468)
		(end 13.361924 -136.715246)
		(width 0.508)
		(layer "F.Cu")
		(net "P1V2_STBY")
	)
	(segment
		(start 25.15743 -132.798058)
		(end 24.869902 -132.51053)
		(width 0.508)
		(layer "F.Cu")
		(net "P1V2_STBY")
	)
	(segment
		(start 52.546758 -168.7068)
		(end 53.0606 -168.192958)
		(width 0.508)
		(layer "F.Cu")
		(net "P1V2_STBY")
	)
	(segment
		(start 23.634954 -148.956014)
		(end 23.634954 -149.216364)
		(width 0.3048)
		(layer "F.Cu")
		(net "P1V2_STBY")
	)
	(segment
		(start 44.72813 -146.828002)
		(end 44.72813 -147.438364)
		(width 0.3556)
		(layer "F.Cu")
		(net "P1V2_STBY")
	)
	(segment
		(start 16.834612 -137.361676)
		(end 16.833342 -137.361676)
		(width 0.3048)
		(layer "F.Cu")
		(net "P1V2_STBY")
	)
	(segment
		(start 13.361162 -139.579604)
		(end 13.354558 -139.573)
		(width 0.508)
		(layer "F.Cu")
		(net "P1V2_STBY")
	)
	(segment
		(start 16.834612 -146.961606)
		(end 16.834866 -146.961606)
		(width 0.254)
		(layer "F.Cu")
		(net "P1V2_STBY")
	)
	(segment
		(start 23.234396 -140.561568)
		(end 24.05888 -141.386052)
		(width 0.3048)
		(layer "F.Cu")
		(net "P1V2_STBY")
	)
	(segment
		(start 23.368 -131.4323)
		(end 23.368 -132.437886)
		(width 0.508)
		(layer "F.Cu")
		(net "P1V2_STBY")
	)
	(segment
		(start 22.43455 -144.561306)
		(end 22.834346 -144.16151)
		(width 0.3048)
		(layer "F.Cu")
		(net "P1V2_STBY")
	)
	(segment
		(start 23.234396 -146.161506)
		(end 23.634446 -145.761456)
		(width 0.3048)
		(layer "F.Cu")
		(net "P1V2_STBY")
	)
	(segment
		(start 44.525692 -146.625564)
		(end 44.72813 -146.828002)
		(width 0.3556)
		(layer "F.Cu")
		(net "P1V2_STBY")
	)
	(segment
		(start 44.099988 -143.00073)
		(end 43.700192 -143.400526)
		(width 0.3556)
		(layer "F.Cu")
		(net "P1V2_STBY")
	)
	(segment
		(start 44.099734 -144.599914)
		(end 43.699938 -144.200118)
		(width 0.3556)
		(layer "F.Cu")
		(net "P1V2_STBY")
	)
	(segment
		(start 22.434296 -142.161514)
		(end 22.0345 -142.56131)
		(width 0.3048)
		(layer "F.Cu")
		(net "P1V2_STBY")
	)
	(segment
		(start 16.834612 -148.561552)
		(end 16.434562 -148.961602)
		(width 0.3048)
		(layer "F.Cu")
		(net "P1V2_STBY")
	)
	(segment
		(start 17.634458 -144.56156)
		(end 17.634458 -144.561814)
		(width 0.3048)
		(layer "F.Cu")
		(net "P1V2_STBY")
	)
	(segment
		(start 16.834612 -146.161506)
		(end 16.834612 -146.16176)
		(width 0.254)
		(layer "F.Cu")
		(net "P1V2_STBY")
	)
	(segment
		(start 23.234396 -136.334246)
		(end 23.5204 -136.048242)
		(width 0.3048)
		(layer "F.Cu")
		(net "P1V2_STBY")
	)
	(segment
		(start 22.011386 -131.451858)
		(end 22.011386 -132.51053)
		(width 0.508)
		(layer "F.Cu")
		(net "P1V2_STBY")
	)
	(segment
		(start 53.0606 -167.645588)
		(end 52.963064 -167.548052)
		(width 0.508)
		(layer "F.Cu")
		(net "P1V2_STBY")
	)
	(segment
		(start 44.099988 -142.999968)
		(end 44.099988 -143.00073)
		(width 0.3556)
		(layer "F.Cu")
		(net "P1V2_STBY")
	)
	(segment
		(start 17.634458 -142.161514)
		(end 17.634458 -142.161768)
		(width 0.254)
		(layer "F.Cu")
		(net "P1V2_STBY")
	)
	(segment
		(start 25.682702 -132.798058)
		(end 25.15743 -132.798058)
		(width 0.508)
		(layer "F.Cu")
		(net "P1V2_STBY")
	)
	(segment
		(start 16.834358 -143.76146)
		(end 16.434054 -144.161764)
		(width 0.3048)
		(layer "F.Cu")
		(net "P1V2_STBY")
	)
	(segment
		(start 13.33119 -141.008862)
		(end 11.236198 -141.008862)
		(width 0.508)
		(layer "F.Cu")
		(net "P1V2_STBY")
	)
	(segment
		(start 13.354558 -139.573)
		(end 11.1887 -139.573)
		(width 0.508)
		(layer "F.Cu")
		(net "P1V2_STBY")
	)
	(segment
		(start 16.834612 -146.16176)
		(end 17.234662 -146.56181)
		(width 0.254)
		(layer "F.Cu")
		(net "P1V2_STBY")
	)
	(segment
		(start 22.43455 -142.161514)
		(end 22.434296 -142.161514)
		(width 0.3048)
		(layer "F.Cu")
		(net "P1V2_STBY")
	)
	(segment
		(start 44.099988 -144.599914)
		(end 44.099734 -144.599914)
		(width 0.3556)
		(layer "F.Cu")
		(net "P1V2_STBY")
	)
	(segment
		(start 11.215624 -135.285988)
		(end 13.595096 -135.285988)
		(width 0.508)
		(layer "F.Cu")
		(net "P1V2_STBY")
	)
	(segment
		(start 49.149 -168.402)
		(end 49.4538 -168.7068)
		(width 0.508)
		(layer "F.Cu")
		(net "P1V2_STBY")
	)
	(segment
		(start 23.240492 -148.561552)
		(end 23.634954 -148.956014)
		(width 0.3048)
		(layer "F.Cu")
		(net "P1V2_STBY")
	)
	(segment
		(start 23.234396 -148.561552)
		(end 23.240492 -148.561552)
		(width 0.3048)
		(layer "F.Cu")
		(net "P1V2_STBY")
	)
	(segment
		(start 20.582128 -131.451858)
		(end 20.582128 -132.51053)
		(width 0.508)
		(layer "F.Cu")
		(net "P1V2_STBY")
	)
	(segment
		(start 16.53667 -140.561568)
		(end 16.117824 -140.980414)
		(width 0.3048)
		(layer "F.Cu")
		(net "P1V2_STBY")
	)
	(segment
		(start 16.834866 -146.961606)
		(end 17.234662 -146.56181)
		(width 0.254)
		(layer "F.Cu")
		(net "P1V2_STBY")
	)
	(segment
		(start 18.434558 -147.761452)
		(end 18.834354 -148.161248)
		(width 0.3048)
		(layer "F.Cu")
		(net "P1V2_STBY")
	)
	(segment
		(start 23.368 -132.437886)
		(end 23.440644 -132.51053)
		(width 0.508)
		(layer "F.Cu")
		(net "P1V2_STBY")
	)
	(segment
		(start 23.234396 -142.161514)
		(end 23.234142 -142.161514)
		(width 0.254)
		(layer "F.Cu")
		(net "P1V2_STBY")
	)
	(segment
		(start 22.43455 -144.56156)
		(end 22.43455 -144.561306)
		(width 0.3048)
		(layer "F.Cu")
		(net "P1V2_STBY")
	)
	(segment
		(start 16.834612 -140.561568)
		(end 16.53667 -140.561568)
		(width 0.3048)
		(layer "F.Cu")
		(net "P1V2_STBY")
	)
	(segment
		(start 44.366434 -147.80006)
		(end 44.099988 -147.80006)
		(width 0.3556)
		(layer "F.Cu")
		(net "P1V2_STBY")
	)
	(segment
		(start 18.834354 -148.161248)
		(end 18.834608 -148.161248)
		(width 0.3048)
		(layer "F.Cu")
		(net "P1V2_STBY")
	)
	(segment
		(start 44.099734 -143.800068)
		(end 43.700192 -143.400526)
		(width 0.3556)
		(layer "F.Cu")
		(net "P1V2_STBY")
	)
	(segment
		(start 16.834612 -143.76146)
		(end 16.834358 -143.76146)
		(width 0.3048)
		(layer "F.Cu")
		(net "P1V2_STBY")
	)
	(segment
		(start 23.234142 -142.161514)
		(end 22.834346 -142.56131)
		(width 0.254)
		(layer "F.Cu")
		(net "P1V2_STBY")
	)
	(segment
		(start 21.63445 -143.76146)
		(end 21.2344 -144.16151)
		(width 0.3048)
		(layer "F.Cu")
		(net "P1V2_STBY")
	)
	(segment
		(start 11.241024 -138.144504)
		(end 13.311632 -138.144504)
		(width 0.508)
		(layer "F.Cu")
		(net "P1V2_STBY")
	)
	(segment
		(start 23.234396 -136.561576)
		(end 23.234396 -136.334246)
		(width 0.3048)
		(layer "F.Cu")
		(net "P1V2_STBY")
	)
	(segment
		(start 19.15287 -131.451858)
		(end 19.15287 -132.51053)
		(width 0.508)
		(layer "F.Cu")
		(net "P1V2_STBY")
	)
	(segment
		(start 17.634458 -144.561814)
		(end 17.234662 -144.96161)
		(width 0.3048)
		(layer "F.Cu")
		(net "P1V2_STBY")
	)
	(segment
		(start 17.723612 -131.451858)
		(end 17.723612 -132.51053)
		(width 0.508)
		(layer "F.Cu")
		(net "P1V2_STBY")
	)
	(segment
		(start 16.834104 -142.161514)
		(end 16.434054 -142.561564)
		(width 0.3048)
		(layer "F.Cu")
		(net "P1V2_STBY")
	)
	(segment
		(start 23.234396 -143.76146)
		(end 22.834346 -144.16151)
		(width 0.3048)
		(layer "F.Cu")
		(net "P1V2_STBY")
	)
	(segment
		(start 13.361924 -136.715246)
		(end 11.241024 -136.715246)
		(width 0.508)
		(layer "F.Cu")
		(net "P1V2_STBY")
	)
	(segment
		(start 44.099988 -146.19986)
		(end 44.525692 -146.625564)
		(width 0.3048)
		(layer "F.Cu")
		(net "P1V2_STBY")
	)
	(via
		(at 16.434054 -137.760964)
		(size 0.508)
		(drill 0.254)
		(layers "F.Cu" "B.Cu")
		(net "P1V2_STBY")
	)
	(via
		(at 17.234662 -144.96161)
		(size 0.508)
		(drill 0.254)
		(layers "F.Cu" "B.Cu")
		(net "P1V2_STBY")
	)
	(via
		(at 20.582128 -132.51053)
		(size 0.508)
		(drill 0.254)
		(layers "F.Cu" "B.Cu")
		(net "P1V2_STBY")
	)
	(via
		(at 21.2344 -144.16151)
		(size 0.508)
		(drill 0.254)
		(layers "F.Cu" "B.Cu")
		(net "P1V2_STBY")
	)
	(via
		(at 43.699938 -144.200118)
		(size 0.4572)
		(drill 0.2032)
		(layers "F.Cu" "B.Cu")
		(net "P1V2_STBY")
	)
	(via
		(at 23.634446 -145.761456)
		(size 0.508)
		(drill 0.254)
		(layers "F.Cu" "B.Cu")
		(net "P1V2_STBY")
	)
	(via
		(at 22.834346 -142.56131)
		(size 0.508)
		(drill 0.254)
		(layers "F.Cu" "B.Cu")
		(net "P1V2_STBY")
	)
	(via
		(at 29.748734 -147.319492)
		(size 0.6096)
		(drill 0.3048)
		(layers "F.Cu" "B.Cu")
		(net "P1V2_STBY")
	)
	(via
		(at 17.723612 -132.51053)
		(size 0.508)
		(drill 0.254)
		(layers "F.Cu" "B.Cu")
		(net "P1V2_STBY")
	)
	(via
		(at 22.0345 -142.56131)
		(size 0.508)
		(drill 0.254)
		(layers "F.Cu" "B.Cu")
		(net "P1V2_STBY")
	)
	(via
		(at 16.434054 -144.161764)
		(size 0.508)
		(drill 0.254)
		(layers "F.Cu" "B.Cu")
		(net "P1V2_STBY")
	)
	(via
		(at 23.634192 -147.361656)
		(size 0.508)
		(drill 0.254)
		(layers "F.Cu" "B.Cu")
		(net "P1V2_STBY")
	)
	(via
		(at 24.869902 -132.51053)
		(size 0.508)
		(drill 0.254)
		(layers "F.Cu" "B.Cu")
		(net "P1V2_STBY")
	)
	(via
		(at 23.5204 -136.048242)
		(size 0.508)
		(drill 0.254)
		(layers "F.Cu" "B.Cu")
		(net "P1V2_STBY")
	)
	(via
		(at 16.434562 -148.961602)
		(size 0.508)
		(drill 0.254)
		(layers "F.Cu" "B.Cu")
		(net "P1V2_STBY")
	)
	(via
		(at 13.311632 -138.144504)
		(size 0.508)
		(drill 0.254)
		(layers "F.Cu" "B.Cu")
		(net "P1V2_STBY")
	)
	(via
		(at 23.440644 -132.51053)
		(size 0.508)
		(drill 0.254)
		(layers "F.Cu" "B.Cu")
		(net "P1V2_STBY")
	)
	(via
		(at 19.15287 -132.51053)
		(size 0.508)
		(drill 0.254)
		(layers "F.Cu" "B.Cu")
		(net "P1V2_STBY")
	)
	(via
		(at 20.404836 -158.79445)
		(size 0.7112)
		(drill 0.4064)
		(layers "F.Cu" "B.Cu")
		(net "P1V2_STBY")
	)
	(via
		(at 18.834608 -148.161248)
		(size 0.508)
		(drill 0.254)
		(layers "F.Cu" "B.Cu")
		(net "P1V2_STBY")
	)
	(via
		(at 13.5382 -142.463266)
		(size 0.508)
		(drill 0.254)
		(layers "F.Cu" "B.Cu")
		(net "P1V2_STBY")
	)
	(via
		(at 16.117824 -140.980414)
		(size 0.508)
		(drill 0.254)
		(layers "F.Cu" "B.Cu")
		(net "P1V2_STBY")
	)
	(via
		(at 22.011386 -132.51053)
		(size 0.508)
		(drill 0.254)
		(layers "F.Cu" "B.Cu")
		(net "P1V2_STBY")
	)
	(via
		(at 44.525692 -146.625564)
		(size 0.4572)
		(drill 0.2032)
		(layers "F.Cu" "B.Cu")
		(net "P1V2_STBY")
	)
	(via
		(at 23.634954 -149.216364)
		(size 0.508)
		(drill 0.254)
		(layers "F.Cu" "B.Cu")
		(net "P1V2_STBY")
	)
	(via
		(at 16.434054 -142.561564)
		(size 0.508)
		(drill 0.254)
		(layers "F.Cu" "B.Cu")
		(net "P1V2_STBY")
	)
	(via
		(at 32.20212 -142.944088)
		(size 0.6096)
		(drill 0.3048)
		(layers "F.Cu" "B.Cu")
		(net "P1V2_STBY")
	)
	(via
		(at 49.149 -168.402)
		(size 0.508)
		(drill 0.254)
		(layers "F.Cu" "B.Cu")
		(net "P1V2_STBY")
	)
	(via
		(at 17.234662 -142.561564)
		(size 0.508)
		(drill 0.254)
		(layers "F.Cu" "B.Cu")
		(net "P1V2_STBY")
	)
	(via
		(at 13.595096 -135.285988)
		(size 0.508)
		(drill 0.254)
		(layers "F.Cu" "B.Cu")
		(net "P1V2_STBY")
	)
	(via
		(at 13.33119 -141.008862)
		(size 0.508)
		(drill 0.254)
		(layers "F.Cu" "B.Cu")
		(net "P1V2_STBY")
	)
	(via
		(at 13.363702 -136.713468)
		(size 0.508)
		(drill 0.254)
		(layers "F.Cu" "B.Cu")
		(net "P1V2_STBY")
	)
	(via
		(at 19.185636 -158.79445)
		(size 0.7112)
		(drill 0.4064)
		(layers "F.Cu" "B.Cu")
		(net "P1V2_STBY")
	)
	(via
		(at 24.05888 -141.518132)
		(size 0.508)
		(drill 0.254)
		(layers "F.Cu" "B.Cu")
		(net "P1V2_STBY")
	)
	(via
		(at 13.595096 -133.85673)
		(size 0.508)
		(drill 0.254)
		(layers "F.Cu" "B.Cu")
		(net "P1V2_STBY")
	)
	(via
		(at 13.595096 -132.402326)
		(size 0.508)
		(drill 0.254)
		(layers "F.Cu" "B.Cu")
		(net "P1V2_STBY")
	)
	(via
		(at 43.700192 -143.400526)
		(size 0.4572)
		(drill 0.2032)
		(layers "F.Cu" "B.Cu")
		(net "P1V2_STBY")
	)
	(via
		(at 13.361162 -139.579604)
		(size 0.508)
		(drill 0.254)
		(layers "F.Cu" "B.Cu")
		(net "P1V2_STBY")
	)
	(via
		(at 17.234662 -146.56181)
		(size 0.508)
		(drill 0.254)
		(layers "F.Cu" "B.Cu")
		(net "P1V2_STBY")
	)
	(via
		(at 22.834346 -144.16151)
		(size 0.508)
		(drill 0.254)
		(layers "F.Cu" "B.Cu")
		(net "P1V2_STBY")
	)
	(via
		(at 16.294354 -132.51053)
		(size 0.508)
		(drill 0.254)
		(layers "F.Cu" "B.Cu")
		(net "P1V2_STBY")
	)
	(segment
		(start 12.536424 -138.144504)
		(end 13.311632 -138.144504)
		(width 0.508)
		(layer "B.Cu")
		(net "P1V2_STBY")
	)
	(segment
		(start 24.869902 -131.451858)
		(end 24.869902 -132.51053)
		(width 0.508)
		(layer "B.Cu")
		(net "P1V2_STBY")
	)
	(segment
		(start 12.55649 -141.008862)
		(end 13.33119 -141.008862)
		(width 0.508)
		(layer "B.Cu")
		(net "P1V2_STBY")
	)
	(segment
		(start 16.294354 -131.451858)
		(end 16.294354 -132.51053)
		(width 0.508)
		(layer "B.Cu")
		(net "P1V2_STBY")
	)
	(segment
		(start 44.666408 -145.810732)
		(end 44.666408 -146.484848)
		(width 0.4572)
		(layer "B.Cu")
		(net "P1V2_STBY")
	)
	(segment
		(start 20.582128 -131.451858)
		(end 20.582128 -132.51053)
		(width 0.508)
		(layer "B.Cu")
		(net "P1V2_STBY")
	)
	(segment
		(start 12.536424 -133.85673)
		(end 13.595096 -133.85673)
		(width 0.508)
		(layer "B.Cu")
		(net "P1V2_STBY")
	)
	(segment
		(start 13.361924 -136.715246)
		(end 13.363702 -136.713468)
		(width 0.508)
		(layer "B.Cu")
		(net "P1V2_STBY")
	)
	(segment
		(start 22.011386 -131.451858)
		(end 22.011386 -132.51053)
		(width 0.508)
		(layer "B.Cu")
		(net "P1V2_STBY")
	)
	(segment
		(start 12.55649 -142.463266)
		(end 13.5382 -142.463266)
		(width 0.508)
		(layer "B.Cu")
		(net "P1V2_STBY")
	)
	(segment
		(start 19.15287 -131.451858)
		(end 19.15287 -132.51053)
		(width 0.508)
		(layer "B.Cu")
		(net "P1V2_STBY")
	)
	(segment
		(start 24.890476 -141.03096)
		(end 24.546052 -141.03096)
		(width 0.508)
		(layer "B.Cu")
		(net "P1V2_STBY")
	)
	(segment
		(start 12.536424 -132.402326)
		(end 13.595096 -132.402326)
		(width 0.508)
		(layer "B.Cu")
		(net "P1V2_STBY")
	)
	(segment
		(start 43.835574 -144.335754)
		(end 43.699938 -144.200118)
		(width 0.508)
		(layer "B.Cu")
		(net "P1V2_STBY")
	)
	(segment
		(start 12.536424 -136.715246)
		(end 13.361924 -136.715246)
		(width 0.508)
		(layer "B.Cu")
		(net "P1V2_STBY")
	)
	(segment
		(start 24.546052 -141.03096)
		(end 24.05888 -141.518132)
		(width 0.508)
		(layer "B.Cu")
		(net "P1V2_STBY")
	)
	(segment
		(start 44.538392 -144.335754)
		(end 43.835574 -144.335754)
		(width 0.508)
		(layer "B.Cu")
		(net "P1V2_STBY")
	)
	(segment
		(start 23.440644 -131.451858)
		(end 23.440644 -132.51053)
		(width 0.508)
		(layer "B.Cu")
		(net "P1V2_STBY")
	)
	(segment
		(start 12.536424 -135.285988)
		(end 13.595096 -135.285988)
		(width 0.508)
		(layer "B.Cu")
		(net "P1V2_STBY")
	)
	(segment
		(start 44.666408 -146.484848)
		(end 44.525692 -146.625564)
		(width 0.4572)
		(layer "B.Cu")
		(net "P1V2_STBY")
	)
	(segment
		(start 12.55649 -139.579604)
		(end 13.361162 -139.579604)
		(width 0.508)
		(layer "B.Cu")
		(net "P1V2_STBY")
	)
	(segment
		(start 17.723612 -131.451858)
		(end 17.723612 -132.51053)
		(width 0.508)
		(layer "B.Cu")
		(net "P1V2_STBY")
	)
	(segment
		(start 47.029878 -168.402)
		(end 43.59402 -164.966142)
		(width 0.762)
		(layer "In5.Cu")
		(net "P1V2_STBY")
	)
	(segment
		(start 49.149 -168.402)
		(end 47.029878 -168.402)
		(width 0.762)
		(layer "In5.Cu")
		(net "P1V2_STBY")
	)
	(segment
		(start 31.9405 -162.395154)
		(end 31.9405 -159.47771)
		(width 0.762)
		(layer "In5.Cu")
		(net "P1V2_STBY")
	)
	(segment
		(start 43.59402 -164.966142)
		(end 34.511488 -164.966142)
		(width 0.762)
		(layer "In5.Cu")
		(net "P1V2_STBY")
	)
	(segment
		(start 34.511488 -164.966142)
		(end 31.9405 -162.395154)
		(width 0.762)
		(layer "In5.Cu")
		(net "P1V2_STBY")
	)
	(segment
		(start 31.25724 -158.79445)
		(end 20.404836 -158.79445)
		(width 0.762)
		(layer "In5.Cu")
		(net "P1V2_STBY")
	)
	(segment
		(start 31.9405 -159.47771)
		(end 31.25724 -158.79445)
		(width 0.762)
		(layer "In5.Cu")
		(net "P1V2_STBY")
	)
	(segment
		(start 46.49978 -141.400022)
		(end 46.500034 -141.400022)
		(width 0.254)
		(layer "F.Cu")
		(net "P1V15_STBY")
	)
	(segment
		(start 45.699426 -146.19986)
		(end 45.300138 -145.800572)
		(width 0.254)
		(layer "F.Cu")
		(net "P1V15_STBY")
	)
	(segment
		(start 48.09998 -148.599906)
		(end 48.499776 -148.999702)
		(width 0.254)
		(layer "F.Cu")
		(net "P1V15_STBY")
	)
	(segment
		(start 51.699668 -148.999956)
		(end 51.299872 -148.60016)
		(width 0.254)
		(layer "F.Cu")
		(net "P1V15_STBY")
	)
	(segment
		(start 45.699934 -148.599906)
		(end 45.699934 -148.60016)
		(width 0.254)
		(layer "F.Cu")
		(net "P1V15_STBY")
	)
	(segment
		(start 46.100238 -141.00048)
		(end 46.49978 -141.400022)
		(width 0.254)
		(layer "F.Cu")
		(net "P1V15_STBY")
	)
	(segment
		(start 45.699172 -146.99996)
		(end 45.299376 -146.600164)
		(width 0.254)
		(layer "F.Cu")
		(net "P1V15_STBY")
	)
	(segment
		(start 45.69968 -143.800068)
		(end 45.300138 -143.400526)
		(width 0.254)
		(layer "F.Cu")
		(net "P1V15_STBY")
	)
	(segment
		(start 45.300138 -145.800572)
		(end 45.699934 -145.400776)
		(width 0.254)
		(layer "F.Cu")
		(net "P1V15_STBY")
	)
	(segment
		(start 51.299872 -145.39976)
		(end 50.900076 -144.999964)
		(width 0.254)
		(layer "F.Cu")
		(net "P1V15_STBY")
	)
	(segment
		(start 52.099972 -149.400006)
		(end 52.099718 -149.400006)
		(width 0.254)
		(layer "F.Cu")
		(net "P1V15_STBY")
	)
	(segment
		(start 51.699922 -142.600172)
		(end 51.699668 -142.600172)
		(width 0.254)
		(layer "F.Cu")
		(net "P1V15_STBY")
	)
	(segment
		(start 51.299872 -147.80006)
		(end 51.299872 -147.799806)
		(width 0.254)
		(layer "F.Cu")
		(net "P1V15_STBY")
	)
	(segment
		(start 44.899834 -148.60016)
		(end 44.899834 -148.599906)
		(width 0.254)
		(layer "F.Cu")
		(net "P1V15_STBY")
	)
	(segment
		(start 44.900088 -141.400022)
		(end 45.299884 -141.000226)
		(width 0.254)
		(layer "F.Cu")
		(net "P1V15_STBY")
	)
	(segment
		(start 45.699934 -148.60016)
		(end 45.299884 -149.00021)
		(width 0.254)
		(layer "F.Cu")
		(net "P1V15_STBY")
	)
	(segment
		(start 51.299872 -147.799806)
		(end 51.699668 -147.40001)
		(width 0.254)
		(layer "F.Cu")
		(net "P1V15_STBY")
	)
	(segment
		(start 42.500042 -140.599922)
		(end 42.099992 -140.199872)
		(width 0.254)
		(layer "F.Cu")
		(net "P1V15_STBY")
	)
	(segment
		(start 51.699668 -143.400272)
		(end 51.299872 -143.800068)
		(width 0.254)
		(layer "F.Cu")
		(net "P1V15_STBY")
	)
	(segment
		(start 49.70018 -141.400022)
		(end 50.10023 -140.999972)
		(width 0.254)
		(layer "F.Cu")
		(net "P1V15_STBY")
	)
	(segment
		(start 45.699934 -146.99996)
		(end 45.699172 -146.99996)
		(width 0.254)
		(layer "F.Cu")
		(net "P1V15_STBY")
	)
	(segment
		(start 51.299872 -148.60016)
		(end 51.299872 -148.599906)
		(width 0.254)
		(layer "F.Cu")
		(net "P1V15_STBY")
	)
	(segment
		(start 46.500034 -148.599906)
		(end 46.500034 -148.60016)
		(width 0.254)
		(layer "F.Cu")
		(net "P1V15_STBY")
	)
	(segment
		(start 45.699934 -143.00073)
		(end 45.699934 -142.999968)
		(width 0.254)
		(layer "F.Cu")
		(net "P1V15_STBY")
	)
	(segment
		(start 51.699668 -142.600172)
		(end 51.299872 -142.999968)
		(width 0.254)
		(layer "F.Cu")
		(net "P1V15_STBY")
	)
	(segment
		(start 45.699934 -141.400022)
		(end 45.700696 -141.400022)
		(width 0.254)
		(layer "F.Cu")
		(net "P1V15_STBY")
	)
	(segment
		(start 45.699934 -145.400776)
		(end 45.699934 -145.400014)
		(width 0.254)
		(layer "F.Cu")
		(net "P1V15_STBY")
	)
	(segment
		(start 45.699934 -143.800068)
		(end 45.69968 -143.800068)
		(width 0.254)
		(layer "F.Cu")
		(net "P1V15_STBY")
	)
	(segment
		(start 45.299884 -149.00021)
		(end 44.899834 -148.60016)
		(width 0.254)
		(layer "F.Cu")
		(net "P1V15_STBY")
	)
	(segment
		(start 45.699934 -146.19986)
		(end 45.699426 -146.19986)
		(width 0.254)
		(layer "F.Cu")
		(net "P1V15_STBY")
	)
	(segment
		(start 50.10023 -140.999972)
		(end 50.500026 -141.399768)
		(width 0.254)
		(layer "F.Cu")
		(net "P1V15_STBY")
	)
	(segment
		(start 44.899834 -141.400022)
		(end 44.900088 -141.400022)
		(width 0.254)
		(layer "F.Cu")
		(net "P1V15_STBY")
	)
	(segment
		(start 51.299872 -142.199868)
		(end 51.299872 -142.200122)
		(width 0.254)
		(layer "F.Cu")
		(net "P1V15_STBY")
	)
	(segment
		(start 40.099996 -140.599922)
		(end 40.099996 -140.599668)
		(width 0.254)
		(layer "F.Cu")
		(net "P1V15_STBY")
	)
	(segment
		(start 51.699922 -143.400272)
		(end 51.699668 -143.400272)
		(width 0.254)
		(layer "F.Cu")
		(net "P1V15_STBY")
	)
	(segment
		(start 51.299872 -145.400014)
		(end 51.299872 -145.39976)
		(width 0.254)
		(layer "F.Cu")
		(net "P1V15_STBY")
	)
	(segment
		(start 48.499776 -140.999972)
		(end 48.09998 -140.600176)
		(width 0.254)
		(layer "F.Cu")
		(net "P1V15_STBY")
	)
	(segment
		(start 45.699934 -144.600676)
		(end 45.699934 -144.599914)
		(width 0.254)
		(layer "F.Cu")
		(net "P1V15_STBY")
	)
	(segment
		(start 51.299872 -142.200122)
		(end 51.699922 -142.600172)
		(width 0.254)
		(layer "F.Cu")
		(net "P1V15_STBY")
	)
	(segment
		(start 45.300138 -145.000472)
		(end 45.699934 -144.600676)
		(width 0.254)
		(layer "F.Cu")
		(net "P1V15_STBY")
	)
	(segment
		(start 51.299872 -147.000214)
		(end 51.299872 -146.99996)
		(width 0.254)
		(layer "F.Cu")
		(net "P1V15_STBY")
	)
	(segment
		(start 51.699668 -147.40001)
		(end 51.299872 -147.000214)
		(width 0.254)
		(layer "F.Cu")
		(net "P1V15_STBY")
	)
	(segment
		(start 52.099718 -149.400006)
		(end 51.699668 -148.999956)
		(width 0.254)
		(layer "F.Cu")
		(net "P1V15_STBY")
	)
	(segment
		(start 48.09998 -140.600176)
		(end 48.09998 -140.599922)
		(width 0.254)
		(layer "F.Cu")
		(net "P1V15_STBY")
	)
	(segment
		(start 40.099996 -140.599668)
		(end 40.499792 -140.199872)
		(width 0.254)
		(layer "F.Cu")
		(net "P1V15_STBY")
	)
	(segment
		(start 51.299872 -146.19986)
		(end 50.900076 -145.800064)
		(width 0.254)
		(layer "F.Cu")
		(net "P1V15_STBY")
	)
	(segment
		(start 45.300138 -143.400526)
		(end 45.699934 -143.00073)
		(width 0.254)
		(layer "F.Cu")
		(net "P1V15_STBY")
	)
	(segment
		(start 50.500026 -141.399768)
		(end 50.500026 -141.400022)
		(width 0.254)
		(layer "F.Cu")
		(net "P1V15_STBY")
	)
	(segment
		(start 51.299872 -144.600168)
		(end 51.299872 -144.599914)
		(width 0.254)
		(layer "F.Cu")
		(net "P1V15_STBY")
	)
	(segment
		(start 45.700696 -141.400022)
		(end 46.100238 -141.00048)
		(width 0.254)
		(layer "F.Cu")
		(net "P1V15_STBY")
	)
	(segment
		(start 50.900076 -144.999964)
		(end 51.299872 -144.600168)
		(width 0.254)
		(layer "F.Cu")
		(net "P1V15_STBY")
	)
	(segment
		(start 66.839084 -160.038034)
		(end 67.709034 -160.038034)
		(width 0.508)
		(layer "F.Cu")
		(net "P1V15_STBY")
	)
	(segment
		(start 48.499776 -148.999702)
		(end 48.499776 -148.999956)
		(width 0.254)
		(layer "F.Cu")
		(net "P1V15_STBY")
	)
	(segment
		(start 46.500034 -148.60016)
		(end 46.100238 -148.999956)
		(width 0.254)
		(layer "F.Cu")
		(net "P1V15_STBY")
	)
	(segment
		(start 49.699926 -141.400022)
		(end 49.70018 -141.400022)
		(width 0.254)
		(layer "F.Cu")
		(net "P1V15_STBY")
	)
	(via
		(at 45.300138 -145.800572)
		(size 0.4572)
		(drill 0.2032)
		(layers "F.Cu" "B.Cu")
		(net "P1V15_STBY")
	)
	(via
		(at 47.76851 -133.086348)
		(size 0.6096)
		(drill 0.3048)
		(layers "F.Cu" "B.Cu")
		(net "P1V15_STBY")
	)
	(via
		(at 42.33926 -156.22524)
		(size 0.508)
		(drill 0.254)
		(layers "F.Cu" "B.Cu")
		(net "P1V15_STBY")
	)
	(via
		(at 42.099992 -140.199872)
		(size 0.4572)
		(drill 0.2032)
		(layers "F.Cu" "B.Cu")
		(net "P1V15_STBY")
	)
	(via
		(at 45.299884 -141.000226)
		(size 0.4572)
		(drill 0.2032)
		(layers "F.Cu" "B.Cu")
		(net "P1V15_STBY")
	)
	(via
		(at 48.499776 -148.999956)
		(size 0.4572)
		(drill 0.2032)
		(layers "F.Cu" "B.Cu")
		(net "P1V15_STBY")
	)
	(via
		(at 42.3164 -156.9339)
		(size 0.508)
		(drill 0.254)
		(layers "F.Cu" "B.Cu")
		(net "P1V15_STBY")
	)
	(via
		(at 51.699668 -147.40001)
		(size 0.4572)
		(drill 0.2032)
		(layers "F.Cu" "B.Cu")
		(net "P1V15_STBY")
	)
	(via
		(at 45.299376 -146.600164)
		(size 0.4572)
		(drill 0.2032)
		(layers "F.Cu" "B.Cu")
		(net "P1V15_STBY")
	)
	(via
		(at 50.900076 -144.999964)
		(size 0.4572)
		(drill 0.2032)
		(layers "F.Cu" "B.Cu")
		(net "P1V15_STBY")
	)
	(via
		(at 51.699668 -148.999956)
		(size 0.4572)
		(drill 0.2032)
		(layers "F.Cu" "B.Cu")
		(net "P1V15_STBY")
	)
	(via
		(at 77.7494 -152.273)
		(size 0.508)
		(drill 0.254)
		(layers "F.Cu" "B.Cu")
		(net "P1V15_STBY")
	)
	(via
		(at 45.300138 -143.400526)
		(size 0.4572)
		(drill 0.2032)
		(layers "F.Cu" "B.Cu")
		(net "P1V15_STBY")
	)
	(via
		(at 46.100238 -141.00048)
		(size 0.4572)
		(drill 0.2032)
		(layers "F.Cu" "B.Cu")
		(net "P1V15_STBY")
	)
	(via
		(at 76.824586 -152.280874)
		(size 0.508)
		(drill 0.254)
		(layers "F.Cu" "B.Cu")
		(net "P1V15_STBY")
	)
	(via
		(at 51.699922 -143.400272)
		(size 0.4572)
		(drill 0.2032)
		(layers "F.Cu" "B.Cu")
		(net "P1V15_STBY")
	)
	(via
		(at 76.75372 -153.183336)
		(size 0.508)
		(drill 0.254)
		(layers "F.Cu" "B.Cu")
		(net "P1V15_STBY")
	)
	(via
		(at 46.100238 -148.999956)
		(size 0.4572)
		(drill 0.2032)
		(layers "F.Cu" "B.Cu")
		(net "P1V15_STBY")
	)
	(via
		(at 40.499792 -140.199872)
		(size 0.4572)
		(drill 0.2032)
		(layers "F.Cu" "B.Cu")
		(net "P1V15_STBY")
	)
	(via
		(at 50.900076 -145.800064)
		(size 0.4572)
		(drill 0.2032)
		(layers "F.Cu" "B.Cu")
		(net "P1V15_STBY")
	)
	(via
		(at 50.10023 -140.999972)
		(size 0.4572)
		(drill 0.2032)
		(layers "F.Cu" "B.Cu")
		(net "P1V15_STBY")
	)
	(via
		(at 48.5394 -133.604)
		(size 0.508)
		(drill 0.254)
		(layers "F.Cu" "B.Cu")
		(net "P1V15_STBY")
	)
	(via
		(at 48.499776 -140.999972)
		(size 0.4572)
		(drill 0.2032)
		(layers "F.Cu" "B.Cu")
		(net "P1V15_STBY")
	)
	(via
		(at 45.300138 -145.000472)
		(size 0.4572)
		(drill 0.2032)
		(layers "F.Cu" "B.Cu")
		(net "P1V15_STBY")
	)
	(via
		(at 48.5648 -134.4676)
		(size 0.508)
		(drill 0.254)
		(layers "F.Cu" "B.Cu")
		(net "P1V15_STBY")
	)
	(via
		(at 77.782674 -153.136092)
		(size 0.508)
		(drill 0.254)
		(layers "F.Cu" "B.Cu")
		(net "P1V15_STBY")
	)
	(via
		(at 67.709034 -160.038034)
		(size 0.508)
		(drill 0.254)
		(layers "F.Cu" "B.Cu")
		(net "P1V15_STBY")
	)
	(via
		(at 45.299884 -149.00021)
		(size 0.4572)
		(drill 0.2032)
		(layers "F.Cu" "B.Cu")
		(net "P1V15_STBY")
	)
	(via
		(at 51.699922 -142.600172)
		(size 0.4572)
		(drill 0.2032)
		(layers "F.Cu" "B.Cu")
		(net "P1V15_STBY")
	)
	(segment
		(start 51.699668 -139.400534)
		(end 51.699668 -140.200126)
		(width 0.127)
		(layer "F.Cu")
		(net "P12V_A_PGOOD_R")
	)
	(segment
		(start 51.699668 -140.200126)
		(end 51.299872 -140.599922)
		(width 0.127)
		(layer "F.Cu")
		(net "P12V_A_PGOOD_R")
	)
	(via
		(at 52.36972 -129.419096)
		(size 0.508)
		(drill 0.254)
		(layers "F.Cu" "B.Cu")
		(net "P12V_A_PGOOD_R")
	)
	(via
		(at 51.699668 -139.400534)
		(size 0.4572)
		(drill 0.2032)
		(layers "F.Cu" "B.Cu")
		(net "P12V_A_PGOOD_R")
	)
	(via
		(at 50.769774 -128.906778)
		(size 0.6096)
		(drill 0.3048)
		(layers "F.Cu" "B.Cu")
		(net "P12V_A_PGOOD_R")
	)
	(segment
		(start 50.769774 -128.906778)
		(end 50.769774 -127.783082)
		(width 0.127)
		(layer "B.Cu")
		(net "P12V_A_PGOOD_R")
	)
	(segment
		(start 52.36972 -129.419096)
		(end 52.197 -129.419096)
		(width 0.127)
		(layer "B.Cu")
		(net "P12V_A_PGOOD_R")
	)
	(segment
		(start 52.177696 -129.4384)
		(end 51.301396 -129.4384)
		(width 0.127)
		(layer "B.Cu")
		(net "P12V_A_PGOOD_R")
	)
	(segment
		(start 52.197 -129.419096)
		(end 52.177696 -129.4384)
		(width 0.127)
		(layer "B.Cu")
		(net "P12V_A_PGOOD_R")
	)
	(segment
		(start 51.301396 -129.4384)
		(end 50.769774 -128.906778)
		(width 0.127)
		(layer "B.Cu")
		(net "P12V_A_PGOOD_R")
	)
	(segment
		(start 50.769774 -127.783082)
		(end 50.772568 -127.780288)
		(width 0.127)
		(layer "B.Cu")
		(net "P12V_A_PGOOD_R")
	)
	(segment
		(start 52.0446 -135.7376)
		(end 52.0446 -137.90041)
		(width 0.127)
		(layer "In2.Cu")
		(net "P12V_A_PGOOD_R")
	)
	(segment
		(start 52.1589 -129.629916)
		(end 52.1589 -135.6233)
		(width 0.127)
		(layer "In2.Cu")
		(net "P12V_A_PGOOD_R")
	)
	(segment
		(start 52.36972 -129.419096)
		(end 52.1589 -129.629916)
		(width 0.127)
		(layer "In2.Cu")
		(net "P12V_A_PGOOD_R")
	)
	(segment
		(start 52.11699 -138.983212)
		(end 51.699668 -139.400534)
		(width 0.0889)
		(layer "In2.Cu")
		(net "P12V_A_PGOOD_R")
	)
	(segment
		(start 52.0446 -137.90041)
		(end 52.11699 -137.9728)
		(width 0.127)
		(layer "In2.Cu")
		(net "P12V_A_PGOOD_R")
	)
	(segment
		(start 52.1589 -135.6233)
		(end 52.0446 -135.7376)
		(width 0.127)
		(layer "In2.Cu")
		(net "P12V_A_PGOOD_R")
	)
	(segment
		(start 52.11699 -137.9728)
		(end 52.11699 -138.983212)
		(width 0.0889)
		(layer "In2.Cu")
		(net "P12V_A_PGOOD_R")
	)
	(segment
		(start 193.20002 -67.109594)
		(end 193.20002 -67.099942)
		(width 0.3556)
		(layer "F.Cu")
		(net "P0V975")
	)
	(segment
		(start 193.999866 -67.900042)
		(end 193.990468 -67.900042)
		(width 0.3556)
		(layer "F.Cu")
		(net "P0V975")
	)
	(segment
		(start 192.39992 -64.699896)
		(end 192.390776 -64.699896)
		(width 0.3556)
		(layer "F.Cu")
		(net "P0V975")
	)
	(segment
		(start 188.399928 -68.709286)
		(end 188.793882 -69.10324)
		(width 0.254)
		(layer "F.Cu")
		(net "P0V975")
	)
	(segment
		(start 97.251012 -83.69681)
		(end 97.32518 -83.770978)
		(width 0.508)
		(layer "F.Cu")
		(net "P0V975")
	)
	(segment
		(start 191.600074 -65.50914)
		(end 191.600074 -65.499996)
		(width 0.3556)
		(layer "F.Cu")
		(net "P0V975")
	)
	(segment
		(start 190.393828 -67.503294)
		(end 189.999874 -67.10934)
		(width 0.3556)
		(layer "F.Cu")
		(net "P0V975")
	)
	(segment
		(start 192.390776 -64.699896)
		(end 191.990726 -64.299846)
		(width 0.3556)
		(layer "F.Cu")
		(net "P0V975")
	)
	(segment
		(start 190.393574 -69.10324)
		(end 190.393574 -69.093588)
		(width 0.3556)
		(layer "F.Cu")
		(net "P0V975")
	)
	(segment
		(start 192.39992 -63.099696)
		(end 192.39992 -63.09995)
		(width 0.3556)
		(layer "F.Cu")
		(net "P0V975")
	)
	(segment
		(start 192.390522 -67.900042)
		(end 191.990472 -67.499992)
		(width 0.3556)
		(layer "F.Cu")
		(net "P0V975")
	)
	(segment
		(start 195.190618 -64.300608)
		(end 195.190618 -64.299846)
		(width 0.3556)
		(layer "F.Cu")
		(net "P0V975")
	)
	(segment
		(start 190.799974 -63.09995)
		(end 190.790576 -63.09995)
		(width 0.3556)
		(layer "F.Cu")
		(net "P0V975")
	)
	(segment
		(start 188.399928 -68.699888)
		(end 188.399928 -68.709286)
		(width 0.254)
		(layer "F.Cu")
		(net "P0V975")
	)
	(segment
		(start 195.60921 -63.09995)
		(end 195.999862 -62.709298)
		(width 0.3048)
		(layer "F.Cu")
		(net "P0V975")
	)
	(segment
		(start 194.799966 -62.29985)
		(end 194.799966 -62.309248)
		(width 0.3556)
		(layer "F.Cu")
		(net "P0V975")
	)
	(segment
		(start 193.990468 -63.09995)
		(end 193.590418 -62.6999)
		(width 0.3556)
		(layer "F.Cu")
		(net "P0V975")
	)
	(segment
		(start 188.793628 -65.903094)
		(end 188.399928 -65.509394)
		(width 0.3556)
		(layer "F.Cu")
		(net "P0V975")
	)
	(segment
		(start 193.999866 -66.299842)
		(end 193.999866 -66.290444)
		(width 0.3556)
		(layer "F.Cu")
		(net "P0V975")
	)
	(segment
		(start 196.399912 -62.309248)
		(end 195.999862 -62.709298)
		(width 0.3556)
		(layer "F.Cu")
		(net "P0V975")
	)
	(segment
		(start 189.190376 -67.900042)
		(end 189.200028 -67.900042)
		(width 0.3556)
		(layer "F.Cu")
		(net "P0V975")
	)
	(segment
		(start 189.19063 -64.699896)
		(end 188.793628 -64.302894)
		(width 0.3556)
		(layer "F.Cu")
		(net "P0V975")
	)
	(segment
		(start 189.200028 -64.699896)
		(end 189.19063 -64.699896)
		(width 0.3556)
		(layer "F.Cu")
		(net "P0V975")
	)
	(segment
		(start 188.399928 -62.29985)
		(end 188.799978 -62.6999)
		(width 0.3556)
		(layer "F.Cu")
		(net "P0V975")
	)
	(segment
		(start 193.590672 -64.299846)
		(end 193.20002 -63.909194)
		(width 0.3556)
		(layer "F.Cu")
		(net "P0V975")
	)
	(segment
		(start 192.8368 -128.0795)
		(end 192.8368 -129.032)
		(width 0.508)
		(layer "F.Cu")
		(net "P0V975")
	)
	(segment
		(start 195.19392 -67.503548)
		(end 194.799966 -67.109594)
		(width 0.3556)
		(layer "F.Cu")
		(net "P0V975")
	)
	(segment
		(start 189.999874 -62.309248)
		(end 189.999874 -62.29985)
		(width 0.3556)
		(layer "F.Cu")
		(net "P0V975")
	)
	(segment
		(start 191.600074 -68.699888)
		(end 191.600074 -68.709286)
		(width 0.254)
		(layer "F.Cu")
		(net "P0V975")
	)
	(segment
		(start 96.755712 -41.663366)
		(end 97.251012 -42.158666)
		(width 0.508)
		(layer "F.Cu")
		(net "P0V975")
	)
	(segment
		(start 194.799966 -62.309248)
		(end 195.190618 -62.6999)
		(width 0.3556)
		(layer "F.Cu")
		(net "P0V975")
	)
	(segment
		(start 192.390522 -61.500004)
		(end 192.39992 -61.500004)
		(width 0.3556)
		(layer "F.Cu")
		(net "P0V975")
	)
	(segment
		(start 195.600066 -66.290444)
		(end 195.203572 -65.89395)
		(width 0.3556)
		(layer "F.Cu")
		(net "P0V975")
	)
	(segment
		(start 193.999866 -61.490352)
		(end 193.603118 -61.093604)
		(width 0.254)
		(layer "F.Cu")
		(net "P0V975")
	)
	(segment
		(start 189.999874 -67.10934)
		(end 189.999874 -67.099942)
		(width 0.3556)
		(layer "F.Cu")
		(net "P0V975")
	)
	(segment
		(start 193.999866 -63.09995)
		(end 193.990468 -63.09995)
		(width 0.3556)
		(layer "F.Cu")
		(net "P0V975")
	)
	(segment
		(start 188.793628 -67.503294)
		(end 189.190376 -67.900042)
		(width 0.3556)
		(layer "F.Cu")
		(net "P0V975")
	)
	(segment
		(start 196.399912 -62.29985)
		(end 196.399912 -62.309248)
		(width 0.3556)
		(layer "F.Cu")
		(net "P0V975")
	)
	(segment
		(start 193.209418 -65.499996)
		(end 193.20002 -65.499996)
		(width 0.3556)
		(layer "F.Cu")
		(net "P0V975")
	)
	(segment
		(start 189.19063 -61.500004)
		(end 188.793374 -61.102748)
		(width 0.3556)
		(layer "F.Cu")
		(net "P0V975")
	)
	(segment
		(start 188.399928 -63.909194)
		(end 188.399928 -63.90005)
		(width 0.3556)
		(layer "F.Cu")
		(net "P0V975")
	)
	(segment
		(start 193.990468 -67.900042)
		(end 193.593974 -67.503548)
		(width 0.3556)
		(layer "F.Cu")
		(net "P0V975")
	)
	(segment
		(start 190.790576 -67.900042)
		(end 190.393828 -67.503294)
		(width 0.3556)
		(layer "F.Cu")
		(net "P0V975")
	)
	(segment
		(start 191.600074 -67.109594)
		(end 191.600074 -67.099942)
		(width 0.3556)
		(layer "F.Cu")
		(net "P0V975")
	)
	(segment
		(start 105.463594 -18.100802)
		(end 104.480614 -18.100802)
		(width 0.508)
		(layer "F.Cu")
		(net "P0V975")
	)
	(segment
		(start 192.390776 -66.299842)
		(end 191.994028 -65.903094)
		(width 0.3556)
		(layer "F.Cu")
		(net "P0V975")
	)
	(segment
		(start 188.399928 -60.709302)
		(end 188.399928 -60.699904)
		(width 0.3556)
		(layer "F.Cu")
		(net "P0V975")
	)
	(segment
		(start 104.480614 -18.100802)
		(end 96.755712 -25.825704)
		(width 0.508)
		(layer "F.Cu")
		(net "P0V975")
	)
	(segment
		(start 195.599812 -59.900058)
		(end 194.799966 -60.699904)
		(width 0.254)
		(layer "F.Cu")
		(net "P0V975")
	)
	(segment
		(start 97.251012 -42.158666)
		(end 97.251012 -83.69681)
		(width 0.508)
		(layer "F.Cu")
		(net "P0V975")
	)
	(segment
		(start 193.990722 -64.699896)
		(end 193.590672 -64.299846)
		(width 0.3556)
		(layer "F.Cu")
		(net "P0V975")
	)
	(segment
		(start 193.20002 -62.309502)
		(end 193.20002 -62.29985)
		(width 0.3556)
		(layer "F.Cu")
		(net "P0V975")
	)
	(segment
		(start 188.793374 -61.102748)
		(end 188.399928 -60.709302)
		(width 0.3556)
		(layer "F.Cu")
		(net "P0V975")
	)
	(segment
		(start 191.990726 -64.299846)
		(end 191.600074 -63.909194)
		(width 0.3556)
		(layer "F.Cu")
		(net "P0V975")
	)
	(segment
		(start 195.589906 -64.699896)
		(end 195.190618 -64.300608)
		(width 0.3556)
		(layer "F.Cu")
		(net "P0V975")
	)
	(segment
		(start 190.000382 -63.90005)
		(end 189.999874 -63.90005)
		(width 0.3556)
		(layer "F.Cu")
		(net "P0V975")
	)
	(segment
		(start 188.399928 -67.109594)
		(end 188.399928 -67.099942)
		(width 0.3556)
		(layer "F.Cu")
		(net "P0V975")
	)
	(segment
		(start 190.799974 -64.699896)
		(end 190.799974 -64.699642)
		(width 0.3556)
		(layer "F.Cu")
		(net "P0V975")
	)
	(segment
		(start 190.790322 -61.500004)
		(end 190.799974 -61.500004)
		(width 0.3556)
		(layer "F.Cu")
		(net "P0V975")
	)
	(segment
		(start 195.600066 -59.900058)
		(end 195.599812 -59.900058)
		(width 0.254)
		(layer "F.Cu")
		(net "P0V975")
	)
	(segment
		(start 190.799974 -66.299842)
		(end 190.790576 -66.299842)
		(width 0.3556)
		(layer "F.Cu")
		(net "P0V975")
	)
	(segment
		(start 190.393574 -69.093588)
		(end 189.999874 -68.699888)
		(width 0.3556)
		(layer "F.Cu")
		(net "P0V975")
	)
	(segment
		(start 193.999866 -66.290444)
		(end 193.603372 -65.89395)
		(width 0.3556)
		(layer "F.Cu")
		(net "P0V975")
	)
	(segment
		(start 192.000378 -62.700154)
		(end 192.39992 -63.099696)
		(width 0.3556)
		(layer "F.Cu")
		(net "P0V975")
	)
	(segment
		(start 188.793628 -64.302894)
		(end 188.399928 -63.909194)
		(width 0.3556)
		(layer "F.Cu")
		(net "P0V975")
	)
	(segment
		(start 195.600066 -63.09995)
		(end 195.60921 -63.09995)
		(width 0.3048)
		(layer "F.Cu")
		(net "P0V975")
	)
	(segment
		(start 193.593974 -67.503548)
		(end 193.20002 -67.109594)
		(width 0.3556)
		(layer "F.Cu")
		(net "P0V975")
	)
	(segment
		(start 190.400432 -64.3001)
		(end 190.000382 -63.90005)
		(width 0.3556)
		(layer "F.Cu")
		(net "P0V975")
	)
	(segment
		(start 189.190376 -66.299842)
		(end 188.793628 -65.903094)
		(width 0.3556)
		(layer "F.Cu")
		(net "P0V975")
	)
	(segment
		(start 188.799978 -62.6999)
		(end 189.200028 -63.09995)
		(width 0.3556)
		(layer "F.Cu")
		(net "P0V975")
	)
	(segment
		(start 194.799966 -60.699904)
		(end 194.799966 -60.700412)
		(width 0.254)
		(layer "F.Cu")
		(net "P0V975")
	)
	(segment
		(start 191.600074 -62.29985)
		(end 192.000378 -62.700154)
		(width 0.3556)
		(layer "F.Cu")
		(net "P0V975")
	)
	(segment
		(start 195.190618 -64.299846)
		(end 194.799966 -63.909194)
		(width 0.3556)
		(layer "F.Cu")
		(net "P0V975")
	)
	(segment
		(start 188.399928 -65.509394)
		(end 188.399928 -65.499996)
		(width 0.3556)
		(layer "F.Cu")
		(net "P0V975")
	)
	(segment
		(start 190.799974 -67.900042)
		(end 190.790576 -67.900042)
		(width 0.3556)
		(layer "F.Cu")
		(net "P0V975")
	)
	(segment
		(start 193.20002 -63.909194)
		(end 193.20002 -63.90005)
		(width 0.3556)
		(layer "F.Cu")
		(net "P0V975")
	)
	(segment
		(start 194.799966 -67.109594)
		(end 194.799966 -67.099942)
		(width 0.3556)
		(layer "F.Cu")
		(net "P0V975")
	)
	(segment
		(start 190.393828 -65.903094)
		(end 189.999874 -65.50914)
		(width 0.3556)
		(layer "F.Cu")
		(net "P0V975")
	)
	(segment
		(start 190.790576 -66.299842)
		(end 190.393828 -65.903094)
		(width 0.3556)
		(layer "F.Cu")
		(net "P0V975")
	)
	(segment
		(start 191.99352 -61.103002)
		(end 192.390522 -61.500004)
		(width 0.3556)
		(layer "F.Cu")
		(net "P0V975")
	)
	(segment
		(start 189.200028 -61.500004)
		(end 189.19063 -61.500004)
		(width 0.3556)
		(layer "F.Cu")
		(net "P0V975")
	)
	(segment
		(start 193.999866 -61.500004)
		(end 193.999866 -61.490352)
		(width 0.254)
		(layer "F.Cu")
		(net "P0V975")
	)
	(segment
		(start 194.799966 -60.700412)
		(end 194.40017 -61.100208)
		(width 0.254)
		(layer "F.Cu")
		(net "P0V975")
	)
	(segment
		(start 195.600066 -64.699896)
		(end 195.589906 -64.699896)
		(width 0.3556)
		(layer "F.Cu")
		(net "P0V975")
	)
	(segment
		(start 194.809618 -65.499996)
		(end 194.799966 -65.499996)
		(width 0.3556)
		(layer "F.Cu")
		(net "P0V975")
	)
	(segment
		(start 190.390526 -62.6999)
		(end 189.999874 -62.309248)
		(width 0.3556)
		(layer "F.Cu")
		(net "P0V975")
	)
	(segment
		(start 189.999874 -65.50914)
		(end 189.999874 -65.499996)
		(width 0.3556)
		(layer "F.Cu")
		(net "P0V975")
	)
	(segment
		(start 193.603372 -65.89395)
		(end 193.209418 -65.499996)
		(width 0.3556)
		(layer "F.Cu")
		(net "P0V975")
	)
	(segment
		(start 195.203572 -65.89395)
		(end 194.809618 -65.499996)
		(width 0.3556)
		(layer "F.Cu")
		(net "P0V975")
	)
	(segment
		(start 188.793628 -67.503294)
		(end 188.399928 -67.109594)
		(width 0.3556)
		(layer "F.Cu")
		(net "P0V975")
	)
	(segment
		(start 193.999866 -64.699896)
		(end 193.990722 -64.699896)
		(width 0.3556)
		(layer "F.Cu")
		(net "P0V975")
	)
	(segment
		(start 189.200028 -66.299842)
		(end 189.190376 -66.299842)
		(width 0.3556)
		(layer "F.Cu")
		(net "P0V975")
	)
	(segment
		(start 191.990472 -67.499992)
		(end 191.600074 -67.109594)
		(width 0.3556)
		(layer "F.Cu")
		(net "P0V975")
	)
	(segment
		(start 195.600066 -66.299842)
		(end 195.600066 -66.290444)
		(width 0.3556)
		(layer "F.Cu")
		(net "P0V975")
	)
	(segment
		(start 191.600074 -63.909194)
		(end 191.600074 -63.90005)
		(width 0.3556)
		(layer "F.Cu")
		(net "P0V975")
	)
	(segment
		(start 192.39992 -67.900042)
		(end 192.390522 -67.900042)
		(width 0.3556)
		(layer "F.Cu")
		(net "P0V975")
	)
	(segment
		(start 193.590418 -62.6999)
		(end 193.20002 -62.309502)
		(width 0.3556)
		(layer "F.Cu")
		(net "P0V975")
	)
	(segment
		(start 190.799974 -64.699642)
		(end 190.400432 -64.3001)
		(width 0.3556)
		(layer "F.Cu")
		(net "P0V975")
	)
	(segment
		(start 194.799966 -63.909194)
		(end 194.799966 -63.90005)
		(width 0.3556)
		(layer "F.Cu")
		(net "P0V975")
	)
	(segment
		(start 190.790576 -63.09995)
		(end 190.390526 -62.6999)
		(width 0.3556)
		(layer "F.Cu")
		(net "P0V975")
	)
	(segment
		(start 191.600074 -68.709286)
		(end 191.994028 -69.10324)
		(width 0.254)
		(layer "F.Cu")
		(net "P0V975")
	)
	(segment
		(start 192.39992 -66.299842)
		(end 192.390776 -66.299842)
		(width 0.3556)
		(layer "F.Cu")
		(net "P0V975")
	)
	(segment
		(start 191.994028 -65.903094)
		(end 191.600074 -65.50914)
		(width 0.3556)
		(layer "F.Cu")
		(net "P0V975")
	)
	(segment
		(start 96.755712 -25.825704)
		(end 96.755712 -41.663366)
		(width 0.508)
		(layer "F.Cu")
		(net "P0V975")
	)
	(segment
		(start 190.39332 -61.103002)
		(end 190.790322 -61.500004)
		(width 0.3556)
		(layer "F.Cu")
		(net "P0V975")
	)
	(via
		(at 209.169 -110.871)
		(size 0.7112)
		(drill 0.4064)
		(layers "F.Cu" "B.Cu")
		(net "P0V975")
	)
	(via
		(at 191.994028 -69.10324)
		(size 0.508)
		(drill 0.254)
		(layers "F.Cu" "B.Cu")
		(net "P0V975")
	)
	(via
		(at 192.8368 -129.032)
		(size 0.508)
		(drill 0.254)
		(layers "F.Cu" "B.Cu")
		(net "P0V975")
	)
	(via
		(at 183.8706 -82.8929)
		(size 0.7112)
		(drill 0.4064)
		(layers "F.Cu" "B.Cu")
		(net "P0V975")
	)
	(via
		(at 190.393828 -65.903094)
		(size 0.508)
		(drill 0.254)
		(layers "F.Cu" "B.Cu")
		(net "P0V975")
	)
	(via
		(at 190.393574 -69.10324)
		(size 0.508)
		(drill 0.254)
		(layers "F.Cu" "B.Cu")
		(net "P0V975")
	)
	(via
		(at 190.393828 -67.503294)
		(size 0.508)
		(drill 0.254)
		(layers "F.Cu" "B.Cu")
		(net "P0V975")
	)
	(via
		(at 193.603118 -61.093604)
		(size 0.508)
		(drill 0.254)
		(layers "F.Cu" "B.Cu")
		(net "P0V975")
	)
	(via
		(at 201.5236 -110.744)
		(size 0.7112)
		(drill 0.4064)
		(layers "F.Cu" "B.Cu")
		(net "P0V975")
	)
	(via
		(at 223.811338 -100.207318)
		(size 0.7112)
		(drill 0.4064)
		(layers "F.Cu" "B.Cu")
		(net "P0V975")
	)
	(via
		(at 196.6468 -110.744)
		(size 0.7112)
		(drill 0.4064)
		(layers "F.Cu" "B.Cu")
		(net "P0V975")
	)
	(via
		(at 190.400432 -64.3001)
		(size 0.508)
		(drill 0.254)
		(layers "F.Cu" "B.Cu")
		(net "P0V975")
	)
	(via
		(at 188.793374 -61.102748)
		(size 0.508)
		(drill 0.254)
		(layers "F.Cu" "B.Cu")
		(net "P0V975")
	)
	(via
		(at 195.190618 -62.6999)
		(size 0.508)
		(drill 0.254)
		(layers "F.Cu" "B.Cu")
		(net "P0V975")
	)
	(via
		(at 191.994028 -65.903094)
		(size 0.508)
		(drill 0.254)
		(layers "F.Cu" "B.Cu")
		(net "P0V975")
	)
	(via
		(at 200.2536 -108.4834)
		(size 0.7112)
		(drill 0.4064)
		(layers "F.Cu" "B.Cu")
		(net "P0V975")
	)
	(via
		(at 197.866 -110.744)
		(size 0.7112)
		(drill 0.4064)
		(layers "F.Cu" "B.Cu")
		(net "P0V975")
	)
	(via
		(at 190.39332 -61.103002)
		(size 0.508)
		(drill 0.254)
		(layers "F.Cu" "B.Cu")
		(net "P0V975")
	)
	(via
		(at 105.463594 -18.100802)
		(size 0.508)
		(drill 0.254)
		(layers "F.Cu" "B.Cu")
		(net "P0V975")
	)
	(via
		(at 191.99352 -61.103002)
		(size 0.508)
		(drill 0.254)
		(layers "F.Cu" "B.Cu")
		(net "P0V975")
	)
	(via
		(at 188.793628 -67.503294)
		(size 0.508)
		(drill 0.254)
		(layers "F.Cu" "B.Cu")
		(net "P0V975")
	)
	(via
		(at 196.596 -108.4834)
		(size 0.7112)
		(drill 0.4064)
		(layers "F.Cu" "B.Cu")
		(net "P0V975")
	)
	(via
		(at 195.3768 -108.4834)
		(size 0.7112)
		(drill 0.4064)
		(layers "F.Cu" "B.Cu")
		(net "P0V975")
	)
	(via
		(at 205.5114 -110.871)
		(size 0.7112)
		(drill 0.4064)
		(layers "F.Cu" "B.Cu")
		(net "P0V975")
	)
	(via
		(at 199.0852 -110.744)
		(size 0.7112)
		(drill 0.4064)
		(layers "F.Cu" "B.Cu")
		(net "P0V975")
	)
	(via
		(at 204.2922 -110.871)
		(size 0.7112)
		(drill 0.4064)
		(layers "F.Cu" "B.Cu")
		(net "P0V975")
	)
	(via
		(at 194.1576 -108.4834)
		(size 0.7112)
		(drill 0.4064)
		(layers "F.Cu" "B.Cu")
		(net "P0V975")
	)
	(via
		(at 192.000378 -62.700154)
		(size 0.508)
		(drill 0.254)
		(layers "F.Cu" "B.Cu")
		(net "P0V975")
	)
	(via
		(at 190.390526 -62.6999)
		(size 0.508)
		(drill 0.254)
		(layers "F.Cu" "B.Cu")
		(net "P0V975")
	)
	(via
		(at 188.793882 -69.10324)
		(size 0.508)
		(drill 0.254)
		(layers "F.Cu" "B.Cu")
		(net "P0V975")
	)
	(via
		(at 193.590418 -62.6999)
		(size 0.508)
		(drill 0.254)
		(layers "F.Cu" "B.Cu")
		(net "P0V975")
	)
	(via
		(at 193.593974 -67.503548)
		(size 0.508)
		(drill 0.254)
		(layers "F.Cu" "B.Cu")
		(net "P0V975")
	)
	(via
		(at 188.799978 -62.6999)
		(size 0.508)
		(drill 0.254)
		(layers "F.Cu" "B.Cu")
		(net "P0V975")
	)
	(via
		(at 200.3044 -110.744)
		(size 0.7112)
		(drill 0.4064)
		(layers "F.Cu" "B.Cu")
		(net "P0V975")
	)
	(via
		(at 7.8994 -116.518182)
		(size 0.508)
		(drill 0.254)
		(layers "F.Cu" "B.Cu")
		(net "P0V975")
	)
	(via
		(at 97.32518 -83.770978)
		(size 0.508)
		(drill 0.254)
		(layers "F.Cu" "B.Cu")
		(net "P0V975")
	)
	(via
		(at 188.793628 -64.302894)
		(size 0.508)
		(drill 0.254)
		(layers "F.Cu" "B.Cu")
		(net "P0V975")
	)
	(via
		(at 108.712254 -6.418326)
		(size 0.508)
		(drill 0.254)
		(layers "F.Cu" "B.Cu")
		(net "P0V975")
	)
	(via
		(at 193.590672 -64.299846)
		(size 0.508)
		(drill 0.254)
		(layers "F.Cu" "B.Cu")
		(net "P0V975")
	)
	(via
		(at 194.40017 -61.100208)
		(size 0.508)
		(drill 0.254)
		(layers "F.Cu" "B.Cu")
		(net "P0V975")
	)
	(via
		(at 198.804022 -109.552232)
		(size 0.6604)
		(drill 0.3302)
		(layers "F.Cu" "B.Cu")
		(net "P0V975")
	)
	(via
		(at 30.226 -160.8328)
		(size 0.508)
		(drill 0.254)
		(layers "F.Cu" "B.Cu")
		(net "P0V975")
	)
	(via
		(at 191.990726 -64.299846)
		(size 0.508)
		(drill 0.254)
		(layers "F.Cu" "B.Cu")
		(net "P0V975")
	)
	(via
		(at 206.1464 -80.5942)
		(size 0.508)
		(drill 0.254)
		(layers "F.Cu" "B.Cu")
		(net "P0V975")
	)
	(via
		(at 223.745298 -101.466396)
		(size 0.7112)
		(drill 0.4064)
		(layers "F.Cu" "B.Cu")
		(net "P0V975")
	)
	(via
		(at 94.612714 -96.01835)
		(size 0.508)
		(drill 0.254)
		(layers "F.Cu" "B.Cu")
		(net "P0V975")
	)
	(via
		(at 151.508206 -3.58394)
		(size 0.508)
		(drill 0.254)
		(layers "F.Cu" "B.Cu")
		(net "P0V975")
	)
	(via
		(at 192.9384 -108.4834)
		(size 0.7112)
		(drill 0.4064)
		(layers "F.Cu" "B.Cu")
		(net "P0V975")
	)
	(via
		(at 190.5 -108.4834)
		(size 0.7112)
		(drill 0.4064)
		(layers "F.Cu" "B.Cu")
		(net "P0V975")
	)
	(via
		(at 193.603372 -65.89395)
		(size 0.508)
		(drill 0.254)
		(layers "F.Cu" "B.Cu")
		(net "P0V975")
	)
	(via
		(at 191.7192 -108.4834)
		(size 0.7112)
		(drill 0.4064)
		(layers "F.Cu" "B.Cu")
		(net "P0V975")
	)
	(via
		(at 191.990472 -67.499992)
		(size 0.508)
		(drill 0.254)
		(layers "F.Cu" "B.Cu")
		(net "P0V975")
	)
	(via
		(at 206.7306 -110.871)
		(size 0.7112)
		(drill 0.4064)
		(layers "F.Cu" "B.Cu")
		(net "P0V975")
	)
	(via
		(at 188.793628 -65.903094)
		(size 0.508)
		(drill 0.254)
		(layers "F.Cu" "B.Cu")
		(net "P0V975")
	)
	(via
		(at 195.19392 -67.503548)
		(size 0.508)
		(drill 0.254)
		(layers "F.Cu" "B.Cu")
		(net "P0V975")
	)
	(via
		(at 182.61076 -82.87258)
		(size 0.7112)
		(drill 0.4064)
		(layers "F.Cu" "B.Cu")
		(net "P0V975")
	)
	(via
		(at 154.7368 -83.9216)
		(size 0.7112)
		(drill 0.4064)
		(layers "F.Cu" "B.Cu")
		(net "P0V975")
	)
	(via
		(at 197.8152 -108.4834)
		(size 0.7112)
		(drill 0.4064)
		(layers "F.Cu" "B.Cu")
		(net "P0V975")
	)
	(via
		(at 195.999862 -62.709298)
		(size 0.508)
		(drill 0.254)
		(layers "F.Cu" "B.Cu")
		(net "P0V975")
	)
	(via
		(at 207.9498 -110.871)
		(size 0.7112)
		(drill 0.4064)
		(layers "F.Cu" "B.Cu")
		(net "P0V975")
	)
	(via
		(at 199.0344 -108.4834)
		(size 0.7112)
		(drill 0.4064)
		(layers "F.Cu" "B.Cu")
		(net "P0V975")
	)
	(via
		(at 195.203572 -65.89395)
		(size 0.508)
		(drill 0.254)
		(layers "F.Cu" "B.Cu")
		(net "P0V975")
	)
	(via
		(at 195.190618 -64.299846)
		(size 0.508)
		(drill 0.254)
		(layers "F.Cu" "B.Cu")
		(net "P0V975")
	)
	(segment
		(start 108.712254 -12.681712)
		(end 107.5182 -13.875766)
		(width 0.508)
		(layer "B.Cu")
		(net "P0V975")
	)
	(segment
		(start 74.945494 -113.7666)
		(end 76.68768 -112.024414)
		(width 0.508)
		(layer "B.Cu")
		(net "P0V975")
	)
	(segment
		(start 220.91142 -97.3074)
		(end 172.26026 -97.3074)
		(width 0.508)
		(layer "B.Cu")
		(net "P0V975")
	)
	(segment
		(start 76.68768 -112.024414)
		(end 89.55913 -112.024414)
		(width 0.508)
		(layer "B.Cu")
		(net "P0V975")
	)
	(segment
		(start 49.377854 -165.811708)
		(end 49.377854 -165.811454)
		(width 0.508)
		(layer "B.Cu")
		(net "P0V975")
	)
	(segment
		(start 48.93183 -165.36543)
		(end 48.931576 -165.36543)
		(width 0.508)
		(layer "B.Cu")
		(net "P0V975")
	)
	(segment
		(start 66.4972 -116.1542)
		(end 67.1576 -115.4938)
		(width 0.508)
		(layer "B.Cu")
		(net "P0V975")
	)
	(segment
		(start 37.332158 -162.2298)
		(end 36.4617 -162.2298)
		(width 0.508)
		(layer "B.Cu")
		(net "P0V975")
	)
	(segment
		(start 49.377854 -165.811454)
		(end 48.93183 -165.36543)
		(width 0.508)
		(layer "B.Cu")
		(net "P0V975")
	)
	(segment
		(start 37.947854 -162.859212)
		(end 37.947854 -162.845496)
		(width 0.508)
		(layer "B.Cu")
		(net "P0V975")
	)
	(segment
		(start 172.26026 -97.3074)
		(end 166.609268 -91.656408)
		(width 0.508)
		(layer "B.Cu")
		(net "P0V975")
	)
	(segment
		(start 11.133582 -113.284)
		(end 30.861 -113.284)
		(width 0.508)
		(layer "B.Cu")
		(net "P0V975")
	)
	(segment
		(start 38.51783 -163.429188)
		(end 37.947854 -162.859212)
		(width 0.508)
		(layer "B.Cu")
		(net "P0V975")
	)
	(segment
		(start 35.7251 -162.9664)
		(end 32.3596 -162.9664)
		(width 0.508)
		(layer "B.Cu")
		(net "P0V975")
	)
	(segment
		(start 107.5182 -16.046196)
		(end 105.463594 -18.100802)
		(width 0.508)
		(layer "B.Cu")
		(net "P0V975")
	)
	(segment
		(start 48.894746 -165.3286)
		(end 45.535088 -165.3286)
		(width 0.508)
		(layer "B.Cu")
		(net "P0V975")
	)
	(segment
		(start 43.619674 -163.429696)
		(end 43.619166 -163.429188)
		(width 0.508)
		(layer "B.Cu")
		(net "P0V975")
	)
	(segment
		(start 107.5182 -13.875766)
		(end 107.5182 -16.046196)
		(width 0.508)
		(layer "B.Cu")
		(net "P0V975")
	)
	(segment
		(start 7.8994 -116.518182)
		(end 11.133582 -113.284)
		(width 0.508)
		(layer "B.Cu")
		(net "P0V975")
	)
	(segment
		(start 32.056324 -112.088676)
		(end 54.313328 -112.088676)
		(width 0.508)
		(layer "B.Cu")
		(net "P0V975")
	)
	(segment
		(start 157.183328 -85.783928)
		(end 155.91155 -85.783928)
		(width 0.508)
		(layer "B.Cu")
		(net "P0V975")
	)
	(segment
		(start 67.1576 -115.4938)
		(end 69.4944 -115.4938)
		(width 0.508)
		(layer "B.Cu")
		(net "P0V975")
	)
	(segment
		(start 206.8322 -79.9084)
		(end 206.1464 -80.5942)
		(width 0.508)
		(layer "B.Cu")
		(net "P0V975")
	)
	(segment
		(start 51.6001 -165.8874)
		(end 49.453546 -165.8874)
		(width 0.508)
		(layer "B.Cu")
		(net "P0V975")
	)
	(segment
		(start 155.91155 -85.783928)
		(end 154.7368 -84.609178)
		(width 0.508)
		(layer "B.Cu")
		(net "P0V975")
	)
	(segment
		(start 49.453546 -165.8874)
		(end 49.377854 -165.811708)
		(width 0.508)
		(layer "B.Cu")
		(net "P0V975")
	)
	(segment
		(start 94.490286 -107.093258)
		(end 94.490286 -96.140778)
		(width 0.508)
		(layer "B.Cu")
		(net "P0V975")
	)
	(segment
		(start 32.3596 -162.9664)
		(end 30.226 -160.8328)
		(width 0.508)
		(layer "B.Cu")
		(net "P0V975")
	)
	(segment
		(start 108.712254 -6.418326)
		(end 108.712254 -12.681712)
		(width 0.508)
		(layer "B.Cu")
		(net "P0V975")
	)
	(segment
		(start 206.8703 -79.9084)
		(end 206.8322 -79.9084)
		(width 0.508)
		(layer "B.Cu")
		(net "P0V975")
	)
	(segment
		(start 37.947854 -162.845496)
		(end 37.332158 -162.2298)
		(width 0.508)
		(layer "B.Cu")
		(net "P0V975")
	)
	(segment
		(start 166.609268 -91.656408)
		(end 163.055808 -91.656408)
		(width 0.508)
		(layer "B.Cu")
		(net "P0V975")
	)
	(segment
		(start 89.55913 -112.024414)
		(end 94.490286 -107.093258)
		(width 0.508)
		(layer "B.Cu")
		(net "P0V975")
	)
	(segment
		(start 69.4944 -115.4938)
		(end 71.2216 -113.7666)
		(width 0.508)
		(layer "B.Cu")
		(net "P0V975")
	)
	(segment
		(start 223.811338 -100.207318)
		(end 220.91142 -97.3074)
		(width 0.508)
		(layer "B.Cu")
		(net "P0V975")
	)
	(segment
		(start 43.636184 -163.429696)
		(end 43.619674 -163.429696)
		(width 0.508)
		(layer "B.Cu")
		(net "P0V975")
	)
	(segment
		(start 43.619166 -163.429188)
		(end 38.51783 -163.429188)
		(width 0.508)
		(layer "B.Cu")
		(net "P0V975")
	)
	(segment
		(start 54.708552 -112.4839)
		(end 57.31256 -112.4839)
		(width 0.508)
		(layer "B.Cu")
		(net "P0V975")
	)
	(segment
		(start 45.535088 -165.3286)
		(end 43.636184 -163.429696)
		(width 0.508)
		(layer "B.Cu")
		(net "P0V975")
	)
	(segment
		(start 94.490286 -96.140778)
		(end 94.612714 -96.01835)
		(width 0.508)
		(layer "B.Cu")
		(net "P0V975")
	)
	(segment
		(start 60.98286 -116.1542)
		(end 66.4972 -116.1542)
		(width 0.508)
		(layer "B.Cu")
		(net "P0V975")
	)
	(segment
		(start 154.7368 -84.609178)
		(end 154.7368 -83.9216)
		(width 0.508)
		(layer "B.Cu")
		(net "P0V975")
	)
	(segment
		(start 57.31256 -112.4839)
		(end 60.98286 -116.1542)
		(width 0.508)
		(layer "B.Cu")
		(net "P0V975")
	)
	(segment
		(start 36.4617 -162.2298)
		(end 35.7251 -162.9664)
		(width 0.508)
		(layer "B.Cu")
		(net "P0V975")
	)
	(segment
		(start 54.313328 -112.088676)
		(end 54.708552 -112.4839)
		(width 0.508)
		(layer "B.Cu")
		(net "P0V975")
	)
	(segment
		(start 48.931576 -165.36543)
		(end 48.894746 -165.3286)
		(width 0.508)
		(layer "B.Cu")
		(net "P0V975")
	)
	(segment
		(start 30.861 -113.284)
		(end 32.056324 -112.088676)
		(width 0.508)
		(layer "B.Cu")
		(net "P0V975")
	)
	(segment
		(start 163.055808 -91.656408)
		(end 157.183328 -85.783928)
		(width 0.508)
		(layer "B.Cu")
		(net "P0V975")
	)
	(segment
		(start 71.2216 -113.7666)
		(end 74.945494 -113.7666)
		(width 0.508)
		(layer "B.Cu")
		(net "P0V975")
	)
	(segment
		(start 204.2922 -110.871)
		(end 201.726546 -113.436654)
		(width 0.508)
		(layer "In2.Cu")
		(net "P0V975")
	)
	(segment
		(start 150.4188 -44.37888)
		(end 152.583642 -46.543722)
		(width 0.508)
		(layer "In2.Cu")
		(net "P0V975")
	)
	(segment
		(start 152.583642 -46.543722)
		(end 152.583642 -81.768442)
		(width 0.508)
		(layer "In2.Cu")
		(net "P0V975")
	)
	(segment
		(start 201.726546 -113.436654)
		(end 201.726546 -118.821454)
		(width 0.508)
		(layer "In2.Cu")
		(net "P0V975")
	)
	(segment
		(start 150.4188 -23.7871)
		(end 150.4188 -44.37888)
		(width 0.508)
		(layer "In2.Cu")
		(net "P0V975")
	)
	(segment
		(start 147.7137 -21.082)
		(end 150.4188 -23.7871)
		(width 0.508)
		(layer "In2.Cu")
		(net "P0V975")
	)
	(segment
		(start 201.726546 -118.821454)
		(end 192.8368 -127.7112)
		(width 0.508)
		(layer "In2.Cu")
		(net "P0V975")
	)
	(segment
		(start 147.4724 -9.72566)
		(end 147.4724 -18.547588)
		(width 0.508)
		(layer "In2.Cu")
		(net "P0V975")
	)
	(segment
		(start 151.508206 -3.58394)
		(end 151.508206 -5.689854)
		(width 0.508)
		(layer "In2.Cu")
		(net "P0V975")
	)
	(segment
		(start 151.508206 -5.689854)
		(end 147.4724 -9.72566)
		(width 0.508)
		(layer "In2.Cu")
		(net "P0V975")
	)
	(segment
		(start 147.7137 -18.788888)
		(end 147.7137 -21.082)
		(width 0.508)
		(layer "In2.Cu")
		(net "P0V975")
	)
	(segment
		(start 147.4724 -18.547588)
		(end 147.7137 -18.788888)
		(width 0.508)
		(layer "In2.Cu")
		(net "P0V975")
	)
	(segment
		(start 152.583642 -81.768442)
		(end 154.7368 -83.9216)
		(width 0.508)
		(layer "In2.Cu")
		(net "P0V975")
	)
	(segment
		(start 192.8368 -127.7112)
		(end 192.8368 -129.032)
		(width 0.508)
		(layer "In2.Cu")
		(net "P0V975")
	)
	(segment
		(start 6.496304 -147.377404)
		(end 19.4183 -160.2994)
		(width 0.508)
		(layer "In5.Cu")
		(net "P0V975")
	)
	(segment
		(start 151.508206 -3.58394)
		(end 134.8359 -3.58394)
		(width 0.508)
		(layer "In5.Cu")
		(net "P0V975")
	)
	(segment
		(start 134.8359 -3.58394)
		(end 133.66496 -4.75488)
		(width 0.508)
		(layer "In5.Cu")
		(net "P0V975")
	)
	(segment
		(start 6.496304 -117.921278)
		(end 6.496304 -147.377404)
		(width 0.508)
		(layer "In5.Cu")
		(net "P0V975")
	)
	(segment
		(start 94.14764 -95.553276)
		(end 94.612714 -96.01835)
		(width 0.508)
		(layer "In5.Cu")
		(net "P0V975")
	)
	(segment
		(start 27.023822 -160.3248)
		(end 29.718 -160.3248)
		(width 0.508)
		(layer "In5.Cu")
		(net "P0V975")
	)
	(segment
		(start 133.66496 -4.75488)
		(end 129.71145 -4.75488)
		(width 0.508)
		(layer "In5.Cu")
		(net "P0V975")
	)
	(segment
		(start 97.32518 -83.770978)
		(end 94.14764 -86.948518)
		(width 0.508)
		(layer "In5.Cu")
		(net "P0V975")
	)
	(segment
		(start 26.998422 -160.2994)
		(end 27.023822 -160.3248)
		(width 0.508)
		(layer "In5.Cu")
		(net "P0V975")
	)
	(segment
		(start 129.044192 -4.087622)
		(end 110.04042 -4.087622)
		(width 0.508)
		(layer "In5.Cu")
		(net "P0V975")
	)
	(segment
		(start 7.8994 -116.518182)
		(end 6.496304 -117.921278)
		(width 0.508)
		(layer "In5.Cu")
		(net "P0V975")
	)
	(segment
		(start 108.712254 -5.415788)
		(end 108.712254 -6.418326)
		(width 0.508)
		(layer "In5.Cu")
		(net "P0V975")
	)
	(segment
		(start 110.04042 -4.087622)
		(end 108.712254 -5.415788)
		(width 0.508)
		(layer "In5.Cu")
		(net "P0V975")
	)
	(segment
		(start 29.718 -160.3248)
		(end 30.226 -160.8328)
		(width 0.508)
		(layer "In5.Cu")
		(net "P0V975")
	)
	(segment
		(start 94.14764 -86.948518)
		(end 94.14764 -95.553276)
		(width 0.508)
		(layer "In5.Cu")
		(net "P0V975")
	)
	(segment
		(start 129.71145 -4.75488)
		(end 129.044192 -4.087622)
		(width 0.508)
		(layer "In5.Cu")
		(net "P0V975")
	)
	(segment
		(start 19.4183 -160.2994)
		(end 26.998422 -160.2994)
		(width 0.508)
		(layer "In5.Cu")
		(net "P0V975")
	)
	(segment
		(start 35.789108 -132.346192)
		(end 34.293048 -132.346192)
		(width 0.127)
		(layer "F.Cu")
		(net "OSC_OUT")
	)
	(segment
		(start 36.0934 -132.0419)
		(end 35.789108 -132.346192)
		(width 0.127)
		(layer "F.Cu")
		(net "OSC_OUT")
	)
	(segment
		(start 33.279334 -131.399534)
		(end 32.576008 -130.696208)
		(width 0.127)
		(layer "F.Cu")
		(net "OSC_OE")
	)
	(segment
		(start 36.068 -130.9497)
		(end 35.618166 -131.399534)
		(width 0.127)
		(layer "F.Cu")
		(net "OSC_OE")
	)
	(segment
		(start 32.576008 -130.696208)
		(end 31.950152 -130.696208)
		(width 0.127)
		(layer "F.Cu")
		(net "OSC_OE")
	)
	(segment
		(start 35.618166 -131.399534)
		(end 33.279334 -131.399534)
		(width 0.127)
		(layer "F.Cu")
		(net "OSC_OE")
	)
	(segment
		(start 41.699942 -145.400014)
		(end 41.299892 -144.999964)
		(width 0.127)
		(layer "F.Cu")
		(net "MIOZ")
	)
	(via
		(at 41.299892 -144.999964)
		(size 0.4572)
		(drill 0.2032)
		(layers "F.Cu" "B.Cu")
		(net "MIOZ")
	)
	(via
		(at 39.751254 -144.26311)
		(size 0.6096)
		(drill 0.3048)
		(layers "F.Cu" "B.Cu")
		(net "MIOZ")
	)
	(segment
		(start 40.901874 -144.601946)
		(end 41.299892 -144.999964)
		(width 0.127)
		(layer "B.Cu")
		(net "MIOZ")
	)
	(segment
		(start 40.09009 -144.601946)
		(end 40.901874 -144.601946)
		(width 0.127)
		(layer "B.Cu")
		(net "MIOZ")
	)
	(segment
		(start 39.751254 -144.26311)
		(end 40.09009 -144.601946)
		(width 0.127)
		(layer "B.Cu")
		(net "MIOZ")
	)
	(segment
		(start 39.751254 -143.336518)
		(end 39.751254 -144.26311)
		(width 0.127)
		(layer "B.Cu")
		(net "MIOZ")
	)
	(via
		(at 18.8976 -141.4018)
		(size 0.6096)
		(drill 0.3048)
		(layers "F.Cu" "B.Cu")
		(net "MEMCK_TER")
	)
	(segment
		(start 19.870674 -141.894814)
		(end 19.932396 -141.833092)
		(width 0.508)
		(layer "B.Cu")
		(net "MEMCK_TER")
	)
	(segment
		(start 19.328892 -141.833092)
		(end 19.932396 -141.833092)
		(width 0.508)
		(layer "B.Cu")
		(net "MEMCK_TER")
	)
	(segment
		(start 19.491198 -140.808202)
		(end 18.8976 -141.4018)
		(width 0.508)
		(layer "B.Cu")
		(net "MEMCK_TER")
	)
	(segment
		(start 19.93265 -140.808202)
		(end 19.491198 -140.808202)
		(width 0.508)
		(layer "B.Cu")
		(net "MEMCK_TER")
	)
	(segment
		(start 19.870674 -142.862046)
		(end 19.870674 -141.894814)
		(width 0.508)
		(layer "B.Cu")
		(net "MEMCK_TER")
	)
	(segment
		(start 18.8976 -141.4018)
		(end 19.328892 -141.833092)
		(width 0.508)
		(layer "B.Cu")
		(net "MEMCK_TER")
	)
	(segment
		(start 16.964406 -139.406122)
		(end 15.470886 -139.406122)
		(width 0.127)
		(layer "F.Cu")
		(net "MEMBG_0")
	)
	(segment
		(start 14.08176 -138.9888)
		(end 13.95476 -138.8618)
		(width 0.127)
		(layer "F.Cu")
		(net "MEMBG_0")
	)
	(segment
		(start 14.46276 -140.365734)
		(end 14.20876 -140.365734)
		(width 0.127)
		(layer "F.Cu")
		(net "MEMBG_0")
	)
	(segment
		(start 15.183358 -139.118594)
		(end 14.734286 -139.118594)
		(width 0.127)
		(layer "F.Cu")
		(net "MEMBG_0")
	)
	(segment
		(start 13.95476 -138.8618)
		(end 10.5283 -138.8618)
		(width 0.127)
		(layer "F.Cu")
		(net "MEMBG_0")
	)
	(segment
		(start 10.5283 -138.8618)
		(end 10.2997 -139.0904)
		(width 0.127)
		(layer "F.Cu")
		(net "MEMBG_0")
	)
	(segment
		(start 17.634712 -139.761468)
		(end 18.034508 -139.361672)
		(width 0.127)
		(layer "F.Cu")
		(net "MEMBG_0")
	)
	(segment
		(start 17.634458 -139.761468)
		(end 17.634712 -139.761468)
		(width 0.127)
		(layer "F.Cu")
		(net "MEMBG_0")
	)
	(segment
		(start 17.634458 -139.761468)
		(end 17.319752 -139.761468)
		(width 0.127)
		(layer "F.Cu")
		(net "MEMBG_0")
	)
	(segment
		(start 10.2997 -139.0904)
		(end 10.2997 -139.573)
		(width 0.127)
		(layer "F.Cu")
		(net "MEMBG_0")
	)
	(segment
		(start 14.20876 -140.365734)
		(end 14.08176 -140.238734)
		(width 0.127)
		(layer "F.Cu")
		(net "MEMBG_0")
	)
	(segment
		(start 41.699434 -143.800068)
		(end 41.699942 -143.800068)
		(width 0.127)
		(layer "F.Cu")
		(net "MEMBG_0")
	)
	(segment
		(start 9.2837 -139.573)
		(end 10.2997 -139.573)
		(width 0.127)
		(layer "F.Cu")
		(net "MEMBG_0")
	)
	(segment
		(start 14.08176 -140.238734)
		(end 14.08176 -138.9888)
		(width 0.127)
		(layer "F.Cu")
		(net "MEMBG_0")
	)
	(segment
		(start 15.470886 -139.406122)
		(end 15.183358 -139.118594)
		(width 0.127)
		(layer "F.Cu")
		(net "MEMBG_0")
	)
	(segment
		(start 17.319752 -139.761468)
		(end 16.964406 -139.406122)
		(width 0.127)
		(layer "F.Cu")
		(net "MEMBG_0")
	)
	(segment
		(start 14.58976 -140.238734)
		(end 14.46276 -140.365734)
		(width 0.127)
		(layer "F.Cu")
		(net "MEMBG_0")
	)
	(segment
		(start 41.29913 -143.400018)
		(end 41.299384 -143.400018)
		(width 0.127)
		(layer "F.Cu")
		(net "MEMBG_0")
	)
	(segment
		(start 14.734286 -139.118594)
		(end 14.58976 -139.26312)
		(width 0.127)
		(layer "F.Cu")
		(net "MEMBG_0")
	)
	(segment
		(start 14.58976 -139.26312)
		(end 14.58976 -140.238734)
		(width 0.127)
		(layer "F.Cu")
		(net "MEMBG_0")
	)
	(segment
		(start 41.299384 -143.400018)
		(end 41.699434 -143.800068)
		(width 0.127)
		(layer "F.Cu")
		(net "MEMBG_0")
	)
	(via
		(at 18.034508 -139.361672)
		(size 0.508)
		(drill 0.254)
		(layers "F.Cu" "B.Cu")
		(net "MEMBG_0")
	)
	(via
		(at 41.29913 -143.400018)
		(size 0.4572)
		(drill 0.2032)
		(layers "F.Cu" "B.Cu")
		(net "MEMBG_0")
	)
	(segment
		(start 21.068538 -139.761468)
		(end 21.00453 -139.825476)
		(width 0.0889)
		(layer "In5.Cu")
		(net "MEMBG_0")
	)
	(segment
		(start 19.241008 -139.58316)
		(end 18.877026 -139.58316)
		(width 0.0889)
		(layer "In5.Cu")
		(net "MEMBG_0")
	)
	(segment
		(start 21.00453 -139.825476)
		(end 20.727924 -139.825476)
		(width 0.0889)
		(layer "In5.Cu")
		(net "MEMBG_0")
	)
	(segment
		(start 39.400226 -143.298164)
		(end 37.971476 -141.869414)
		(width 0.127)
		(layer "In5.Cu")
		(net "MEMBG_0")
	)
	(segment
		(start 20.639024 -139.914376)
		(end 20.639024 -140.221716)
		(width 0.0889)
		(layer "In5.Cu")
		(net "MEMBG_0")
	)
	(segment
		(start 19.572224 -140.221716)
		(end 19.572224 -139.914376)
		(width 0.0889)
		(layer "In5.Cu")
		(net "MEMBG_0")
	)
	(segment
		(start 31.732982 -142.06982)
		(end 29.97708 -142.06982)
		(width 0.127)
		(layer "In5.Cu")
		(net "MEMBG_0")
	)
	(segment
		(start 20.372324 -140.310616)
		(end 20.283424 -140.221716)
		(width 0.0889)
		(layer "In5.Cu")
		(net "MEMBG_0")
	)
	(segment
		(start 17.46377 -139.361672)
		(end 18.034508 -139.361672)
		(width 0.0889)
		(layer "In5.Cu")
		(net "MEMBG_0")
	)
	(segment
		(start 19.927824 -140.221716)
		(end 19.838924 -140.310616)
		(width 0.0889)
		(layer "In5.Cu")
		(net "MEMBG_0")
	)
	(segment
		(start 21.368004 -139.462764)
		(end 21.148548 -139.68222)
		(width 0.127)
		(layer "In5.Cu")
		(net "MEMBG_0")
	)
	(segment
		(start 21.148548 -139.68222)
		(end 21.0693 -139.761468)
		(width 0.0889)
		(layer "In5.Cu")
		(net "MEMBG_0")
	)
	(segment
		(start 18.156428 -140.303758)
		(end 17.514316 -140.303758)
		(width 0.0889)
		(layer "In5.Cu")
		(net "MEMBG_0")
	)
	(segment
		(start 17.278604 -140.068046)
		(end 17.278604 -139.546838)
		(width 0.0889)
		(layer "In5.Cu")
		(net "MEMBG_0")
	)
	(segment
		(start 19.572224 -139.914376)
		(end 19.241008 -139.58316)
		(width 0.0889)
		(layer "In5.Cu")
		(net "MEMBG_0")
	)
	(segment
		(start 17.278604 -139.546838)
		(end 17.46377 -139.361672)
		(width 0.0889)
		(layer "In5.Cu")
		(net "MEMBG_0")
	)
	(segment
		(start 20.194524 -139.825476)
		(end 20.016724 -139.825476)
		(width 0.0889)
		(layer "In5.Cu")
		(net "MEMBG_0")
	)
	(segment
		(start 21.0693 -139.761468)
		(end 21.068538 -139.761468)
		(width 0.0889)
		(layer "In5.Cu")
		(net "MEMBG_0")
	)
	(segment
		(start 19.927824 -139.914376)
		(end 19.927824 -140.221716)
		(width 0.0889)
		(layer "In5.Cu")
		(net "MEMBG_0")
	)
	(segment
		(start 20.639024 -140.221716)
		(end 20.550124 -140.310616)
		(width 0.0889)
		(layer "In5.Cu")
		(net "MEMBG_0")
	)
	(segment
		(start 29.97708 -142.06982)
		(end 27.4955 -139.58824)
		(width 0.127)
		(layer "In5.Cu")
		(net "MEMBG_0")
	)
	(segment
		(start 37.971476 -141.869414)
		(end 31.933388 -141.869414)
		(width 0.127)
		(layer "In5.Cu")
		(net "MEMBG_0")
	)
	(segment
		(start 20.283424 -140.221716)
		(end 20.283424 -139.914376)
		(width 0.0889)
		(layer "In5.Cu")
		(net "MEMBG_0")
	)
	(segment
		(start 40.926766 -143.298164)
		(end 39.400226 -143.298164)
		(width 0.127)
		(layer "In5.Cu")
		(net "MEMBG_0")
	)
	(segment
		(start 27.4955 -139.58824)
		(end 24.551894 -139.58824)
		(width 0.127)
		(layer "In5.Cu")
		(net "MEMBG_0")
	)
	(segment
		(start 20.550124 -140.310616)
		(end 20.372324 -140.310616)
		(width 0.0889)
		(layer "In5.Cu")
		(net "MEMBG_0")
	)
	(segment
		(start 31.933388 -141.869414)
		(end 31.732982 -142.06982)
		(width 0.127)
		(layer "In5.Cu")
		(net "MEMBG_0")
	)
	(segment
		(start 19.838924 -140.310616)
		(end 19.661124 -140.310616)
		(width 0.0889)
		(layer "In5.Cu")
		(net "MEMBG_0")
	)
	(segment
		(start 24.551894 -139.58824)
		(end 24.426418 -139.462764)
		(width 0.127)
		(layer "In5.Cu")
		(net "MEMBG_0")
	)
	(segment
		(start 17.514316 -140.303758)
		(end 17.278604 -140.068046)
		(width 0.0889)
		(layer "In5.Cu")
		(net "MEMBG_0")
	)
	(segment
		(start 18.877026 -139.58316)
		(end 18.156428 -140.303758)
		(width 0.0889)
		(layer "In5.Cu")
		(net "MEMBG_0")
	)
	(segment
		(start 20.016724 -139.825476)
		(end 19.927824 -139.914376)
		(width 0.0889)
		(layer "In5.Cu")
		(net "MEMBG_0")
	)
	(segment
		(start 19.661124 -140.310616)
		(end 19.572224 -140.221716)
		(width 0.0889)
		(layer "In5.Cu")
		(net "MEMBG_0")
	)
	(segment
		(start 24.426418 -139.462764)
		(end 21.368004 -139.462764)
		(width 0.127)
		(layer "In5.Cu")
		(net "MEMBG_0")
	)
	(segment
		(start 20.283424 -139.914376)
		(end 20.194524 -139.825476)
		(width 0.0889)
		(layer "In5.Cu")
		(net "MEMBG_0")
	)
	(segment
		(start 20.727924 -139.825476)
		(end 20.639024 -139.914376)
		(width 0.0889)
		(layer "In5.Cu")
		(net "MEMBG_0")
	)
	(arc
		(start 41.088056 -143.364966)
		(mid 41.014056 -143.31552)
		(end 40.926766 -143.298164)
		(width 0.127)
		(layer "In5.Cu")
		(net "MEMBG_0")
	)
	(arc
		(start 41.29913 -143.400018)
		(mid 41.187972 -143.416344)
		(end 41.088056 -143.364966)
		(width 0.127)
		(layer "In5.Cu")
		(net "MEMBG_0")
	)
	(segment
		(start 53.299614 -150.599902)
		(end 53.699664 -150.999952)
		(width 0.127)
		(layer "F.Cu")
		(net "MAC2_TXD3")
	)
	(segment
		(start 53.699664 -150.999952)
		(end 53.699918 -150.999952)
		(width 0.127)
		(layer "F.Cu")
		(net "MAC2_TXD3")
	)
	(via
		(at 53.299614 -150.599902)
		(size 0.4572)
		(drill 0.2032)
		(layers "F.Cu" "B.Cu")
		(net "MAC2_TXD3")
	)
	(via
		(at 58.690764 -153.101802)
		(size 0.6096)
		(drill 0.3048)
		(layers "F.Cu" "B.Cu")
		(net "MAC2_TXD3")
	)
	(segment
		(start 57.643522 -153.101802)
		(end 58.690764 -153.101802)
		(width 0.127)
		(layer "B.Cu")
		(net "MAC2_TXD3")
	)
	(segment
		(start 58.690764 -153.101802)
		(end 59.157108 -153.101802)
		(width 0.127)
		(layer "B.Cu")
		(net "MAC2_TXD3")
	)
	(segment
		(start 59.31027 -152.94864)
		(end 59.78144 -152.94864)
		(width 0.127)
		(layer "B.Cu")
		(net "MAC2_TXD3")
	)
	(segment
		(start 59.78144 -153.433526)
		(end 59.769248 -153.445718)
		(width 0.127)
		(layer "B.Cu")
		(net "MAC2_TXD3")
	)
	(segment
		(start 59.157108 -153.101802)
		(end 59.31027 -152.94864)
		(width 0.127)
		(layer "B.Cu")
		(net "MAC2_TXD3")
	)
	(segment
		(start 53.556408 -150.627588)
		(end 54.520084 -151.591264)
		(width 0.127)
		(layer "B.Cu")
		(net "MAC2_TXD3")
	)
	(segment
		(start 56.373014 -152.1333)
		(end 56.67502 -152.1333)
		(width 0.127)
		(layer "B.Cu")
		(net "MAC2_TXD3")
	)
	(segment
		(start 55.830978 -151.591264)
		(end 56.373014 -152.1333)
		(width 0.127)
		(layer "B.Cu")
		(net "MAC2_TXD3")
	)
	(segment
		(start 56.67502 -152.1333)
		(end 57.643522 -153.101802)
		(width 0.127)
		(layer "B.Cu")
		(net "MAC2_TXD3")
	)
	(segment
		(start 59.769248 -153.445718)
		(end 59.769248 -154.031188)
		(width 0.127)
		(layer "B.Cu")
		(net "MAC2_TXD3")
	)
	(segment
		(start 53.3273 -150.627588)
		(end 53.556408 -150.627588)
		(width 0.127)
		(layer "B.Cu")
		(net "MAC2_TXD3")
	)
	(segment
		(start 53.299614 -150.599902)
		(end 53.3273 -150.627588)
		(width 0.127)
		(layer "B.Cu")
		(net "MAC2_TXD3")
	)
	(segment
		(start 54.520084 -151.591264)
		(end 55.830978 -151.591264)
		(width 0.127)
		(layer "B.Cu")
		(net "MAC2_TXD3")
	)
	(segment
		(start 59.78144 -152.94864)
		(end 59.78144 -153.433526)
		(width 0.127)
		(layer "B.Cu")
		(net "MAC2_TXD3")
	)
	(segment
		(start 54.099968 -149.800056)
		(end 53.700172 -150.199852)
		(width 0.127)
		(layer "F.Cu")
		(net "MAC2_TXD2")
	)
	(segment
		(start 53.700172 -150.199852)
		(end 53.699918 -150.199852)
		(width 0.127)
		(layer "F.Cu")
		(net "MAC2_TXD2")
	)
	(via
		(at 59.8678 -150.6982)
		(size 0.6096)
		(drill 0.3048)
		(layers "F.Cu" "B.Cu")
		(net "MAC2_TXD2")
	)
	(via
		(at 54.099968 -149.800056)
		(size 0.4572)
		(drill 0.2032)
		(layers "F.Cu" "B.Cu")
		(net "MAC2_TXD2")
	)
	(segment
		(start 61.468 -150.9395)
		(end 62.56401 -150.9395)
		(width 0.127)
		(layer "B.Cu")
		(net "MAC2_TXD2")
	)
	(segment
		(start 55.038244 -150.495)
		(end 56.0578 -150.495)
		(width 0.127)
		(layer "B.Cu")
		(net "MAC2_TXD2")
	)
	(segment
		(start 56.3245 -150.2283)
		(end 59.3979 -150.2283)
		(width 0.127)
		(layer "B.Cu")
		(net "MAC2_TXD2")
	)
	(segment
		(start 56.0578 -150.495)
		(end 56.3245 -150.2283)
		(width 0.127)
		(layer "B.Cu")
		(net "MAC2_TXD2")
	)
	(segment
		(start 60.1091 -150.9395)
		(end 61.468 -150.9395)
		(width 0.127)
		(layer "B.Cu")
		(net "MAC2_TXD2")
	)
	(segment
		(start 59.3979 -150.2283)
		(end 59.8678 -150.6982)
		(width 0.127)
		(layer "B.Cu")
		(net "MAC2_TXD2")
	)
	(segment
		(start 54.3433 -149.800056)
		(end 55.038244 -150.495)
		(width 0.127)
		(layer "B.Cu")
		(net "MAC2_TXD2")
	)
	(segment
		(start 54.099968 -149.800056)
		(end 54.3433 -149.800056)
		(width 0.127)
		(layer "B.Cu")
		(net "MAC2_TXD2")
	)
	(segment
		(start 59.8678 -150.6982)
		(end 60.1091 -150.9395)
		(width 0.127)
		(layer "B.Cu")
		(net "MAC2_TXD2")
	)
	(segment
		(start 60.5155 -160.8328)
		(end 61.03747 -160.31083)
		(width 0.127)
		(layer "F.Cu")
		(net "MAC2_TXD1")
	)
	(segment
		(start 58.489342 -156.2862)
		(end 59.792616 -156.2862)
		(width 0.127)
		(layer "F.Cu")
		(net "MAC2_TXD1")
	)
	(segment
		(start 61.03747 -158.76397)
		(end 60.452 -158.1785)
		(width 0.127)
		(layer "F.Cu")
		(net "MAC2_TXD1")
	)
	(segment
		(start 55.73141 -152.231598)
		(end 56.252618 -152.231598)
		(width 0.127)
		(layer "F.Cu")
		(net "MAC2_TXD1")
	)
	(segment
		(start 56.52262 -152.5016)
		(end 56.52262 -152.883108)
		(width 0.127)
		(layer "F.Cu")
		(net "MAC2_TXD1")
	)
	(segment
		(start 57.267856 -153.628344)
		(end 57.267856 -155.064714)
		(width 0.127)
		(layer "F.Cu")
		(net "MAC2_TXD1")
	)
	(segment
		(start 56.52262 -152.883108)
		(end 57.267856 -153.628344)
		(width 0.127)
		(layer "F.Cu")
		(net "MAC2_TXD1")
	)
	(segment
		(start 56.252618 -152.231598)
		(end 56.52262 -152.5016)
		(width 0.127)
		(layer "F.Cu")
		(net "MAC2_TXD1")
	)
	(segment
		(start 60.452 -158.1785)
		(end 60.452 -156.945584)
		(width 0.127)
		(layer "F.Cu")
		(net "MAC2_TXD1")
	)
	(segment
		(start 59.792616 -156.2862)
		(end 60.452 -156.945584)
		(width 0.127)
		(layer "F.Cu")
		(net "MAC2_TXD1")
	)
	(segment
		(start 55.299864 -151.800052)
		(end 55.73141 -152.231598)
		(width 0.127)
		(layer "F.Cu")
		(net "MAC2_TXD1")
	)
	(segment
		(start 61.03747 -160.31083)
		(end 61.03747 -158.76397)
		(width 0.127)
		(layer "F.Cu")
		(net "MAC2_TXD1")
	)
	(segment
		(start 57.267856 -155.064714)
		(end 58.489342 -156.2862)
		(width 0.127)
		(layer "F.Cu")
		(net "MAC2_TXD1")
	)
	(via
		(at 60.452 -156.945584)
		(size 0.6604)
		(drill 0.3302)
		(layers "F.Cu" "B.Cu")
		(net "MAC2_TXD1")
	)
	(segment
		(start 58.8772 -158.7373)
		(end 58.3946 -158.7373)
		(width 0.127)
		(layer "F.Cu")
		(net "MAC2_TXD0")
	)
	(segment
		(start 56.29402 -152.97785)
		(end 56.9468 -153.63063)
		(width 0.127)
		(layer "F.Cu")
		(net "MAC2_TXD0")
	)
	(segment
		(start 59.436 -158.1785)
		(end 58.8772 -158.7373)
		(width 0.127)
		(layer "F.Cu")
		(net "MAC2_TXD0")
	)
	(segment
		(start 59.436 -157.226)
		(end 59.436 -158.1785)
		(width 0.127)
		(layer "F.Cu")
		(net "MAC2_TXD0")
	)
	(segment
		(start 56.9468 -155.067)
		(end 58.607198 -156.727398)
		(width 0.127)
		(layer "F.Cu")
		(net "MAC2_TXD0")
	)
	(segment
		(start 58.607198 -156.727398)
		(end 58.937398 -156.727398)
		(width 0.127)
		(layer "F.Cu")
		(net "MAC2_TXD0")
	)
	(segment
		(start 56.9468 -153.63063)
		(end 56.9468 -155.067)
		(width 0.127)
		(layer "F.Cu")
		(net "MAC2_TXD0")
	)
	(segment
		(start 56.29402 -152.793954)
		(end 56.29402 -152.97785)
		(width 0.127)
		(layer "F.Cu")
		(net "MAC2_TXD0")
	)
	(segment
		(start 56.099964 -152.599898)
		(end 56.29402 -152.793954)
		(width 0.127)
		(layer "F.Cu")
		(net "MAC2_TXD0")
	)
	(segment
		(start 59.2582 -157.0482)
		(end 59.436 -157.226)
		(width 0.127)
		(layer "F.Cu")
		(net "MAC2_TXD0")
	)
	(segment
		(start 58.937398 -156.727398)
		(end 59.2582 -157.0482)
		(width 0.127)
		(layer "F.Cu")
		(net "MAC2_TXD0")
	)
	(via
		(at 59.2582 -157.0482)
		(size 0.6604)
		(drill 0.3302)
		(layers "F.Cu" "B.Cu")
		(net "MAC2_TXD0")
	)
	(segment
		(start 55.299864 -153.399998)
		(end 55.299864 -154.9654)
		(width 0.127)
		(layer "F.Cu")
		(net "MAC2_TXCTL")
	)
	(segment
		(start 56.846978 -157.922722)
		(end 56.3626 -158.4071)
		(width 0.127)
		(layer "F.Cu")
		(net "MAC2_TXCTL")
	)
	(segment
		(start 56.846978 -157.413198)
		(end 56.846978 -157.922722)
		(width 0.127)
		(layer "F.Cu")
		(net "MAC2_TXCTL")
	)
	(segment
		(start 55.299864 -154.9654)
		(end 55.8546 -155.520136)
		(width 0.127)
		(layer "F.Cu")
		(net "MAC2_TXCTL")
	)
	(segment
		(start 55.8546 -156.42082)
		(end 56.035956 -156.602176)
		(width 0.127)
		(layer "F.Cu")
		(net "MAC2_TXCTL")
	)
	(segment
		(start 55.8546 -155.520136)
		(end 55.8546 -156.42082)
		(width 0.127)
		(layer "F.Cu")
		(net "MAC2_TXCTL")
	)
	(segment
		(start 56.3626 -158.4071)
		(end 57.3786 -158.4071)
		(width 0.127)
		(layer "F.Cu")
		(net "MAC2_TXCTL")
	)
	(segment
		(start 56.035956 -156.602176)
		(end 56.846978 -157.413198)
		(width 0.127)
		(layer "F.Cu")
		(net "MAC2_TXCTL")
	)
	(via
		(at 56.035956 -156.602176)
		(size 0.6604)
		(drill 0.3302)
		(layers "F.Cu" "B.Cu")
		(net "MAC2_TXCTL")
	)
	(segment
		(start 53.299868 -148.999702)
		(end 53.300122 -148.999702)
		(width 0.127)
		(layer "F.Cu")
		(net "MAC1_TXD3")
	)
	(segment
		(start 53.300122 -148.999702)
		(end 53.699918 -148.599906)
		(width 0.127)
		(layer "F.Cu")
		(net "MAC1_TXD3")
	)
	(via
		(at 59.064144 -149.371812)
		(size 0.6096)
		(drill 0.3048)
		(layers "F.Cu" "B.Cu")
		(net "MAC1_TXD3")
	)
	(via
		(at 53.299868 -148.999702)
		(size 0.4572)
		(drill 0.2032)
		(layers "F.Cu" "B.Cu")
		(net "MAC1_TXD3")
	)
	(segment
		(start 55.542688 -149.8854)
		(end 55.063136 -149.405848)
		(width 0.127)
		(layer "B.Cu")
		(net "MAC1_TXD3")
	)
	(segment
		(start 55.063136 -149.405848)
		(end 53.706014 -149.405848)
		(width 0.127)
		(layer "B.Cu")
		(net "MAC1_TXD3")
	)
	(segment
		(start 60.4774 -148.9583)
		(end 59.477656 -148.9583)
		(width 0.127)
		(layer "B.Cu")
		(net "MAC1_TXD3")
	)
	(segment
		(start 53.706014 -149.405848)
		(end 53.299868 -148.999702)
		(width 0.127)
		(layer "B.Cu")
		(net "MAC1_TXD3")
	)
	(segment
		(start 59.064144 -149.371812)
		(end 58.550556 -149.8854)
		(width 0.127)
		(layer "B.Cu")
		(net "MAC1_TXD3")
	)
	(segment
		(start 59.477656 -148.9583)
		(end 59.064144 -149.371812)
		(width 0.127)
		(layer "B.Cu")
		(net "MAC1_TXD3")
	)
	(segment
		(start 58.550556 -149.8854)
		(end 55.542688 -149.8854)
		(width 0.127)
		(layer "B.Cu")
		(net "MAC1_TXD3")
	)
	(segment
		(start 61.4934 -148.9583)
		(end 60.4774 -148.9583)
		(width 0.127)
		(layer "B.Cu")
		(net "MAC1_TXD3")
	)
	(segment
		(start 52.899818 -148.599906)
		(end 52.499768 -148.999956)
		(width 0.127)
		(layer "F.Cu")
		(net "MAC1_TXD2")
	)
	(via
		(at 54.741826 -151.095964)
		(size 0.6096)
		(drill 0.3048)
		(layers "F.Cu" "B.Cu")
		(net "MAC1_TXD2")
	)
	(via
		(at 52.499768 -148.999956)
		(size 0.4572)
		(drill 0.2032)
		(layers "F.Cu" "B.Cu")
		(net "MAC1_TXD2")
	)
	(segment
		(start 52.899818 -149.565106)
		(end 52.899818 -149.956774)
		(width 0.127)
		(layer "B.Cu")
		(net "MAC1_TXD2")
	)
	(segment
		(start 52.899818 -149.956774)
		(end 53.148992 -150.205948)
		(width 0.127)
		(layer "B.Cu")
		(net "MAC1_TXD2")
	)
	(segment
		(start 53.148992 -150.205948)
		(end 54.263544 -150.205948)
		(width 0.127)
		(layer "B.Cu")
		(net "MAC1_TXD2")
	)
	(segment
		(start 54.741826 -151.095964)
		(end 54.902862 -151.257)
		(width 0.127)
		(layer "B.Cu")
		(net "MAC1_TXD2")
	)
	(segment
		(start 54.548278 -150.490682)
		(end 54.548278 -150.902416)
		(width 0.127)
		(layer "B.Cu")
		(net "MAC1_TXD2")
	)
	(segment
		(start 52.499768 -148.999956)
		(end 52.499768 -149.165056)
		(width 0.127)
		(layer "B.Cu")
		(net "MAC1_TXD2")
	)
	(segment
		(start 56.6801 -151.6888)
		(end 56.6801 -150.6728)
		(width 0.127)
		(layer "B.Cu")
		(net "MAC1_TXD2")
	)
	(segment
		(start 54.263544 -150.205948)
		(end 54.548278 -150.490682)
		(width 0.127)
		(layer "B.Cu")
		(net "MAC1_TXD2")
	)
	(segment
		(start 54.902862 -151.257)
		(end 56.0959 -151.257)
		(width 0.127)
		(layer "B.Cu")
		(net "MAC1_TXD2")
	)
	(segment
		(start 54.548278 -150.902416)
		(end 54.741826 -151.095964)
		(width 0.127)
		(layer "B.Cu")
		(net "MAC1_TXD2")
	)
	(segment
		(start 52.499768 -149.165056)
		(end 52.899818 -149.565106)
		(width 0.127)
		(layer "B.Cu")
		(net "MAC1_TXD2")
	)
	(segment
		(start 56.0959 -151.257)
		(end 56.6801 -150.6728)
		(width 0.127)
		(layer "B.Cu")
		(net "MAC1_TXD2")
	)
	(segment
		(start 45.299884 -138.60018)
		(end 45.69968 -138.999976)
		(width 0.127)
		(layer "F.Cu")
		(net "IOM_FULL_PWR_EN_R")
	)
	(segment
		(start 45.69968 -138.999976)
		(end 45.699934 -138.999976)
		(width 0.127)
		(layer "F.Cu")
		(net "IOM_FULL_PWR_EN_R")
	)
	(via
		(at 45.299884 -138.60018)
		(size 0.4572)
		(drill 0.2032)
		(layers "F.Cu" "B.Cu")
		(net "IOM_FULL_PWR_EN_R")
	)
	(via
		(at 44.6278 -132.334)
		(size 0.6096)
		(drill 0.3048)
		(layers "F.Cu" "B.Cu")
		(net "IOM_FULL_PWR_EN_R")
	)
	(via
		(at 44.65447 -133.114542)
		(size 0.508)
		(drill 0.254)
		(layers "F.Cu" "B.Cu")
		(net "IOM_FULL_PWR_EN_R")
	)
	(segment
		(start 44.1579 -131.318)
		(end 44.6278 -131.7879)
		(width 0.127)
		(layer "B.Cu")
		(net "IOM_FULL_PWR_EN_R")
	)
	(segment
		(start 44.6278 -131.7879)
		(end 44.6278 -132.334)
		(width 0.127)
		(layer "B.Cu")
		(net "IOM_FULL_PWR_EN_R")
	)
	(segment
		(start 44.6278 -133.087872)
		(end 44.6278 -132.334)
		(width 0.127)
		(layer "B.Cu")
		(net "IOM_FULL_PWR_EN_R")
	)
	(segment
		(start 44.65447 -133.114542)
		(end 44.6278 -133.087872)
		(width 0.127)
		(layer "B.Cu")
		(net "IOM_FULL_PWR_EN_R")
	)
	(segment
		(start 45.1612 -134.3152)
		(end 44.7802 -133.9342)
		(width 0.127)
		(layer "In2.Cu")
		(net "IOM_FULL_PWR_EN_R")
	)
	(segment
		(start 44.7802 -133.9342)
		(end 44.7802 -133.240272)
		(width 0.127)
		(layer "In2.Cu")
		(net "IOM_FULL_PWR_EN_R")
	)
	(segment
		(start 44.7802 -133.240272)
		(end 44.65447 -133.114542)
		(width 0.127)
		(layer "In2.Cu")
		(net "IOM_FULL_PWR_EN_R")
	)
	(segment
		(start 45.299884 -138.60018)
		(end 45.1612 -138.461496)
		(width 0.127)
		(layer "In2.Cu")
		(net "IOM_FULL_PWR_EN_R")
	)
	(segment
		(start 45.1612 -138.461496)
		(end 45.1612 -134.3152)
		(width 0.127)
		(layer "In2.Cu")
		(net "IOM_FULL_PWR_EN_R")
	)
	(segment
		(start 94.087188 -62.302136)
		(end 94.087188 -61.159136)
		(width 0.127)
		(layer "F.Cu")
		(net "IOM_FULL_PWR_EN")
	)
	(segment
		(start 81.623154 -44.905422)
		(end 82.149188 -45.431456)
		(width 0.127)
		(layer "F.Cu")
		(net "IOM_FULL_PWR_EN")
	)
	(segment
		(start 82.149188 -45.441616)
		(end 82.189828 -45.482256)
		(width 0.127)
		(layer "F.Cu")
		(net "IOM_FULL_PWR_EN")
	)
	(segment
		(start 82.362548 -56.127396)
		(end 82.060288 -56.127396)
		(width 0.127)
		(layer "F.Cu")
		(net "IOM_FULL_PWR_EN")
	)
	(segment
		(start 75.548998 -44.905422)
		(end 75.77836 -44.67606)
		(width 0.127)
		(layer "F.Cu")
		(net "IOM_FULL_PWR_EN")
	)
	(segment
		(start 75.77836 -44.67606)
		(end 76.167996 -44.67606)
		(width 0.127)
		(layer "F.Cu")
		(net "IOM_FULL_PWR_EN")
	)
	(segment
		(start 93.351096 -59.873896)
		(end 89.109296 -59.873896)
		(width 0.127)
		(layer "F.Cu")
		(net "IOM_FULL_PWR_EN")
	)
	(segment
		(start 83.283552 -57.0484)
		(end 82.362548 -56.127396)
		(width 0.127)
		(layer "F.Cu")
		(net "IOM_FULL_PWR_EN")
	)
	(segment
		(start 94.112588 -60.635388)
		(end 93.351096 -59.873896)
		(width 0.127)
		(layer "F.Cu")
		(net "IOM_FULL_PWR_EN")
	)
	(segment
		(start 89.109296 -59.873896)
		(end 88.2396 -59.0042)
		(width 0.127)
		(layer "F.Cu")
		(net "IOM_FULL_PWR_EN")
	)
	(segment
		(start 82.060288 -56.127396)
		(end 81.864454 -55.931562)
		(width 0.127)
		(layer "F.Cu")
		(net "IOM_FULL_PWR_EN")
	)
	(segment
		(start 94.204028 -62.418976)
		(end 94.087188 -62.302136)
		(width 0.127)
		(layer "F.Cu")
		(net "IOM_FULL_PWR_EN")
	)
	(segment
		(start 76.397358 -44.905422)
		(end 81.623154 -44.905422)
		(width 0.127)
		(layer "F.Cu")
		(net "IOM_FULL_PWR_EN")
	)
	(segment
		(start 88.2396 -57.277)
		(end 88.011 -57.0484)
		(width 0.127)
		(layer "F.Cu")
		(net "IOM_FULL_PWR_EN")
	)
	(segment
		(start 88.2396 -59.0042)
		(end 88.2396 -57.277)
		(width 0.127)
		(layer "F.Cu")
		(net "IOM_FULL_PWR_EN")
	)
	(segment
		(start 75.143614 -44.905422)
		(end 75.548998 -44.905422)
		(width 0.127)
		(layer "F.Cu")
		(net "IOM_FULL_PWR_EN")
	)
	(segment
		(start 82.149188 -45.431456)
		(end 82.149188 -45.441616)
		(width 0.127)
		(layer "F.Cu")
		(net "IOM_FULL_PWR_EN")
	)
	(segment
		(start 95.152972 -56.755284)
		(end 95.152972 -61.821822)
		(width 0.127)
		(layer "F.Cu")
		(net "IOM_FULL_PWR_EN")
	)
	(segment
		(start 95.152972 -61.821822)
		(end 94.555818 -62.418976)
		(width 0.127)
		(layer "F.Cu")
		(net "IOM_FULL_PWR_EN")
	)
	(segment
		(start 88.011 -57.0484)
		(end 83.283552 -57.0484)
		(width 0.127)
		(layer "F.Cu")
		(net "IOM_FULL_PWR_EN")
	)
	(segment
		(start 94.112588 -61.133736)
		(end 94.112588 -60.635388)
		(width 0.127)
		(layer "F.Cu")
		(net "IOM_FULL_PWR_EN")
	)
	(segment
		(start 93.75013 -55.352442)
		(end 95.152972 -56.755284)
		(width 0.127)
		(layer "F.Cu")
		(net "IOM_FULL_PWR_EN")
	)
	(segment
		(start 94.555818 -62.418976)
		(end 94.204028 -62.418976)
		(width 0.127)
		(layer "F.Cu")
		(net "IOM_FULL_PWR_EN")
	)
	(segment
		(start 94.087188 -61.159136)
		(end 94.112588 -61.133736)
		(width 0.127)
		(layer "F.Cu")
		(net "IOM_FULL_PWR_EN")
	)
	(segment
		(start 81.864454 -55.931562)
		(end 81.864454 -55.882286)
		(width 0.127)
		(layer "F.Cu")
		(net "IOM_FULL_PWR_EN")
	)
	(segment
		(start 76.167996 -44.67606)
		(end 76.397358 -44.905422)
		(width 0.127)
		(layer "F.Cu")
		(net "IOM_FULL_PWR_EN")
	)
	(via
		(at 75.143614 -44.905422)
		(size 0.508)
		(drill 0.254)
		(layers "F.Cu" "B.Cu")
		(net "IOM_FULL_PWR_EN")
	)
	(via
		(at 44.9072 -125.9586)
		(size 0.6096)
		(drill 0.3048)
		(layers "F.Cu" "B.Cu")
		(net "IOM_FULL_PWR_EN")
	)
	(via
		(at 81.864454 -55.882286)
		(size 0.508)
		(drill 0.254)
		(layers "F.Cu" "B.Cu")
		(net "IOM_FULL_PWR_EN")
	)
	(via
		(at 44.9072 -125.0188)
		(size 0.508)
		(drill 0.254)
		(layers "F.Cu" "B.Cu")
		(net "IOM_FULL_PWR_EN")
	)
	(via
		(at 82.189828 -45.482256)
		(size 0.508)
		(drill 0.254)
		(layers "F.Cu" "B.Cu")
		(net "IOM_FULL_PWR_EN")
	)
	(via
		(at 43.7388 -116.8654)
		(size 0.508)
		(drill 0.254)
		(layers "F.Cu" "B.Cu")
		(net "IOM_FULL_PWR_EN")
	)
	(segment
		(start 44.9072 -125.0188)
		(end 44.9072 -125.9586)
		(width 0.127)
		(layer "B.Cu")
		(net "IOM_FULL_PWR_EN")
	)
	(segment
		(start 44.9326 -131.2037)
		(end 44.9326 -126.4158)
		(width 0.127)
		(layer "B.Cu")
		(net "IOM_FULL_PWR_EN")
	)
	(segment
		(start 44.9326 -126.4158)
		(end 44.9072 -126.3904)
		(width 0.127)
		(layer "B.Cu")
		(net "IOM_FULL_PWR_EN")
	)
	(segment
		(start 45.0469 -131.318)
		(end 44.9326 -131.2037)
		(width 0.127)
		(layer "B.Cu")
		(net "IOM_FULL_PWR_EN")
	)
	(segment
		(start 44.9072 -126.3904)
		(end 44.9072 -125.9586)
		(width 0.127)
		(layer "B.Cu")
		(net "IOM_FULL_PWR_EN")
	)
	(segment
		(start 43.9166 -120.2436)
		(end 44.2976 -119.8626)
		(width 0.127)
		(layer "In2.Cu")
		(net "IOM_FULL_PWR_EN")
	)
	(segment
		(start 44.873672 -125.029976)
		(end 44.3865 -124.542804)
		(width 0.127)
		(layer "In2.Cu")
		(net "IOM_FULL_PWR_EN")
	)
	(segment
		(start 44.2976 -117.4242)
		(end 43.7388 -116.8654)
		(width 0.127)
		(layer "In2.Cu")
		(net "IOM_FULL_PWR_EN")
	)
	(segment
		(start 44.3865 -124.542804)
		(end 44.3865 -121.925334)
		(width 0.127)
		(layer "In2.Cu")
		(net "IOM_FULL_PWR_EN")
	)
	(segment
		(start 44.896024 -125.029976)
		(end 44.873672 -125.029976)
		(width 0.127)
		(layer "In2.Cu")
		(net "IOM_FULL_PWR_EN")
	)
	(segment
		(start 44.3865 -121.925334)
		(end 43.9166 -121.455434)
		(width 0.127)
		(layer "In2.Cu")
		(net "IOM_FULL_PWR_EN")
	)
	(segment
		(start 44.2976 -119.8626)
		(end 44.2976 -117.4242)
		(width 0.127)
		(layer "In2.Cu")
		(net "IOM_FULL_PWR_EN")
	)
	(segment
		(start 43.9166 -121.455434)
		(end 43.9166 -120.2436)
		(width 0.127)
		(layer "In2.Cu")
		(net "IOM_FULL_PWR_EN")
	)
	(segment
		(start 44.9072 -125.0188)
		(end 44.896024 -125.029976)
		(width 0.127)
		(layer "In2.Cu")
		(net "IOM_FULL_PWR_EN")
	)
	(segment
		(start 82.803238 -106.70667)
		(end 82.803238 -104.012238)
		(width 0.127)
		(layer "In5.Cu")
		(net "IOM_FULL_PWR_EN")
	)
	(segment
		(start 77.232002 -108.111798)
		(end 81.39811 -108.111798)
		(width 0.127)
		(layer "In5.Cu")
		(net "IOM_FULL_PWR_EN")
	)
	(segment
		(start 82.222594 -55.524146)
		(end 82.222594 -45.515022)
		(width 0.127)
		(layer "In5.Cu")
		(net "IOM_FULL_PWR_EN")
	)
	(segment
		(start 43.7388 -116.8654)
		(end 46.710854 -113.893346)
		(width 0.127)
		(layer "In5.Cu")
		(net "IOM_FULL_PWR_EN")
	)
	(segment
		(start 77.01153 -102.397052)
		(end 74.620628 -100.00615)
		(width 0.127)
		(layer "In5.Cu")
		(net "IOM_FULL_PWR_EN")
	)
	(segment
		(start 63.697612 -111.6584)
		(end 73.6854 -111.6584)
		(width 0.127)
		(layer "In5.Cu")
		(net "IOM_FULL_PWR_EN")
	)
	(segment
		(start 81.864454 -55.882286)
		(end 82.222594 -55.524146)
		(width 0.127)
		(layer "In5.Cu")
		(net "IOM_FULL_PWR_EN")
	)
	(segment
		(start 74.620628 -100.00615)
		(end 74.620628 -45.428408)
		(width 0.127)
		(layer "In5.Cu")
		(net "IOM_FULL_PWR_EN")
	)
	(segment
		(start 82.803238 -104.012238)
		(end 81.188052 -102.397052)
		(width 0.127)
		(layer "In5.Cu")
		(net "IOM_FULL_PWR_EN")
	)
	(segment
		(start 46.710854 -113.893346)
		(end 61.462666 -113.893346)
		(width 0.127)
		(layer "In5.Cu")
		(net "IOM_FULL_PWR_EN")
	)
	(segment
		(start 74.620628 -45.428408)
		(end 75.143614 -44.905422)
		(width 0.127)
		(layer "In5.Cu")
		(net "IOM_FULL_PWR_EN")
	)
	(segment
		(start 61.462666 -113.893346)
		(end 63.697612 -111.6584)
		(width 0.127)
		(layer "In5.Cu")
		(net "IOM_FULL_PWR_EN")
	)
	(segment
		(start 82.222594 -45.515022)
		(end 82.189828 -45.482256)
		(width 0.127)
		(layer "In5.Cu")
		(net "IOM_FULL_PWR_EN")
	)
	(segment
		(start 73.6854 -111.6584)
		(end 77.232002 -108.111798)
		(width 0.127)
		(layer "In5.Cu")
		(net "IOM_FULL_PWR_EN")
	)
	(segment
		(start 81.188052 -102.397052)
		(end 77.01153 -102.397052)
		(width 0.127)
		(layer "In5.Cu")
		(net "IOM_FULL_PWR_EN")
	)
	(segment
		(start 81.39811 -108.111798)
		(end 82.803238 -106.70667)
		(width 0.127)
		(layer "In5.Cu")
		(net "IOM_FULL_PWR_EN")
	)
	(segment
		(start 75.5777 -145.044922)
		(end 76.130912 -145.598134)
		(width 0.127)
		(layer "F.Cu")
		(net "I2C_SCC_SDA_R")
	)
	(segment
		(start 79.710534 -145.965418)
		(end 78.640432 -145.965418)
		(width 0.127)
		(layer "F.Cu")
		(net "I2C_SCC_SDA_R")
	)
	(segment
		(start 76.907644 -145.2372)
		(end 76.54671 -145.598134)
		(width 0.127)
		(layer "F.Cu")
		(net "I2C_SCC_SDA_R")
	)
	(segment
		(start 78.640432 -145.965418)
		(end 77.912214 -145.2372)
		(width 0.127)
		(layer "F.Cu")
		(net "I2C_SCC_SDA_R")
	)
	(segment
		(start 75.5777 -144.7038)
		(end 75.5777 -145.044922)
		(width 0.127)
		(layer "F.Cu")
		(net "I2C_SCC_SDA_R")
	)
	(segment
		(start 77.912214 -145.2372)
		(end 76.907644 -145.2372)
		(width 0.127)
		(layer "F.Cu")
		(net "I2C_SCC_SDA_R")
	)
	(segment
		(start 76.130912 -145.598134)
		(end 76.54671 -145.598134)
		(width 0.127)
		(layer "F.Cu")
		(net "I2C_SCC_SDA_R")
	)
	(via
		(at 76.54671 -145.598134)
		(size 0.6604)
		(drill 0.3302)
		(layers "F.Cu" "B.Cu")
		(net "I2C_SCC_SDA_R")
	)
	(segment
		(start 76.985114 -144.45488)
		(end 77.07503 -144.544796)
		(width 0.127)
		(layer "F.Cu")
		(net "I2C_SCC_SCL_R")
	)
	(segment
		(start 78.797404 -145.315178)
		(end 79.710534 -145.315178)
		(width 0.127)
		(layer "F.Cu")
		(net "I2C_SCC_SCL_R")
	)
	(segment
		(start 75.3491 -144.0434)
		(end 74.9681 -143.6624)
		(width 0.127)
		(layer "F.Cu")
		(net "I2C_SCC_SCL_R")
	)
	(segment
		(start 78.027022 -144.544796)
		(end 78.797404 -145.315178)
		(width 0.127)
		(layer "F.Cu")
		(net "I2C_SCC_SCL_R")
	)
	(segment
		(start 77.07503 -144.544796)
		(end 78.027022 -144.544796)
		(width 0.127)
		(layer "F.Cu")
		(net "I2C_SCC_SCL_R")
	)
	(segment
		(start 76.985114 -144.45488)
		(end 76.573634 -144.0434)
		(width 0.127)
		(layer "F.Cu")
		(net "I2C_SCC_SCL_R")
	)
	(segment
		(start 76.573634 -144.0434)
		(end 75.3491 -144.0434)
		(width 0.127)
		(layer "F.Cu")
		(net "I2C_SCC_SCL_R")
	)
	(via
		(at 76.985114 -144.45488)
		(size 0.6604)
		(drill 0.3302)
		(layers "F.Cu" "B.Cu")
		(net "I2C_SCC_SCL_R")
	)
	(segment
		(start 76.96073 -59.349894)
		(end 77.668628 -58.641996)
		(width 0.127)
		(layer "F.Cu")
		(net "I2C_MEZZ_ALERT_R_N")
	)
	(segment
		(start 75.475084 -59.349894)
		(end 76.96073 -59.349894)
		(width 0.127)
		(layer "F.Cu")
		(net "I2C_MEZZ_ALERT_R_N")
	)
	(segment
		(start 86.402418 -58.713624)
		(end 85.217 -58.713624)
		(width 0.127)
		(layer "F.Cu")
		(net "I2C_MEZZ_ALERT_R_N")
	)
	(segment
		(start 85.217 -58.713624)
		(end 85.110828 -58.819796)
		(width 0.127)
		(layer "F.Cu")
		(net "I2C_MEZZ_ALERT_R_N")
	)
	(via
		(at 84.8868 -61.4426)
		(size 0.6096)
		(drill 0.3048)
		(layers "F.Cu" "B.Cu")
		(net "I2C_MEZZ_ALERT_R_N")
	)
	(via
		(at 77.668628 -58.641996)
		(size 0.508)
		(drill 0.254)
		(layers "F.Cu" "B.Cu")
		(net "I2C_MEZZ_ALERT_R_N")
	)
	(via
		(at 85.110828 -58.819796)
		(size 0.508)
		(drill 0.254)
		(layers "F.Cu" "B.Cu")
		(net "I2C_MEZZ_ALERT_R_N")
	)
	(segment
		(start 80.164432 -62.0014)
		(end 79.078328 -60.915296)
		(width 0.127)
		(layer "B.Cu")
		(net "I2C_MEZZ_ALERT_R_N")
	)
	(segment
		(start 85.110828 -58.819796)
		(end 85.110828 -61.218572)
		(width 0.127)
		(layer "B.Cu")
		(net "I2C_MEZZ_ALERT_R_N")
	)
	(segment
		(start 84.328 -62.0014)
		(end 80.164432 -62.0014)
		(width 0.127)
		(layer "B.Cu")
		(net "I2C_MEZZ_ALERT_R_N")
	)
	(segment
		(start 84.8868 -61.4426)
		(end 84.328 -62.0014)
		(width 0.127)
		(layer "B.Cu")
		(net "I2C_MEZZ_ALERT_R_N")
	)
	(segment
		(start 79.078328 -60.915296)
		(end 79.078328 -60.051696)
		(width 0.127)
		(layer "B.Cu")
		(net "I2C_MEZZ_ALERT_R_N")
	)
	(segment
		(start 85.110828 -61.218572)
		(end 84.8868 -61.4426)
		(width 0.127)
		(layer "B.Cu")
		(net "I2C_MEZZ_ALERT_R_N")
	)
	(segment
		(start 79.078328 -60.051696)
		(end 77.668628 -58.641996)
		(width 0.127)
		(layer "B.Cu")
		(net "I2C_MEZZ_ALERT_R_N")
	)
	(segment
		(start 71.4502 -116.8654)
		(end 74.72934 -116.8654)
		(width 0.127)
		(layer "F.Cu")
		(net "I2C_MEZZ_ALERT_N")
	)
	(segment
		(start 87.291418 -59.580018)
		(end 87.291418 -58.713624)
		(width 0.127)
		(layer "F.Cu")
		(net "I2C_MEZZ_ALERT_N")
	)
	(segment
		(start 95.5802 -85.471)
		(end 94.555818 -84.446618)
		(width 0.127)
		(layer "F.Cu")
		(net "I2C_MEZZ_ALERT_N")
	)
	(segment
		(start 98.215958 -94.15653)
		(end 97.31756 -93.258132)
		(width 0.127)
		(layer "F.Cu")
		(net "I2C_MEZZ_ALERT_N")
	)
	(segment
		(start 94.555818 -84.446618)
		(end 94.555818 -65.313306)
		(width 0.127)
		(layer "F.Cu")
		(net "I2C_MEZZ_ALERT_N")
	)
	(segment
		(start 46.100238 -139.400534)
		(end 46.100492 -139.400534)
		(width 0.127)
		(layer "F.Cu")
		(net "I2C_MEZZ_ALERT_N")
	)
	(segment
		(start 90.4494 -114.0206)
		(end 96.3422 -114.0206)
		(width 0.127)
		(layer "F.Cu")
		(net "I2C_MEZZ_ALERT_N")
	)
	(segment
		(start 88.86571 -114.57686)
		(end 88.865964 -114.577114)
		(width 0.127)
		(layer "F.Cu")
		(net "I2C_MEZZ_ALERT_N")
	)
	(segment
		(start 77.01788 -114.57686)
		(end 88.86571 -114.57686)
		(width 0.127)
		(layer "F.Cu")
		(net "I2C_MEZZ_ALERT_N")
	)
	(segment
		(start 69.6468 -115.062)
		(end 71.4502 -116.8654)
		(width 0.127)
		(layer "F.Cu")
		(net "I2C_MEZZ_ALERT_N")
	)
	(segment
		(start 87.299038 -57.655968)
		(end 87.299038 -58.706004)
		(width 0.127)
		(layer "F.Cu")
		(net "I2C_MEZZ_ALERT_N")
	)
	(segment
		(start 66.0146 -115.062)
		(end 69.6468 -115.062)
		(width 0.127)
		(layer "F.Cu")
		(net "I2C_MEZZ_ALERT_N")
	)
	(segment
		(start 94.555818 -65.313306)
		(end 89.897712 -60.6552)
		(width 0.127)
		(layer "F.Cu")
		(net "I2C_MEZZ_ALERT_N")
	)
	(segment
		(start 88.3666 -60.6552)
		(end 87.291418 -59.580018)
		(width 0.127)
		(layer "F.Cu")
		(net "I2C_MEZZ_ALERT_N")
	)
	(segment
		(start 98.215958 -112.146842)
		(end 98.215958 -94.15653)
		(width 0.127)
		(layer "F.Cu")
		(net "I2C_MEZZ_ALERT_N")
	)
	(segment
		(start 88.865964 -114.577114)
		(end 89.892886 -114.577114)
		(width 0.127)
		(layer "F.Cu")
		(net "I2C_MEZZ_ALERT_N")
	)
	(segment
		(start 97.31756 -93.258132)
		(end 95.5802 -91.520772)
		(width 0.127)
		(layer "F.Cu")
		(net "I2C_MEZZ_ALERT_N")
	)
	(segment
		(start 65.786 -115.2906)
		(end 66.0146 -115.062)
		(width 0.127)
		(layer "F.Cu")
		(net "I2C_MEZZ_ALERT_N")
	)
	(segment
		(start 96.3422 -114.0206)
		(end 98.215958 -112.146842)
		(width 0.127)
		(layer "F.Cu")
		(net "I2C_MEZZ_ALERT_N")
	)
	(segment
		(start 74.72934 -116.8654)
		(end 77.01788 -114.57686)
		(width 0.127)
		(layer "F.Cu")
		(net "I2C_MEZZ_ALERT_N")
	)
	(segment
		(start 89.897712 -60.6552)
		(end 88.3666 -60.6552)
		(width 0.127)
		(layer "F.Cu")
		(net "I2C_MEZZ_ALERT_N")
	)
	(segment
		(start 95.5802 -91.520772)
		(end 95.5802 -85.471)
		(width 0.127)
		(layer "F.Cu")
		(net "I2C_MEZZ_ALERT_N")
	)
	(segment
		(start 89.892886 -114.577114)
		(end 90.4494 -114.0206)
		(width 0.127)
		(layer "F.Cu")
		(net "I2C_MEZZ_ALERT_N")
	)
	(segment
		(start 87.299038 -58.706004)
		(end 87.291418 -58.713624)
		(width 0.127)
		(layer "F.Cu")
		(net "I2C_MEZZ_ALERT_N")
	)
	(segment
		(start 46.100492 -139.400534)
		(end 46.500034 -139.800076)
		(width 0.127)
		(layer "F.Cu")
		(net "I2C_MEZZ_ALERT_N")
	)
	(via
		(at 97.31756 -93.258132)
		(size 0.6604)
		(drill 0.3302)
		(layers "F.Cu" "B.Cu")
		(net "I2C_MEZZ_ALERT_N")
	)
	(via
		(at 43.7134 -118.6942)
		(size 0.508)
		(drill 0.254)
		(layers "F.Cu" "B.Cu")
		(net "I2C_MEZZ_ALERT_N")
	)
	(via
		(at 46.100238 -139.400534)
		(size 0.4572)
		(drill 0.2032)
		(layers "F.Cu" "B.Cu")
		(net "I2C_MEZZ_ALERT_N")
	)
	(via
		(at 65.786 -115.2906)
		(size 0.508)
		(drill 0.254)
		(layers "F.Cu" "B.Cu")
		(net "I2C_MEZZ_ALERT_N")
	)
	(segment
		(start 43.8785 -127.220218)
		(end 43.86961 -127.229108)
		(width 0.127)
		(layer "In2.Cu")
		(net "I2C_MEZZ_ALERT_N")
	)
	(segment
		(start 45.149516 -139.006834)
		(end 45.706538 -139.006834)
		(width 0.127)
		(layer "In2.Cu")
		(net "I2C_MEZZ_ALERT_N")
	)
	(segment
		(start 43.4086 -118.999)
		(end 43.4086 -121.666)
		(width 0.127)
		(layer "In2.Cu")
		(net "I2C_MEZZ_ALERT_N")
	)
	(segment
		(start 43.86961 -132.005324)
		(end 44.2214 -132.357114)
		(width 0.127)
		(layer "In2.Cu")
		(net "I2C_MEZZ_ALERT_N")
	)
	(segment
		(start 44.893738 -135.402574)
		(end 44.893738 -138.751056)
		(width 0.127)
		(layer "In2.Cu")
		(net "I2C_MEZZ_ALERT_N")
	)
	(segment
		(start 43.4086 -121.666)
		(end 43.8785 -122.1359)
		(width 0.127)
		(layer "In2.Cu")
		(net "I2C_MEZZ_ALERT_N")
	)
	(segment
		(start 44.893738 -138.751056)
		(end 45.149516 -139.006834)
		(width 0.127)
		(layer "In2.Cu")
		(net "I2C_MEZZ_ALERT_N")
	)
	(segment
		(start 44.0563 -133.194806)
		(end 44.0563 -134.565136)
		(width 0.127)
		(layer "In2.Cu")
		(net "I2C_MEZZ_ALERT_N")
	)
	(segment
		(start 44.0563 -134.565136)
		(end 44.893738 -135.402574)
		(width 0.127)
		(layer "In2.Cu")
		(net "I2C_MEZZ_ALERT_N")
	)
	(segment
		(start 43.8785 -122.1359)
		(end 43.8785 -127.220218)
		(width 0.127)
		(layer "In2.Cu")
		(net "I2C_MEZZ_ALERT_N")
	)
	(segment
		(start 45.706538 -139.006834)
		(end 46.100238 -139.400534)
		(width 0.127)
		(layer "In2.Cu")
		(net "I2C_MEZZ_ALERT_N")
	)
	(segment
		(start 44.2214 -133.029706)
		(end 44.0563 -133.194806)
		(width 0.127)
		(layer "In2.Cu")
		(net "I2C_MEZZ_ALERT_N")
	)
	(segment
		(start 43.86961 -127.229108)
		(end 43.86961 -132.005324)
		(width 0.127)
		(layer "In2.Cu")
		(net "I2C_MEZZ_ALERT_N")
	)
	(segment
		(start 44.2214 -132.357114)
		(end 44.2214 -133.029706)
		(width 0.127)
		(layer "In2.Cu")
		(net "I2C_MEZZ_ALERT_N")
	)
	(segment
		(start 43.7134 -118.6942)
		(end 43.4086 -118.999)
		(width 0.127)
		(layer "In2.Cu")
		(net "I2C_MEZZ_ALERT_N")
	)
	(segment
		(start 56.183784 -115.1128)
		(end 64.203834 -115.1128)
		(width 0.127)
		(layer "In5.Cu")
		(net "I2C_MEZZ_ALERT_N")
	)
	(segment
		(start 64.203834 -115.1128)
		(end 64.534288 -114.782346)
		(width 0.127)
		(layer "In5.Cu")
		(net "I2C_MEZZ_ALERT_N")
	)
	(segment
		(start 64.534288 -114.782346)
		(end 64.954912 -114.782346)
		(width 0.127)
		(layer "In5.Cu")
		(net "I2C_MEZZ_ALERT_N")
	)
	(segment
		(start 47.53102 -114.782346)
		(end 55.85333 -114.782346)
		(width 0.127)
		(layer "In5.Cu")
		(net "I2C_MEZZ_ALERT_N")
	)
	(segment
		(start 64.955166 -114.7826)
		(end 65.278 -114.7826)
		(width 0.127)
		(layer "In5.Cu")
		(net "I2C_MEZZ_ALERT_N")
	)
	(segment
		(start 45.3898 -117.1702)
		(end 45.3898 -116.923566)
		(width 0.127)
		(layer "In5.Cu")
		(net "I2C_MEZZ_ALERT_N")
	)
	(segment
		(start 64.954912 -114.782346)
		(end 64.955166 -114.7826)
		(width 0.127)
		(layer "In5.Cu")
		(net "I2C_MEZZ_ALERT_N")
	)
	(segment
		(start 43.8658 -118.6942)
		(end 45.3898 -117.1702)
		(width 0.127)
		(layer "In5.Cu")
		(net "I2C_MEZZ_ALERT_N")
	)
	(segment
		(start 55.85333 -114.782346)
		(end 56.183784 -115.1128)
		(width 0.127)
		(layer "In5.Cu")
		(net "I2C_MEZZ_ALERT_N")
	)
	(segment
		(start 45.3898 -116.923566)
		(end 47.53102 -114.782346)
		(width 0.127)
		(layer "In5.Cu")
		(net "I2C_MEZZ_ALERT_N")
	)
	(segment
		(start 43.7134 -118.6942)
		(end 43.8658 -118.6942)
		(width 0.127)
		(layer "In5.Cu")
		(net "I2C_MEZZ_ALERT_N")
	)
	(segment
		(start 65.278 -114.7826)
		(end 65.786 -115.2906)
		(width 0.127)
		(layer "In5.Cu")
		(net "I2C_MEZZ_ALERT_N")
	)
	(segment
		(start 76.8731 -143.3068)
		(end 77.551534 -143.3068)
		(width 0.127)
		(layer "F.Cu")
		(net "I2C_EXP_RMT_SDA_R")
	)
	(segment
		(start 77.551534 -143.3068)
		(end 78.025498 -143.780764)
		(width 0.127)
		(layer "F.Cu")
		(net "I2C_EXP_RMT_SDA_R")
	)
	(segment
		(start 78.909672 -144.664938)
		(end 78.025498 -143.780764)
		(width 0.127)
		(layer "F.Cu")
		(net "I2C_EXP_RMT_SDA_R")
	)
	(segment
		(start 79.710534 -144.664938)
		(end 78.909672 -144.664938)
		(width 0.127)
		(layer "F.Cu")
		(net "I2C_EXP_RMT_SDA_R")
	)
	(via
		(at 78.025498 -143.780764)
		(size 0.6604)
		(drill 0.3302)
		(layers "F.Cu" "B.Cu")
		(net "I2C_EXP_RMT_SDA_R")
	)
	(segment
		(start 78.07579 -142.124176)
		(end 78.587854 -142.63624)
		(width 0.127)
		(layer "F.Cu")
		(net "I2C_EXP_RMT_SCL_R")
	)
	(segment
		(start 78.587854 -142.63624)
		(end 78.587854 -143.577564)
		(width 0.127)
		(layer "F.Cu")
		(net "I2C_EXP_RMT_SCL_R")
	)
	(segment
		(start 76.943204 -141.633194)
		(end 77.584808 -141.633194)
		(width 0.127)
		(layer "F.Cu")
		(net "I2C_EXP_RMT_SCL_R")
	)
	(segment
		(start 79.024988 -144.014698)
		(end 79.710534 -144.014698)
		(width 0.127)
		(layer "F.Cu")
		(net "I2C_EXP_RMT_SCL_R")
	)
	(segment
		(start 77.584808 -141.633194)
		(end 78.07579 -142.124176)
		(width 0.127)
		(layer "F.Cu")
		(net "I2C_EXP_RMT_SCL_R")
	)
	(segment
		(start 78.587854 -143.577564)
		(end 79.024988 -144.014698)
		(width 0.127)
		(layer "F.Cu")
		(net "I2C_EXP_RMT_SCL_R")
	)
	(via
		(at 78.07579 -142.124176)
		(size 0.6604)
		(drill 0.3302)
		(layers "F.Cu" "B.Cu")
		(net "I2C_EXP_RMT_SCL_R")
	)
	(segment
		(start 79.710534 -143.364458)
		(end 80.56118 -143.364458)
		(width 0.127)
		(layer "F.Cu")
		(net "I2C_EXP_LOC_SDA_R")
	)
	(segment
		(start 80.56118 -143.364458)
		(end 81.090008 -143.893286)
		(width 0.127)
		(layer "F.Cu")
		(net "I2C_EXP_LOC_SDA_R")
	)
	(via
		(at 81.090008 -143.893286)
		(size 0.508)
		(drill 0.254)
		(layers "F.Cu" "B.Cu")
		(net "I2C_EXP_LOC_SDA_R")
	)
	(via
		(at 80.137 -144.4498)
		(size 0.6096)
		(drill 0.3048)
		(layers "F.Cu" "B.Cu")
		(net "I2C_EXP_LOC_SDA_R")
	)
	(segment
		(start 79.4131 -145.542)
		(end 79.4131 -145.1737)
		(width 0.127)
		(layer "B.Cu")
		(net "I2C_EXP_LOC_SDA_R")
	)
	(segment
		(start 79.4131 -145.1737)
		(end 80.137 -144.4498)
		(width 0.127)
		(layer "B.Cu")
		(net "I2C_EXP_LOC_SDA_R")
	)
	(segment
		(start 81.090008 -143.893286)
		(end 80.693514 -143.893286)
		(width 0.127)
		(layer "B.Cu")
		(net "I2C_EXP_LOC_SDA_R")
	)
	(segment
		(start 80.693514 -143.893286)
		(end 80.137 -144.4498)
		(width 0.127)
		(layer "B.Cu")
		(net "I2C_EXP_LOC_SDA_R")
	)
	(segment
		(start 81.021682 -142.714218)
		(end 79.710534 -142.714218)
		(width 0.127)
		(layer "F.Cu")
		(net "I2C_EXP_LOC_SCL_R")
	)
	(segment
		(start 81.160366 -142.852902)
		(end 81.021682 -142.714218)
		(width 0.127)
		(layer "F.Cu")
		(net "I2C_EXP_LOC_SCL_R")
	)
	(via
		(at 81.160366 -142.852902)
		(size 0.508)
		(drill 0.254)
		(layers "F.Cu" "B.Cu")
		(net "I2C_EXP_LOC_SCL_R")
	)
	(via
		(at 80.137 -143.0147)
		(size 0.6096)
		(drill 0.3048)
		(layers "F.Cu" "B.Cu")
		(net "I2C_EXP_LOC_SCL_R")
	)
	(segment
		(start 80.998568 -143.0147)
		(end 81.160366 -142.852902)
		(width 0.127)
		(layer "B.Cu")
		(net "I2C_EXP_LOC_SCL_R")
	)
	(segment
		(start 79.0194 -143.0147)
		(end 78.9178 -142.9131)
		(width 0.127)
		(layer "B.Cu")
		(net "I2C_EXP_LOC_SCL_R")
	)
	(segment
		(start 80.137 -143.0147)
		(end 79.0194 -143.0147)
		(width 0.127)
		(layer "B.Cu")
		(net "I2C_EXP_LOC_SCL_R")
	)
	(segment
		(start 80.137 -143.0147)
		(end 80.998568 -143.0147)
		(width 0.127)
		(layer "B.Cu")
		(net "I2C_EXP_LOC_SCL_R")
	)
	(segment
		(start 78.109826 -148.38553)
		(end 78.99527 -148.38553)
		(width 0.127)
		(layer "F.Cu")
		(net "I2C_DPB_SDA_R")
	)
	(segment
		(start 79.710534 -147.670266)
		(end 79.710534 -147.265898)
		(width 0.127)
		(layer "F.Cu")
		(net "I2C_DPB_SDA_R")
	)
	(segment
		(start 76.830428 -146.839432)
		(end 77.403452 -146.839432)
		(width 0.127)
		(layer "F.Cu")
		(net "I2C_DPB_SDA_R")
	)
	(segment
		(start 77.787754 -148.063458)
		(end 78.109826 -148.38553)
		(width 0.127)
		(layer "F.Cu")
		(net "I2C_DPB_SDA_R")
	)
	(segment
		(start 78.99527 -148.38553)
		(end 79.710534 -147.670266)
		(width 0.127)
		(layer "F.Cu")
		(net "I2C_DPB_SDA_R")
	)
	(segment
		(start 77.403452 -146.839432)
		(end 77.787754 -147.223734)
		(width 0.127)
		(layer "F.Cu")
		(net "I2C_DPB_SDA_R")
	)
	(segment
		(start 77.787754 -147.223734)
		(end 77.787754 -148.063458)
		(width 0.127)
		(layer "F.Cu")
		(net "I2C_DPB_SDA_R")
	)
	(via
		(at 78.109826 -148.38553)
		(size 0.6604)
		(drill 0.3302)
		(layers "F.Cu" "B.Cu")
		(net "I2C_DPB_SDA_R")
	)
	(segment
		(start 77.547978 -146.182334)
		(end 75.862434 -146.182334)
		(width 0.127)
		(layer "F.Cu")
		(net "I2C_DPB_SCL_R")
	)
	(segment
		(start 75.862434 -146.182334)
		(end 75.3999 -145.7198)
		(width 0.127)
		(layer "F.Cu")
		(net "I2C_DPB_SCL_R")
	)
	(segment
		(start 77.816456 -145.913856)
		(end 77.547978 -146.182334)
		(width 0.127)
		(layer "F.Cu")
		(net "I2C_DPB_SCL_R")
	)
	(segment
		(start 78.518258 -146.615658)
		(end 77.816456 -145.913856)
		(width 0.127)
		(layer "F.Cu")
		(net "I2C_DPB_SCL_R")
	)
	(segment
		(start 79.710534 -146.615658)
		(end 78.518258 -146.615658)
		(width 0.127)
		(layer "F.Cu")
		(net "I2C_DPB_SCL_R")
	)
	(via
		(at 77.816456 -145.913856)
		(size 0.6604)
		(drill 0.3302)
		(layers "F.Cu" "B.Cu")
		(net "I2C_DPB_SCL_R")
	)
	(segment
		(start 88.0237 -133.2103)
		(end 87.5538 -132.7404)
		(width 0.127)
		(layer "F.Cu")
		(net "EEPROM_A2")
	)
	(segment
		(start 87.5538 -131.9276)
		(end 87.5538 -132.7404)
		(width 0.127)
		(layer "F.Cu")
		(net "EEPROM_A2")
	)
	(segment
		(start 91.208352 -133.776974)
		(end 90.787474 -133.776974)
		(width 0.127)
		(layer "F.Cu")
		(net "EEPROM_A2")
	)
	(segment
		(start 87.757 -131.7244)
		(end 87.5538 -131.9276)
		(width 0.127)
		(layer "F.Cu")
		(net "EEPROM_A2")
	)
	(segment
		(start 90.787474 -133.776974)
		(end 90.2208 -133.2103)
		(width 0.127)
		(layer "F.Cu")
		(net "EEPROM_A2")
	)
	(segment
		(start 88.9 -133.2103)
		(end 88.0237 -133.2103)
		(width 0.127)
		(layer "F.Cu")
		(net "EEPROM_A2")
	)
	(segment
		(start 87.738712 -131.339844)
		(end 87.757 -131.358132)
		(width 0.127)
		(layer "F.Cu")
		(net "EEPROM_A2")
	)
	(segment
		(start 90.2208 -133.2103)
		(end 88.9 -133.2103)
		(width 0.127)
		(layer "F.Cu")
		(net "EEPROM_A2")
	)
	(segment
		(start 87.757 -131.358132)
		(end 87.757 -131.7244)
		(width 0.127)
		(layer "F.Cu")
		(net "EEPROM_A2")
	)
	(via
		(at 87.5538 -132.7404)
		(size 0.6604)
		(drill 0.3302)
		(layers "F.Cu" "B.Cu")
		(net "EEPROM_A2")
	)
	(segment
		(start 86.984586 -134.232904)
		(end 87.742522 -134.99084)
		(width 0.127)
		(layer "F.Cu")
		(net "EEPROM_A1")
	)
	(segment
		(start 91.208352 -135.046974)
		(end 89.894918 -135.046974)
		(width 0.127)
		(layer "F.Cu")
		(net "EEPROM_A1")
	)
	(segment
		(start 87.742522 -134.99084)
		(end 87.993982 -135.2423)
		(width 0.127)
		(layer "F.Cu")
		(net "EEPROM_A1")
	)
	(segment
		(start 89.894918 -135.046974)
		(end 89.699592 -135.2423)
		(width 0.127)
		(layer "F.Cu")
		(net "EEPROM_A1")
	)
	(segment
		(start 86.599268 -134.232904)
		(end 86.984586 -134.232904)
		(width 0.127)
		(layer "F.Cu")
		(net "EEPROM_A1")
	)
	(segment
		(start 87.993982 -135.2423)
		(end 88.9 -135.2423)
		(width 0.127)
		(layer "F.Cu")
		(net "EEPROM_A1")
	)
	(segment
		(start 89.699592 -135.2423)
		(end 88.9 -135.2423)
		(width 0.127)
		(layer "F.Cu")
		(net "EEPROM_A1")
	)
	(via
		(at 87.742522 -134.99084)
		(size 0.6604)
		(drill 0.3302)
		(layers "F.Cu" "B.Cu")
		(net "EEPROM_A1")
	)
	(segment
		(start 87.702898 -137.416286)
		(end 88.80221 -136.316974)
		(width 0.127)
		(layer "F.Cu")
		(net "EEPROM_A0")
	)
	(segment
		(start 87.702898 -137.416286)
		(end 87.6935 -137.425684)
		(width 0.127)
		(layer "F.Cu")
		(net "EEPROM_A0")
	)
	(segment
		(start 89.16162 -136.316974)
		(end 91.208352 -136.316974)
		(width 0.127)
		(layer "F.Cu")
		(net "EEPROM_A0")
	)
	(segment
		(start 87.6935 -137.425684)
		(end 87.6935 -138.4554)
		(width 0.127)
		(layer "F.Cu")
		(net "EEPROM_A0")
	)
	(segment
		(start 88.80221 -136.316974)
		(end 89.16162 -136.316974)
		(width 0.127)
		(layer "F.Cu")
		(net "EEPROM_A0")
	)
	(via
		(at 89.16162 -136.316974)
		(size 0.6604)
		(drill 0.3302)
		(layers "F.Cu" "B.Cu")
		(net "EEPROM_A0")
	)
	(segment
		(start 15.07363 -136.571736)
		(end 15.07363 -135.62711)
		(width 0.127)
		(layer "F.Cu")
		(net "DDR4_RST_N")
	)
	(segment
		(start 9.323832 -136.716516)
		(end 10.350754 -136.716516)
		(width 0.127)
		(layer "F.Cu")
		(net "DDR4_RST_N")
	)
	(segment
		(start 14.27734 -136.016746)
		(end 14.56563 -136.305036)
		(width 0.127)
		(layer "F.Cu")
		(net "DDR4_RST_N")
	)
	(segment
		(start 35.153854 -138.709654)
		(end 35.153854 -137.97534)
		(width 0.127)
		(layer "F.Cu")
		(net "DDR4_RST_N")
	)
	(segment
		(start 35.153854 -137.97534)
		(end 33.922716 -136.744202)
		(width 0.127)
		(layer "F.Cu")
		(net "DDR4_RST_N")
	)
	(segment
		(start 10.350754 -136.716516)
		(end 10.352024 -136.715246)
		(width 0.127)
		(layer "F.Cu")
		(net "DDR4_RST_N")
	)
	(segment
		(start 16.177768 -138.248136)
		(end 16.747998 -138.248136)
		(width 0.127)
		(layer "F.Cu")
		(net "DDR4_RST_N")
	)
	(segment
		(start 14.56563 -136.305036)
		(end 14.56563 -136.571736)
		(width 0.127)
		(layer "F.Cu")
		(net "DDR4_RST_N")
	)
	(segment
		(start 16.747998 -138.248136)
		(end 16.834612 -138.161522)
		(width 0.127)
		(layer "F.Cu")
		(net "DDR4_RST_N")
	)
	(segment
		(start 39.299896 -140.599922)
		(end 37.044122 -140.599922)
		(width 0.127)
		(layer "F.Cu")
		(net "DDR4_RST_N")
	)
	(segment
		(start 15.58163 -136.774174)
		(end 15.923768 -137.116312)
		(width 0.127)
		(layer "F.Cu")
		(net "DDR4_RST_N")
	)
	(segment
		(start 33.922716 -136.744202)
		(end 33.922716 -136.492996)
		(width 0.127)
		(layer "F.Cu")
		(net "DDR4_RST_N")
	)
	(segment
		(start 15.58163 -135.62711)
		(end 15.58163 -136.774174)
		(width 0.127)
		(layer "F.Cu")
		(net "DDR4_RST_N")
	)
	(segment
		(start 14.56563 -136.571736)
		(end 14.714474 -136.72058)
		(width 0.127)
		(layer "F.Cu")
		(net "DDR4_RST_N")
	)
	(segment
		(start 15.923768 -137.116312)
		(end 15.923768 -137.994136)
		(width 0.127)
		(layer "F.Cu")
		(net "DDR4_RST_N")
	)
	(segment
		(start 37.044122 -140.599922)
		(end 35.153854 -138.709654)
		(width 0.127)
		(layer "F.Cu")
		(net "DDR4_RST_N")
	)
	(segment
		(start 17.234662 -137.761472)
		(end 16.834612 -138.161522)
		(width 0.127)
		(layer "F.Cu")
		(net "DDR4_RST_N")
	)
	(segment
		(start 15.222474 -135.478266)
		(end 15.432786 -135.478266)
		(width 0.127)
		(layer "F.Cu")
		(net "DDR4_RST_N")
	)
	(segment
		(start 14.714474 -136.72058)
		(end 14.924786 -136.72058)
		(width 0.127)
		(layer "F.Cu")
		(net "DDR4_RST_N")
	)
	(segment
		(start 15.923768 -137.994136)
		(end 16.177768 -138.248136)
		(width 0.127)
		(layer "F.Cu")
		(net "DDR4_RST_N")
	)
	(segment
		(start 10.352024 -136.197594)
		(end 10.532872 -136.016746)
		(width 0.127)
		(layer "F.Cu")
		(net "DDR4_RST_N")
	)
	(segment
		(start 15.432786 -135.478266)
		(end 15.58163 -135.62711)
		(width 0.127)
		(layer "F.Cu")
		(net "DDR4_RST_N")
	)
	(segment
		(start 15.07363 -135.62711)
		(end 15.222474 -135.478266)
		(width 0.127)
		(layer "F.Cu")
		(net "DDR4_RST_N")
	)
	(segment
		(start 10.352024 -136.715246)
		(end 10.352024 -136.197594)
		(width 0.127)
		(layer "F.Cu")
		(net "DDR4_RST_N")
	)
	(segment
		(start 10.532872 -136.016746)
		(end 14.27734 -136.016746)
		(width 0.127)
		(layer "F.Cu")
		(net "DDR4_RST_N")
	)
	(segment
		(start 14.924786 -136.72058)
		(end 15.07363 -136.571736)
		(width 0.127)
		(layer "F.Cu")
		(net "DDR4_RST_N")
	)
	(via
		(at 33.922716 -136.492996)
		(size 0.508)
		(drill 0.254)
		(layers "F.Cu" "B.Cu")
		(net "DDR4_RST_N")
	)
	(via
		(at 17.234662 -137.761472)
		(size 0.508)
		(drill 0.254)
		(layers "F.Cu" "B.Cu")
		(net "DDR4_RST_N")
	)
	(segment
		(start 28.190698 -134.232396)
		(end 21.311108 -134.232396)
		(width 0.127)
		(layer "In5.Cu")
		(net "DDR4_RST_N")
	)
	(segment
		(start 32.798258 -136.57326)
		(end 32.671258 -136.44626)
		(width 0.127)
		(layer "In5.Cu")
		(net "DDR4_RST_N")
	)
	(segment
		(start 34.31286 -135.89762)
		(end 34.17824 -135.763)
		(width 0.127)
		(layer "In5.Cu")
		(net "DDR4_RST_N")
	)
	(segment
		(start 33.179258 -136.44626)
		(end 33.052258 -136.57326)
		(width 0.127)
		(layer "In5.Cu")
		(net "DDR4_RST_N")
	)
	(segment
		(start 33.179258 -135.89)
		(end 33.179258 -136.44626)
		(width 0.127)
		(layer "In5.Cu")
		(net "DDR4_RST_N")
	)
	(segment
		(start 34.17824 -135.763)
		(end 33.306258 -135.763)
		(width 0.127)
		(layer "In5.Cu")
		(net "DDR4_RST_N")
	)
	(segment
		(start 17.714722 -136.615678)
		(end 17.634458 -136.695942)
		(width 0.0889)
		(layer "In5.Cu")
		(net "DDR4_RST_N")
	)
	(segment
		(start 18.280634 -136.542526)
		(end 17.787874 -136.542526)
		(width 0.127)
		(layer "In5.Cu")
		(net "DDR4_RST_N")
	)
	(segment
		(start 18.292572 -136.554464)
		(end 18.280634 -136.542526)
		(width 0.127)
		(layer "In5.Cu")
		(net "DDR4_RST_N")
	)
	(segment
		(start 32.671258 -135.89)
		(end 32.544258 -135.763)
		(width 0.127)
		(layer "In5.Cu")
		(net "DDR4_RST_N")
	)
	(segment
		(start 18.98904 -136.554464)
		(end 18.292572 -136.554464)
		(width 0.127)
		(layer "In5.Cu")
		(net "DDR4_RST_N")
	)
	(segment
		(start 34.10331 -136.492996)
		(end 34.31286 -136.283446)
		(width 0.127)
		(layer "In5.Cu")
		(net "DDR4_RST_N")
	)
	(segment
		(start 17.634458 -136.695942)
		(end 17.634458 -137.361676)
		(width 0.0889)
		(layer "In5.Cu")
		(net "DDR4_RST_N")
	)
	(segment
		(start 31.7627 -136.357106)
		(end 31.62681 -136.492996)
		(width 0.127)
		(layer "In5.Cu")
		(net "DDR4_RST_N")
	)
	(segment
		(start 31.311596 -136.492996)
		(end 30.5816 -135.763)
		(width 0.127)
		(layer "In5.Cu")
		(net "DDR4_RST_N")
	)
	(segment
		(start 32.671258 -136.44626)
		(end 32.671258 -135.89)
		(width 0.127)
		(layer "In5.Cu")
		(net "DDR4_RST_N")
	)
	(segment
		(start 30.5816 -135.763)
		(end 29.721302 -135.763)
		(width 0.127)
		(layer "In5.Cu")
		(net "DDR4_RST_N")
	)
	(segment
		(start 33.306258 -135.763)
		(end 33.179258 -135.89)
		(width 0.127)
		(layer "In5.Cu")
		(net "DDR4_RST_N")
	)
	(segment
		(start 34.31286 -136.283446)
		(end 34.31286 -135.89762)
		(width 0.127)
		(layer "In5.Cu")
		(net "DDR4_RST_N")
	)
	(segment
		(start 31.7627 -135.89)
		(end 31.7627 -136.357106)
		(width 0.127)
		(layer "In5.Cu")
		(net "DDR4_RST_N")
	)
	(segment
		(start 33.922716 -136.492996)
		(end 34.10331 -136.492996)
		(width 0.127)
		(layer "In5.Cu")
		(net "DDR4_RST_N")
	)
	(segment
		(start 29.721302 -135.763)
		(end 28.190698 -134.232396)
		(width 0.127)
		(layer "In5.Cu")
		(net "DDR4_RST_N")
	)
	(segment
		(start 31.62681 -136.492996)
		(end 31.311596 -136.492996)
		(width 0.127)
		(layer "In5.Cu")
		(net "DDR4_RST_N")
	)
	(segment
		(start 31.8897 -135.763)
		(end 31.7627 -135.89)
		(width 0.127)
		(layer "In5.Cu")
		(net "DDR4_RST_N")
	)
	(segment
		(start 32.544258 -135.763)
		(end 31.8897 -135.763)
		(width 0.127)
		(layer "In5.Cu")
		(net "DDR4_RST_N")
	)
	(segment
		(start 17.787874 -136.542526)
		(end 17.714722 -136.615678)
		(width 0.127)
		(layer "In5.Cu")
		(net "DDR4_RST_N")
	)
	(segment
		(start 21.311108 -134.232396)
		(end 18.98904 -136.554464)
		(width 0.127)
		(layer "In5.Cu")
		(net "DDR4_RST_N")
	)
	(segment
		(start 33.052258 -136.57326)
		(end 32.798258 -136.57326)
		(width 0.127)
		(layer "In5.Cu")
		(net "DDR4_RST_N")
	)
	(segment
		(start 17.634458 -137.361676)
		(end 17.234662 -137.761472)
		(width 0.0889)
		(layer "In5.Cu")
		(net "DDR4_RST_N")
	)
	(segment
		(start 23.810976 -137.672826)
		(end 23.32228 -138.161522)
		(width 0.127)
		(layer "F.Cu")
		(net "DDR4_ALERT")
	)
	(segment
		(start 42.900092 -141.000226)
		(end 43.299888 -141.399768)
		(width 0.127)
		(layer "F.Cu")
		(net "DDR4_ALERT")
	)
	(segment
		(start 25.174194 -134.796022)
		(end 25.174194 -136.957054)
		(width 0.127)
		(layer "F.Cu")
		(net "DDR4_ALERT")
	)
	(segment
		(start 23.32228 -138.161522)
		(end 23.234396 -138.161522)
		(width 0.127)
		(layer "F.Cu")
		(net "DDR4_ALERT")
	)
	(segment
		(start 24.139144 -133.760972)
		(end 25.174194 -134.796022)
		(width 0.127)
		(layer "F.Cu")
		(net "DDR4_ALERT")
	)
	(segment
		(start 23.368 -130.5433)
		(end 22.030944 -130.5433)
		(width 0.127)
		(layer "F.Cu")
		(net "DDR4_ALERT")
	)
	(segment
		(start 24.139144 -130.859784)
		(end 24.139144 -133.760972)
		(width 0.127)
		(layer "F.Cu")
		(net "DDR4_ALERT")
	)
	(segment
		(start 23.82266 -130.5433)
		(end 24.139144 -130.859784)
		(width 0.127)
		(layer "F.Cu")
		(net "DDR4_ALERT")
	)
	(segment
		(start 25.174194 -136.957054)
		(end 24.458422 -137.672826)
		(width 0.127)
		(layer "F.Cu")
		(net "DDR4_ALERT")
	)
	(segment
		(start 23.368 -130.5433)
		(end 23.82266 -130.5433)
		(width 0.127)
		(layer "F.Cu")
		(net "DDR4_ALERT")
	)
	(segment
		(start 22.030944 -130.5433)
		(end 22.011386 -130.562858)
		(width 0.127)
		(layer "F.Cu")
		(net "DDR4_ALERT")
	)
	(segment
		(start 22.011386 -130.562858)
		(end 22.011386 -129.556256)
		(width 0.127)
		(layer "F.Cu")
		(net "DDR4_ALERT")
	)
	(segment
		(start 22.011386 -129.556256)
		(end 22.014942 -129.5527)
		(width 0.127)
		(layer "F.Cu")
		(net "DDR4_ALERT")
	)
	(segment
		(start 24.458422 -137.672826)
		(end 23.810976 -137.672826)
		(width 0.127)
		(layer "F.Cu")
		(net "DDR4_ALERT")
	)
	(segment
		(start 43.299888 -141.399768)
		(end 43.299888 -141.400022)
		(width 0.127)
		(layer "F.Cu")
		(net "DDR4_ALERT")
	)
	(via
		(at 23.810976 -137.672826)
		(size 0.508)
		(drill 0.254)
		(layers "F.Cu" "B.Cu")
		(net "DDR4_ALERT")
	)
	(via
		(at 42.900092 -141.000226)
		(size 0.4572)
		(drill 0.2032)
		(layers "F.Cu" "B.Cu")
		(net "DDR4_ALERT")
	)
	(segment
		(start 24.426164 -137.926318)
		(end 27.281124 -137.926318)
		(width 0.127)
		(layer "In2.Cu")
		(net "DDR4_ALERT")
	)
	(segment
		(start 31.712662 -137.8077)
		(end 32.129222 -137.39114)
		(width 0.127)
		(layer "In2.Cu")
		(net "DDR4_ALERT")
	)
	(segment
		(start 33.885124 -137.8585)
		(end 34.012124 -137.7315)
		(width 0.127)
		(layer "In2.Cu")
		(net "DDR4_ALERT")
	)
	(segment
		(start 35.790124 -138.80084)
		(end 35.917124 -138.67384)
		(width 0.127)
		(layer "In2.Cu")
		(net "DDR4_ALERT")
	)
	(segment
		(start 34.012124 -137.7315)
		(end 34.266124 -137.7315)
		(width 0.127)
		(layer "In2.Cu")
		(net "DDR4_ALERT")
	)
	(segment
		(start 31.0896 -139.91844)
		(end 31.0896 -137.99312)
		(width 0.127)
		(layer "In2.Cu")
		(net "DDR4_ALERT")
	)
	(segment
		(start 40.257984 -141.393672)
		(end 42.506646 -141.393672)
		(width 0.127)
		(layer "In2.Cu")
		(net "DDR4_ALERT")
	)
	(segment
		(start 32.944816 -137.7315)
		(end 33.250124 -137.7315)
		(width 0.127)
		(layer "In2.Cu")
		(net "DDR4_ALERT")
	)
	(segment
		(start 35.917124 -138.67384)
		(end 35.917124 -137.8585)
		(width 0.127)
		(layer "In2.Cu")
		(net "DDR4_ALERT")
	)
	(segment
		(start 35.536124 -138.80084)
		(end 35.790124 -138.80084)
		(width 0.127)
		(layer "In2.Cu")
		(net "DDR4_ALERT")
	)
	(segment
		(start 33.250124 -137.7315)
		(end 33.377124 -137.8585)
		(width 0.127)
		(layer "In2.Cu")
		(net "DDR4_ALERT")
	)
	(segment
		(start 31.0896 -137.99312)
		(end 31.27502 -137.8077)
		(width 0.127)
		(layer "In2.Cu")
		(net "DDR4_ALERT")
	)
	(segment
		(start 33.377124 -138.39952)
		(end 33.504124 -138.52652)
		(width 0.127)
		(layer "In2.Cu")
		(net "DDR4_ALERT")
	)
	(segment
		(start 35.282124 -137.7315)
		(end 35.409124 -137.8585)
		(width 0.127)
		(layer "In2.Cu")
		(net "DDR4_ALERT")
	)
	(segment
		(start 42.506646 -141.393672)
		(end 42.900092 -141.000226)
		(width 0.127)
		(layer "In2.Cu")
		(net "DDR4_ALERT")
	)
	(segment
		(start 30.9626 -140.04544)
		(end 31.0896 -139.91844)
		(width 0.127)
		(layer "In2.Cu")
		(net "DDR4_ALERT")
	)
	(segment
		(start 35.409124 -138.67384)
		(end 35.536124 -138.80084)
		(width 0.127)
		(layer "In2.Cu")
		(net "DDR4_ALERT")
	)
	(segment
		(start 34.774124 -138.76782)
		(end 34.901124 -138.64082)
		(width 0.127)
		(layer "In2.Cu")
		(net "DDR4_ALERT")
	)
	(segment
		(start 34.393124 -138.64082)
		(end 34.520124 -138.76782)
		(width 0.127)
		(layer "In2.Cu")
		(net "DDR4_ALERT")
	)
	(segment
		(start 27.281124 -137.926318)
		(end 29.400246 -140.04544)
		(width 0.127)
		(layer "In2.Cu")
		(net "DDR4_ALERT")
	)
	(segment
		(start 32.129222 -137.39114)
		(end 32.604456 -137.39114)
		(width 0.127)
		(layer "In2.Cu")
		(net "DDR4_ALERT")
	)
	(segment
		(start 23.810976 -137.672826)
		(end 24.172672 -137.672826)
		(width 0.127)
		(layer "In2.Cu")
		(net "DDR4_ALERT")
	)
	(segment
		(start 34.901124 -138.64082)
		(end 34.901124 -137.8585)
		(width 0.127)
		(layer "In2.Cu")
		(net "DDR4_ALERT")
	)
	(segment
		(start 36.595812 -137.7315)
		(end 40.257984 -141.393672)
		(width 0.127)
		(layer "In2.Cu")
		(net "DDR4_ALERT")
	)
	(segment
		(start 33.377124 -137.8585)
		(end 33.377124 -138.39952)
		(width 0.127)
		(layer "In2.Cu")
		(net "DDR4_ALERT")
	)
	(segment
		(start 29.400246 -140.04544)
		(end 30.9626 -140.04544)
		(width 0.127)
		(layer "In2.Cu")
		(net "DDR4_ALERT")
	)
	(segment
		(start 34.901124 -137.8585)
		(end 35.028124 -137.7315)
		(width 0.127)
		(layer "In2.Cu")
		(net "DDR4_ALERT")
	)
	(segment
		(start 34.520124 -138.76782)
		(end 34.774124 -138.76782)
		(width 0.127)
		(layer "In2.Cu")
		(net "DDR4_ALERT")
	)
	(segment
		(start 31.27502 -137.8077)
		(end 31.712662 -137.8077)
		(width 0.127)
		(layer "In2.Cu")
		(net "DDR4_ALERT")
	)
	(segment
		(start 35.028124 -137.7315)
		(end 35.282124 -137.7315)
		(width 0.127)
		(layer "In2.Cu")
		(net "DDR4_ALERT")
	)
	(segment
		(start 35.409124 -137.8585)
		(end 35.409124 -138.67384)
		(width 0.127)
		(layer "In2.Cu")
		(net "DDR4_ALERT")
	)
	(segment
		(start 32.604456 -137.39114)
		(end 32.944816 -137.7315)
		(width 0.127)
		(layer "In2.Cu")
		(net "DDR4_ALERT")
	)
	(segment
		(start 24.172672 -137.672826)
		(end 24.426164 -137.926318)
		(width 0.127)
		(layer "In2.Cu")
		(net "DDR4_ALERT")
	)
	(segment
		(start 35.917124 -137.8585)
		(end 36.044124 -137.7315)
		(width 0.127)
		(layer "In2.Cu")
		(net "DDR4_ALERT")
	)
	(segment
		(start 34.393124 -137.8585)
		(end 34.393124 -138.64082)
		(width 0.127)
		(layer "In2.Cu")
		(net "DDR4_ALERT")
	)
	(segment
		(start 33.504124 -138.52652)
		(end 33.758124 -138.52652)
		(width 0.127)
		(layer "In2.Cu")
		(net "DDR4_ALERT")
	)
	(segment
		(start 34.266124 -137.7315)
		(end 34.393124 -137.8585)
		(width 0.127)
		(layer "In2.Cu")
		(net "DDR4_ALERT")
	)
	(segment
		(start 33.885124 -138.39952)
		(end 33.885124 -137.8585)
		(width 0.127)
		(layer "In2.Cu")
		(net "DDR4_ALERT")
	)
	(segment
		(start 36.044124 -137.7315)
		(end 36.595812 -137.7315)
		(width 0.127)
		(layer "In2.Cu")
		(net "DDR4_ALERT")
	)
	(segment
		(start 33.758124 -138.52652)
		(end 33.885124 -138.39952)
		(width 0.127)
		(layer "In2.Cu")
		(net "DDR4_ALERT")
	)
	(segment
		(start 18.958052 -134.238492)
		(end 19.383248 -134.663688)
		(width 0.127)
		(layer "F.Cu")
		(net "DDR4_ACT")
	)
	(segment
		(start 18.422112 -132.983732)
		(end 18.422112 -131.261358)
		(width 0.127)
		(layer "F.Cu")
		(net "DDR4_ACT")
	)
	(segment
		(start 18.434558 -140.561568)
		(end 18.761456 -140.888466)
		(width 0.127)
		(layer "F.Cu")
		(net "DDR4_ACT")
	)
	(segment
		(start 18.74774 -134.238492)
		(end 18.958052 -134.238492)
		(width 0.127)
		(layer "F.Cu")
		(net "DDR4_ACT")
	)
	(segment
		(start 19.383248 -134.663688)
		(end 19.59356 -134.663688)
		(width 0.127)
		(layer "F.Cu")
		(net "DDR4_ACT")
	)
	(segment
		(start 17.723612 -129.583688)
		(end 17.7546 -129.5527)
		(width 0.127)
		(layer "F.Cu")
		(net "DDR4_ACT")
	)
	(segment
		(start 18.598388 -134.597648)
		(end 18.598388 -134.38759)
		(width 0.127)
		(layer "F.Cu")
		(net "DDR4_ACT")
	)
	(segment
		(start 18.422112 -131.261358)
		(end 17.723612 -130.562858)
		(width 0.127)
		(layer "F.Cu")
		(net "DDR4_ACT")
	)
	(segment
		(start 19.882104 -135.881364)
		(end 18.598388 -134.597648)
		(width 0.127)
		(layer "F.Cu")
		(net "DDR4_ACT")
	)
	(segment
		(start 19.882104 -140.461238)
		(end 19.882104 -138.573764)
		(width 0.127)
		(layer "F.Cu")
		(net "DDR4_ACT")
	)
	(segment
		(start 19.454876 -140.888466)
		(end 19.882104 -140.461238)
		(width 0.127)
		(layer "F.Cu")
		(net "DDR4_ACT")
	)
	(segment
		(start 19.742912 -134.51459)
		(end 19.742912 -134.304532)
		(width 0.127)
		(layer "F.Cu")
		(net "DDR4_ACT")
	)
	(segment
		(start 40.899842 -142.199868)
		(end 41.299892 -142.599918)
		(width 0.127)
		(layer "F.Cu")
		(net "DDR4_ACT")
	)
	(segment
		(start 19.742912 -134.304532)
		(end 18.422112 -132.983732)
		(width 0.127)
		(layer "F.Cu")
		(net "DDR4_ACT")
	)
	(segment
		(start 18.761456 -140.888466)
		(end 19.454876 -140.888466)
		(width 0.127)
		(layer "F.Cu")
		(net "DDR4_ACT")
	)
	(segment
		(start 18.598388 -134.38759)
		(end 18.74774 -134.238492)
		(width 0.127)
		(layer "F.Cu")
		(net "DDR4_ACT")
	)
	(segment
		(start 19.882104 -138.573764)
		(end 19.882104 -135.881364)
		(width 0.127)
		(layer "F.Cu")
		(net "DDR4_ACT")
	)
	(segment
		(start 17.723612 -130.562858)
		(end 17.723612 -129.583688)
		(width 0.127)
		(layer "F.Cu")
		(net "DDR4_ACT")
	)
	(segment
		(start 19.59356 -134.663688)
		(end 19.742912 -134.51459)
		(width 0.127)
		(layer "F.Cu")
		(net "DDR4_ACT")
	)
	(via
		(at 19.882104 -138.573764)
		(size 0.508)
		(drill 0.254)
		(layers "F.Cu" "B.Cu")
		(net "DDR4_ACT")
	)
	(via
		(at 41.299892 -142.599918)
		(size 0.4572)
		(drill 0.2032)
		(layers "F.Cu" "B.Cu")
		(net "DDR4_ACT")
	)
	(segment
		(start 32.608266 -140.537692)
		(end 31.999174 -139.9286)
		(width 0.127)
		(layer "In5.Cu")
		(net "DDR4_ACT")
	)
	(segment
		(start 20.577556 -137.432796)
		(end 20.473416 -137.536936)
		(width 0.0889)
		(layer "In5.Cu")
		(net "DDR4_ACT")
	)
	(segment
		(start 20.473416 -137.536936)
		(end 20.473416 -137.684256)
		(width 0.0889)
		(layer "In5.Cu")
		(net "DDR4_ACT")
	)
	(segment
		(start 23.387304 -137.360914)
		(end 23.386796 -137.361422)
		(width 0.0889)
		(layer "In5.Cu")
		(net "DDR4_ACT")
	)
	(segment
		(start 20.203922 -137.917682)
		(end 20.056602 -137.917682)
		(width 0.0889)
		(layer "In5.Cu")
		(net "DDR4_ACT")
	)
	(segment
		(start 39.397686 -142.05712)
		(end 37.878258 -140.537692)
		(width 0.127)
		(layer "In5.Cu")
		(net "DDR4_ACT")
	)
	(segment
		(start 27.609038 -137.54608)
		(end 24.380698 -137.54608)
		(width 0.127)
		(layer "In5.Cu")
		(net "DDR4_ACT")
	)
	(segment
		(start 24.380698 -137.54608)
		(end 24.088344 -137.253726)
		(width 0.127)
		(layer "In5.Cu")
		(net "DDR4_ACT")
	)
	(segment
		(start 37.878258 -140.537692)
		(end 32.608266 -140.537692)
		(width 0.127)
		(layer "In5.Cu")
		(net "DDR4_ACT")
	)
	(segment
		(start 21.694902 -137.361422)
		(end 21.299932 -137.756392)
		(width 0.0889)
		(layer "In5.Cu")
		(net "DDR4_ACT")
	)
	(segment
		(start 20.839684 -138.050524)
		(end 20.839684 -138.197844)
		(width 0.0889)
		(layer "In5.Cu")
		(net "DDR4_ACT")
	)
	(segment
		(start 40.972486 -142.51432)
		(end 40.74033 -142.282164)
		(width 0.127)
		(layer "In5.Cu")
		(net "DDR4_ACT")
	)
	(segment
		(start 20.588224 -138.301984)
		(end 20.203922 -137.917682)
		(width 0.0889)
		(layer "In5.Cu")
		(net "DDR4_ACT")
	)
	(segment
		(start 23.386796 -137.361422)
		(end 21.694902 -137.361422)
		(width 0.0889)
		(layer "In5.Cu")
		(net "DDR4_ACT")
	)
	(segment
		(start 20.473416 -137.684256)
		(end 20.839684 -138.050524)
		(width 0.0889)
		(layer "In5.Cu")
		(net "DDR4_ACT")
	)
	(segment
		(start 31.999174 -139.9286)
		(end 29.991558 -139.9286)
		(width 0.127)
		(layer "In5.Cu")
		(net "DDR4_ACT")
	)
	(segment
		(start 19.882104 -138.09218)
		(end 19.882104 -138.573764)
		(width 0.0889)
		(layer "In5.Cu")
		(net "DDR4_ACT")
	)
	(segment
		(start 20.724876 -137.432796)
		(end 20.577556 -137.432796)
		(width 0.0889)
		(layer "In5.Cu")
		(net "DDR4_ACT")
	)
	(segment
		(start 20.735544 -138.301984)
		(end 20.588224 -138.301984)
		(width 0.0889)
		(layer "In5.Cu")
		(net "DDR4_ACT")
	)
	(segment
		(start 21.299932 -137.756392)
		(end 21.048472 -137.756392)
		(width 0.0889)
		(layer "In5.Cu")
		(net "DDR4_ACT")
	)
	(segment
		(start 24.088344 -137.253726)
		(end 23.494492 -137.253726)
		(width 0.127)
		(layer "In5.Cu")
		(net "DDR4_ACT")
	)
	(segment
		(start 29.991558 -139.9286)
		(end 27.609038 -137.54608)
		(width 0.127)
		(layer "In5.Cu")
		(net "DDR4_ACT")
	)
	(segment
		(start 20.839684 -138.197844)
		(end 20.735544 -138.301984)
		(width 0.0889)
		(layer "In5.Cu")
		(net "DDR4_ACT")
	)
	(segment
		(start 20.056602 -137.917682)
		(end 19.882104 -138.09218)
		(width 0.0889)
		(layer "In5.Cu")
		(net "DDR4_ACT")
	)
	(segment
		(start 41.299892 -142.599918)
		(end 41.179242 -142.599918)
		(width 0.127)
		(layer "In5.Cu")
		(net "DDR4_ACT")
	)
	(segment
		(start 21.048472 -137.756392)
		(end 20.724876 -137.432796)
		(width 0.0889)
		(layer "In5.Cu")
		(net "DDR4_ACT")
	)
	(segment
		(start 23.494492 -137.253726)
		(end 23.387304 -137.360914)
		(width 0.127)
		(layer "In5.Cu")
		(net "DDR4_ACT")
	)
	(arc
		(start 40.15613 -142.231364)
		(mid 39.739214 -142.308444)
		(end 39.397686 -142.05712)
		(width 0.127)
		(layer "In5.Cu")
		(net "DDR4_ACT")
	)
	(arc
		(start 41.179242 -142.599918)
		(mid 41.067363 -142.577664)
		(end 40.972486 -142.51432)
		(width 0.127)
		(layer "In5.Cu")
		(net "DDR4_ACT")
	)
	(arc
		(start 40.628316 -142.201392)
		(mid 40.388187 -142.152585)
		(end 40.15613 -142.231364)
		(width 0.127)
		(layer "In5.Cu")
		(net "DDR4_ACT")
	)
	(arc
		(start 40.74033 -142.282164)
		(mid 40.687556 -142.237296)
		(end 40.628316 -142.201392)
		(width 0.127)
		(layer "In5.Cu")
		(net "DDR4_ACT")
	)
	(segment
		(start 49.299622 -149.799802)
		(end 48.899826 -149.400006)
		(width 0.127)
		(layer "F.Cu")
		(net "DACAV33")
	)
	(segment
		(start 48.899826 -150.200106)
		(end 48.899826 -150.199852)
		(width 0.127)
		(layer "F.Cu")
		(net "DACAV33")
	)
	(segment
		(start 49.299622 -149.800056)
		(end 49.299622 -149.799802)
		(width 0.127)
		(layer "F.Cu")
		(net "DACAV33")
	)
	(segment
		(start 49.299622 -150.599902)
		(end 48.899826 -150.200106)
		(width 0.127)
		(layer "F.Cu")
		(net "DACAV33")
	)
	(via
		(at 49.299622 -150.599902)
		(size 0.4572)
		(drill 0.2032)
		(layers "F.Cu" "B.Cu")
		(net "DACAV33")
	)
	(via
		(at 49.299622 -149.800056)
		(size 0.4572)
		(drill 0.2032)
		(layers "F.Cu" "B.Cu")
		(net "DACAV33")
	)
	(via
		(at 47.052484 -153.226516)
		(size 0.6096)
		(drill 0.3048)
		(layers "F.Cu" "B.Cu")
		(net "DACAV33")
	)
	(segment
		(start 49.299622 -150.599902)
		(end 49.299622 -149.800056)
		(width 0.127)
		(layer "B.Cu")
		(net "DACAV33")
	)
	(segment
		(start 46.77918 -155.25496)
		(end 46.77918 -154.27706)
		(width 0.127)
		(layer "B.Cu")
		(net "DACAV33")
	)
	(segment
		(start 48.26508 -150.99538)
		(end 48.046132 -151.214328)
		(width 0.127)
		(layer "B.Cu")
		(net "DACAV33")
	)
	(segment
		(start 46.7868 -153.4922)
		(end 46.7868 -154.26944)
		(width 0.127)
		(layer "B.Cu")
		(net "DACAV33")
	)
	(segment
		(start 46.77918 -154.27706)
		(end 46.7868 -154.26944)
		(width 0.127)
		(layer "B.Cu")
		(net "DACAV33")
	)
	(segment
		(start 49.041558 -150.777702)
		(end 48.82388 -150.99538)
		(width 0.127)
		(layer "B.Cu")
		(net "DACAV33")
	)
	(segment
		(start 46.77918 -155.25496)
		(end 46.77918 -156.16682)
		(width 0.127)
		(layer "B.Cu")
		(net "DACAV33")
	)
	(segment
		(start 49.121822 -150.777702)
		(end 49.041558 -150.777702)
		(width 0.127)
		(layer "B.Cu")
		(net "DACAV33")
	)
	(segment
		(start 46.96714 -157.99308)
		(end 46.96714 -156.35478)
		(width 0.127)
		(layer "B.Cu")
		(net "DACAV33")
	)
	(segment
		(start 47.052484 -153.226516)
		(end 46.7868 -153.4922)
		(width 0.127)
		(layer "B.Cu")
		(net "DACAV33")
	)
	(segment
		(start 49.299622 -150.599902)
		(end 49.121822 -150.777702)
		(width 0.127)
		(layer "B.Cu")
		(net "DACAV33")
	)
	(segment
		(start 47.30623 -151.95423)
		(end 47.30623 -152.97277)
		(width 0.127)
		(layer "B.Cu")
		(net "DACAV33")
	)
	(segment
		(start 48.046132 -151.265382)
		(end 47.668434 -151.64308)
		(width 0.127)
		(layer "B.Cu")
		(net "DACAV33")
	)
	(segment
		(start 47.668434 -151.64308)
		(end 47.61738 -151.64308)
		(width 0.127)
		(layer "B.Cu")
		(net "DACAV33")
	)
	(segment
		(start 48.046132 -151.214328)
		(end 48.046132 -151.265382)
		(width 0.127)
		(layer "B.Cu")
		(net "DACAV33")
	)
	(segment
		(start 46.77918 -156.16682)
		(end 46.95952 -156.34716)
		(width 0.127)
		(layer "B.Cu")
		(net "DACAV33")
	)
	(segment
		(start 47.61738 -151.64308)
		(end 47.30623 -151.95423)
		(width 0.127)
		(layer "B.Cu")
		(net "DACAV33")
	)
	(segment
		(start 48.82388 -150.99538)
		(end 48.26508 -150.99538)
		(width 0.127)
		(layer "B.Cu")
		(net "DACAV33")
	)
	(segment
		(start 47.30623 -152.97277)
		(end 47.052484 -153.226516)
		(width 0.127)
		(layer "B.Cu")
		(net "DACAV33")
	)
	(segment
		(start 46.96714 -156.35478)
		(end 46.95952 -156.34716)
		(width 0.127)
		(layer "B.Cu")
		(net "DACAV33")
	)
	(segment
		(start 41.699942 -150.999952)
		(end 41.299892 -151.400002)
		(width 0.127)
		(layer "F.Cu")
		(net "COMP_PWR_EN_R")
	)
	(via
		(at 41.299892 -151.400002)
		(size 0.4572)
		(drill 0.2032)
		(layers "F.Cu" "B.Cu")
		(net "COMP_PWR_EN_R")
	)
	(via
		(at 38.65118 -150.73376)
		(size 0.6096)
		(drill 0.3048)
		(layers "F.Cu" "B.Cu")
		(net "COMP_PWR_EN_R")
	)
	(segment
		(start 41.299892 -151.400002)
		(end 40.906192 -151.006302)
		(width 0.127)
		(layer "B.Cu")
		(net "COMP_PWR_EN_R")
	)
	(segment
		(start 38.558216 -150.640796)
		(end 38.65118 -150.73376)
		(width 0.127)
		(layer "B.Cu")
		(net "COMP_PWR_EN_R")
	)
	(segment
		(start 40.906192 -151.006302)
		(end 38.923722 -151.006302)
		(width 0.127)
		(layer "B.Cu")
		(net "COMP_PWR_EN_R")
	)
	(segment
		(start 38.558216 -149.555708)
		(end 38.558216 -150.640796)
		(width 0.127)
		(layer "B.Cu")
		(net "COMP_PWR_EN_R")
	)
	(segment
		(start 38.923722 -151.006302)
		(end 38.65118 -150.73376)
		(width 0.127)
		(layer "B.Cu")
		(net "COMP_PWR_EN_R")
	)
	(via
		(at 69.523356 -159.98698)
		(size 0.508)
		(drill 0.254)
		(layers "F.Cu" "B.Cu")
		(net "COMP_PWR_EN")
	)
	(via
		(at 23.635462 -154.110436)
		(size 0.508)
		(drill 0.254)
		(layers "F.Cu" "B.Cu")
		(net "COMP_PWR_EN")
	)
	(via
		(at 70.370192 -149.97938)
		(size 0.508)
		(drill 0.254)
		(layers "F.Cu" "B.Cu")
		(net "COMP_PWR_EN")
	)
	(via
		(at 37.01034 -151.54656)
		(size 0.6096)
		(drill 0.3048)
		(layers "F.Cu" "B.Cu")
		(net "COMP_PWR_EN")
	)
	(via
		(at 36.181538 -155.375356)
		(size 0.508)
		(drill 0.254)
		(layers "F.Cu" "B.Cu")
		(net "COMP_PWR_EN")
	)
	(via
		(at 99.566222 -147.867116)
		(size 0.508)
		(drill 0.254)
		(layers "F.Cu" "B.Cu")
		(net "COMP_PWR_EN")
	)
	(via
		(at 10.4775 -125.6284)
		(size 0.508)
		(drill 0.254)
		(layers "F.Cu" "B.Cu")
		(net "COMP_PWR_EN")
	)
	(segment
		(start 36.17976 -153.426414)
		(end 36.17976 -153.38044)
		(width 0.127)
		(layer "B.Cu")
		(net "COMP_PWR_EN")
	)
	(segment
		(start 91.42984 -179.61864)
		(end 91.71178 -179.61864)
		(width 0.127)
		(layer "B.Cu")
		(net "COMP_PWR_EN")
	)
	(segment
		(start 29.777436 -127.049784)
		(end 29.94152 -126.8857)
		(width 0.127)
		(layer "B.Cu")
		(net "COMP_PWR_EN")
	)
	(segment
		(start 36.17722 -153.428954)
		(end 36.17976 -153.426414)
		(width 0.127)
		(layer "B.Cu")
		(net "COMP_PWR_EN")
	)
	(segment
		(start 99.500182 -176.3649)
		(end 99.036632 -175.90135)
		(width 0.127)
		(layer "B.Cu")
		(net "COMP_PWR_EN")
	)
	(segment
		(start 91.68638 -176.41824)
		(end 90.91168 -177.19294)
		(width 0.127)
		(layer "B.Cu")
		(net "COMP_PWR_EN")
	)
	(segment
		(start 90.91168 -177.19294)
		(end 90.91168 -179.10048)
		(width 0.127)
		(layer "B.Cu")
		(net "COMP_PWR_EN")
	)
	(segment
		(start 100.482908 -171.398692)
		(end 100.482908 -169.873168)
		(width 0.127)
		(layer "B.Cu")
		(net "COMP_PWR_EN")
	)
	(segment
		(start 15.8623 -126.2126)
		(end 25.74798 -126.2126)
		(width 0.127)
		(layer "B.Cu")
		(net "COMP_PWR_EN")
	)
	(segment
		(start 37.669216 -150.887684)
		(end 37.01034 -151.54656)
		(width 0.127)
		(layer "B.Cu")
		(net "COMP_PWR_EN")
	)
	(segment
		(start 11.0109 -125.095)
		(end 14.7447 -125.095)
		(width 0.127)
		(layer "B.Cu")
		(net "COMP_PWR_EN")
	)
	(segment
		(start 100.282502 -166.696136)
		(end 100.282502 -148.583396)
		(width 0.127)
		(layer "B.Cu")
		(net "COMP_PWR_EN")
	)
	(segment
		(start 100.457 -179.4002)
		(end 100.457 -176.88306)
		(width 0.127)
		(layer "B.Cu")
		(net "COMP_PWR_EN")
	)
	(segment
		(start 36.8173 -152.7429)
		(end 36.8173 -151.7396)
		(width 0.127)
		(layer "B.Cu")
		(net "COMP_PWR_EN")
	)
	(segment
		(start 98.35896 -180.66004)
		(end 97.192846 -181.826154)
		(width 0.127)
		(layer "B.Cu")
		(net "COMP_PWR_EN")
	)
	(segment
		(start 99.036632 -175.90135)
		(end 99.036632 -171.825412)
		(width 0.127)
		(layer "B.Cu")
		(net "COMP_PWR_EN")
	)
	(segment
		(start 99.93884 -176.3649)
		(end 99.500182 -176.3649)
		(width 0.127)
		(layer "B.Cu")
		(net "COMP_PWR_EN")
	)
	(segment
		(start 100.482908 -169.873168)
		(end 100.914454 -169.441622)
		(width 0.127)
		(layer "B.Cu")
		(net "COMP_PWR_EN")
	)
	(segment
		(start 100.457 -176.88306)
		(end 99.93884 -176.3649)
		(width 0.127)
		(layer "B.Cu")
		(net "COMP_PWR_EN")
	)
	(segment
		(start 92.217494 -181.826154)
		(end 91.71178 -181.32044)
		(width 0.127)
		(layer "B.Cu")
		(net "COMP_PWR_EN")
	)
	(segment
		(start 100.914454 -169.441622)
		(end 100.914454 -167.328088)
		(width 0.127)
		(layer "B.Cu")
		(net "COMP_PWR_EN")
	)
	(segment
		(start 90.91168 -179.10048)
		(end 91.42984 -179.61864)
		(width 0.127)
		(layer "B.Cu")
		(net "COMP_PWR_EN")
	)
	(segment
		(start 98.77298 -180.66004)
		(end 99.19716 -180.66004)
		(width 0.127)
		(layer "B.Cu")
		(net "COMP_PWR_EN")
	)
	(segment
		(start 28.585922 -127.049784)
		(end 29.777436 -127.049784)
		(width 0.127)
		(layer "B.Cu")
		(net "COMP_PWR_EN")
	)
	(segment
		(start 36.181538 -155.375356)
		(end 36.17722 -155.371038)
		(width 0.127)
		(layer "B.Cu")
		(net "COMP_PWR_EN")
	)
	(segment
		(start 97.192846 -181.826154)
		(end 92.217494 -181.826154)
		(width 0.127)
		(layer "B.Cu")
		(net "COMP_PWR_EN")
	)
	(segment
		(start 91.71178 -181.32044)
		(end 91.71178 -179.61864)
		(width 0.127)
		(layer "B.Cu")
		(net "COMP_PWR_EN")
	)
	(segment
		(start 99.19716 -180.66004)
		(end 100.457 -179.4002)
		(width 0.127)
		(layer "B.Cu")
		(net "COMP_PWR_EN")
	)
	(segment
		(start 25.74798 -126.2126)
		(end 26.58618 -127.0508)
		(width 0.127)
		(layer "B.Cu")
		(net "COMP_PWR_EN")
	)
	(segment
		(start 100.281232 -171.600368)
		(end 100.482908 -171.398692)
		(width 0.127)
		(layer "B.Cu")
		(net "COMP_PWR_EN")
	)
	(segment
		(start 26.58618 -127.0508)
		(end 28.576016 -127.0508)
		(width 0.127)
		(layer "B.Cu")
		(net "COMP_PWR_EN")
	)
	(segment
		(start 37.669216 -149.555708)
		(end 37.669216 -150.887684)
		(width 0.127)
		(layer "B.Cu")
		(net "COMP_PWR_EN")
	)
	(segment
		(start 28.576016 -127.0508)
		(end 28.585922 -127.049784)
		(width 0.127)
		(layer "B.Cu")
		(net "COMP_PWR_EN")
	)
	(segment
		(start 99.036632 -171.825412)
		(end 99.261676 -171.600368)
		(width 0.127)
		(layer "B.Cu")
		(net "COMP_PWR_EN")
	)
	(segment
		(start 99.261676 -171.600368)
		(end 100.281232 -171.600368)
		(width 0.127)
		(layer "B.Cu")
		(net "COMP_PWR_EN")
	)
	(segment
		(start 36.17976 -153.38044)
		(end 36.8173 -152.7429)
		(width 0.127)
		(layer "B.Cu")
		(net "COMP_PWR_EN")
	)
	(segment
		(start 14.7447 -125.095)
		(end 15.8623 -126.2126)
		(width 0.127)
		(layer "B.Cu")
		(net "COMP_PWR_EN")
	)
	(segment
		(start 100.282502 -148.583396)
		(end 99.566222 -147.867116)
		(width 0.127)
		(layer "B.Cu")
		(net "COMP_PWR_EN")
	)
	(segment
		(start 98.77298 -180.66004)
		(end 98.35896 -180.66004)
		(width 0.127)
		(layer "B.Cu")
		(net "COMP_PWR_EN")
	)
	(segment
		(start 100.914454 -167.328088)
		(end 100.282502 -166.696136)
		(width 0.127)
		(layer "B.Cu")
		(net "COMP_PWR_EN")
	)
	(segment
		(start 36.8173 -151.7396)
		(end 37.01034 -151.54656)
		(width 0.127)
		(layer "B.Cu")
		(net "COMP_PWR_EN")
	)
	(segment
		(start 36.17722 -155.371038)
		(end 36.17722 -153.428954)
		(width 0.127)
		(layer "B.Cu")
		(net "COMP_PWR_EN")
	)
	(segment
		(start 10.4775 -125.6284)
		(end 11.0109 -125.095)
		(width 0.127)
		(layer "B.Cu")
		(net "COMP_PWR_EN")
	)
	(segment
		(start 70.840092 -152.245822)
		(end 72.81799 -154.22372)
		(width 0.127)
		(layer "In2.Cu")
		(net "COMP_PWR_EN")
	)
	(segment
		(start 99.295458 -140.492226)
		(end 99.295458 -142.949676)
		(width 0.127)
		(layer "In2.Cu")
		(net "COMP_PWR_EN")
	)
	(segment
		(start 24.642318 -154.466036)
		(end 24.646382 -154.4701)
		(width 0.127)
		(layer "In2.Cu")
		(net "COMP_PWR_EN")
	)
	(segment
		(start 23.991062 -154.466036)
		(end 24.642318 -154.466036)
		(width 0.127)
		(layer "In2.Cu")
		(net "COMP_PWR_EN")
	)
	(segment
		(start 104.5718 -31.663894)
		(end 104.5718 -40.849804)
		(width 0.127)
		(layer "In2.Cu")
		(net "COMP_PWR_EN")
	)
	(segment
		(start 70.370192 -149.97938)
		(end 70.840092 -150.44928)
		(width 0.127)
		(layer "In2.Cu")
		(net "COMP_PWR_EN")
	)
	(segment
		(start 99.245166 -128.241044)
		(end 99.626166 -128.622044)
		(width 0.127)
		(layer "In2.Cu")
		(net "COMP_PWR_EN")
	)
	(segment
		(start 25.975818 -154.4447)
		(end 26.763218 -154.4447)
		(width 0.127)
		(layer "In2.Cu")
		(net "COMP_PWR_EN")
	)
	(segment
		(start 99.626166 -140.161518)
		(end 99.295458 -140.492226)
		(width 0.127)
		(layer "In2.Cu")
		(net "COMP_PWR_EN")
	)
	(segment
		(start 111.97463 -29.566616)
		(end 106.669078 -29.566616)
		(width 0.127)
		(layer "In2.Cu")
		(net "COMP_PWR_EN")
	)
	(segment
		(start 99.804474 -113.368582)
		(end 99.804474 -123.164854)
		(width 0.127)
		(layer "In2.Cu")
		(net "COMP_PWR_EN")
	)
	(segment
		(start 25.950418 -154.4701)
		(end 25.975818 -154.4447)
		(width 0.127)
		(layer "In2.Cu")
		(net "COMP_PWR_EN")
	)
	(segment
		(start 98.817938 -147.118832)
		(end 99.566222 -147.867116)
		(width 0.127)
		(layer "In2.Cu")
		(net "COMP_PWR_EN")
	)
	(segment
		(start 26.763218 -154.4447)
		(end 27.36088 -155.042362)
		(width 0.127)
		(layer "In2.Cu")
		(net "COMP_PWR_EN")
	)
	(segment
		(start 99.358958 -83.683348)
		(end 99.012502 -84.029804)
		(width 0.127)
		(layer "In2.Cu")
		(net "COMP_PWR_EN")
	)
	(segment
		(start 29.90469 -155.071572)
		(end 35.877754 -155.071572)
		(width 0.127)
		(layer "In2.Cu")
		(net "COMP_PWR_EN")
	)
	(segment
		(start 104.5718 -40.849804)
		(end 99.358958 -46.062646)
		(width 0.127)
		(layer "In2.Cu")
		(net "COMP_PWR_EN")
	)
	(segment
		(start 99.012502 -84.029804)
		(end 99.012502 -112.57661)
		(width 0.127)
		(layer "In2.Cu")
		(net "COMP_PWR_EN")
	)
	(segment
		(start 29.709618 -154.8765)
		(end 29.90469 -155.071572)
		(width 0.127)
		(layer "In2.Cu")
		(net "COMP_PWR_EN")
	)
	(segment
		(start 99.358958 -46.062646)
		(end 99.358958 -83.683348)
		(width 0.127)
		(layer "In2.Cu")
		(net "COMP_PWR_EN")
	)
	(segment
		(start 114.3 -41.800018)
		(end 113.215928 -40.715946)
		(width 0.127)
		(layer "In2.Cu")
		(net "COMP_PWR_EN")
	)
	(segment
		(start 99.804474 -123.164854)
		(end 99.245166 -123.724162)
		(width 0.127)
		(layer "In2.Cu")
		(net "COMP_PWR_EN")
	)
	(segment
		(start 72.81799 -154.223974)
		(end 73.392538 -154.798522)
		(width 0.127)
		(layer "In2.Cu")
		(net "COMP_PWR_EN")
	)
	(segment
		(start 72.81799 -154.22372)
		(end 72.81799 -154.223974)
		(width 0.127)
		(layer "In2.Cu")
		(net "COMP_PWR_EN")
	)
	(segment
		(start 106.669078 -29.566616)
		(end 104.5718 -31.663894)
		(width 0.127)
		(layer "In2.Cu")
		(net "COMP_PWR_EN")
	)
	(segment
		(start 98.817938 -143.427196)
		(end 98.817938 -147.118832)
		(width 0.127)
		(layer "In2.Cu")
		(net "COMP_PWR_EN")
	)
	(segment
		(start 73.392538 -154.798522)
		(end 73.392538 -158.150814)
		(width 0.127)
		(layer "In2.Cu")
		(net "COMP_PWR_EN")
	)
	(segment
		(start 24.646382 -154.4701)
		(end 25.950418 -154.4701)
		(width 0.127)
		(layer "In2.Cu")
		(net "COMP_PWR_EN")
	)
	(segment
		(start 71.556372 -159.98698)
		(end 69.523356 -159.98698)
		(width 0.127)
		(layer "In2.Cu")
		(net "COMP_PWR_EN")
	)
	(segment
		(start 27.36088 -155.042362)
		(end 29.153866 -155.042362)
		(width 0.127)
		(layer "In2.Cu")
		(net "COMP_PWR_EN")
	)
	(segment
		(start 23.635462 -154.110436)
		(end 23.991062 -154.466036)
		(width 0.127)
		(layer "In2.Cu")
		(net "COMP_PWR_EN")
	)
	(segment
		(start 99.295458 -142.949676)
		(end 98.817938 -143.427196)
		(width 0.127)
		(layer "In2.Cu")
		(net "COMP_PWR_EN")
	)
	(segment
		(start 73.392538 -158.150814)
		(end 71.556372 -159.98698)
		(width 0.127)
		(layer "In2.Cu")
		(net "COMP_PWR_EN")
	)
	(segment
		(start 99.012502 -112.57661)
		(end 99.804474 -113.368582)
		(width 0.127)
		(layer "In2.Cu")
		(net "COMP_PWR_EN")
	)
	(segment
		(start 70.840092 -150.44928)
		(end 70.840092 -152.245822)
		(width 0.127)
		(layer "In2.Cu")
		(net "COMP_PWR_EN")
	)
	(segment
		(start 29.319982 -154.8765)
		(end 29.709618 -154.8765)
		(width 0.127)
		(layer "In2.Cu")
		(net "COMP_PWR_EN")
	)
	(segment
		(start 99.626166 -128.622044)
		(end 99.626166 -140.161518)
		(width 0.127)
		(layer "In2.Cu")
		(net "COMP_PWR_EN")
	)
	(segment
		(start 35.877754 -155.071572)
		(end 36.181538 -155.375356)
		(width 0.127)
		(layer "In2.Cu")
		(net "COMP_PWR_EN")
	)
	(segment
		(start 113.215928 -30.807914)
		(end 111.97463 -29.566616)
		(width 0.127)
		(layer "In2.Cu")
		(net "COMP_PWR_EN")
	)
	(segment
		(start 29.153866 -155.042362)
		(end 29.319982 -154.8765)
		(width 0.127)
		(layer "In2.Cu")
		(net "COMP_PWR_EN")
	)
	(segment
		(start 99.245166 -123.724162)
		(end 99.245166 -128.241044)
		(width 0.127)
		(layer "In2.Cu")
		(net "COMP_PWR_EN")
	)
	(segment
		(start 113.215928 -40.715946)
		(end 113.215928 -30.807914)
		(width 0.127)
		(layer "In2.Cu")
		(net "COMP_PWR_EN")
	)
	(segment
		(start 93.38183 -148.163534)
		(end 94.30766 -149.089364)
		(width 0.127)
		(layer "In5.Cu")
		(net "COMP_PWR_EN")
	)
	(segment
		(start 79.4004 -150.533862)
		(end 80.031336 -150.533862)
		(width 0.127)
		(layer "In5.Cu")
		(net "COMP_PWR_EN")
	)
	(segment
		(start 86.841076 -150.178008)
		(end 87.803228 -149.215856)
		(width 0.127)
		(layer "In5.Cu")
		(net "COMP_PWR_EN")
	)
	(segment
		(start 83.852512 -150.178008)
		(end 86.841076 -150.178008)
		(width 0.127)
		(layer "In5.Cu")
		(net "COMP_PWR_EN")
	)
	(segment
		(start 65.969134 -160.507934)
		(end 69.002402 -160.507934)
		(width 0.127)
		(layer "In5.Cu")
		(net "COMP_PWR_EN")
	)
	(segment
		(start 49.155096 -157.41904)
		(end 50.872136 -155.702)
		(width 0.127)
		(layer "In5.Cu")
		(net "COMP_PWR_EN")
	)
	(segment
		(start 94.30766 -149.089364)
		(end 98.343974 -149.089364)
		(width 0.127)
		(layer "In5.Cu")
		(net "COMP_PWR_EN")
	)
	(segment
		(start 62.272164 -157.7594)
		(end 64.202564 -159.6898)
		(width 0.127)
		(layer "In5.Cu")
		(net "COMP_PWR_EN")
	)
	(segment
		(start 64.202564 -159.6898)
		(end 65.151 -159.6898)
		(width 0.127)
		(layer "In5.Cu")
		(net "COMP_PWR_EN")
	)
	(segment
		(start 80.226662 -150.338536)
		(end 83.691984 -150.338536)
		(width 0.127)
		(layer "In5.Cu")
		(net "COMP_PWR_EN")
	)
	(segment
		(start 80.031336 -150.533862)
		(end 80.226662 -150.338536)
		(width 0.127)
		(layer "In5.Cu")
		(net "COMP_PWR_EN")
	)
	(segment
		(start 50.872136 -155.702)
		(end 55.8292 -155.702)
		(width 0.127)
		(layer "In5.Cu")
		(net "COMP_PWR_EN")
	)
	(segment
		(start 12.0523 -148.201888)
		(end 17.960848 -154.110436)
		(width 0.127)
		(layer "In5.Cu")
		(net "COMP_PWR_EN")
	)
	(segment
		(start 70.370192 -149.97938)
		(end 70.987412 -150.5966)
		(width 0.127)
		(layer "In5.Cu")
		(net "COMP_PWR_EN")
	)
	(segment
		(start 87.803228 -149.215856)
		(end 91.136978 -149.215856)
		(width 0.127)
		(layer "In5.Cu")
		(net "COMP_PWR_EN")
	)
	(segment
		(start 36.181538 -155.375356)
		(end 38.225222 -157.41904)
		(width 0.127)
		(layer "In5.Cu")
		(net "COMP_PWR_EN")
	)
	(segment
		(start 12.0523 -131.065524)
		(end 12.0523 -148.201888)
		(width 0.127)
		(layer "In5.Cu")
		(net "COMP_PWR_EN")
	)
	(segment
		(start 77.222096 -150.5966)
		(end 77.834236 -151.20874)
		(width 0.127)
		(layer "In5.Cu")
		(net "COMP_PWR_EN")
	)
	(segment
		(start 98.343974 -149.089364)
		(end 99.566222 -147.867116)
		(width 0.127)
		(layer "In5.Cu")
		(net "COMP_PWR_EN")
	)
	(segment
		(start 92.1893 -148.163534)
		(end 93.38183 -148.163534)
		(width 0.127)
		(layer "In5.Cu")
		(net "COMP_PWR_EN")
	)
	(segment
		(start 10.4775 -129.490724)
		(end 12.0523 -131.065524)
		(width 0.127)
		(layer "In5.Cu")
		(net "COMP_PWR_EN")
	)
	(segment
		(start 70.987412 -150.5966)
		(end 77.222096 -150.5966)
		(width 0.127)
		(layer "In5.Cu")
		(net "COMP_PWR_EN")
	)
	(segment
		(start 69.002402 -160.507934)
		(end 69.523356 -159.98698)
		(width 0.127)
		(layer "In5.Cu")
		(net "COMP_PWR_EN")
	)
	(segment
		(start 65.151 -159.6898)
		(end 65.969134 -160.507934)
		(width 0.127)
		(layer "In5.Cu")
		(net "COMP_PWR_EN")
	)
	(segment
		(start 38.225222 -157.41904)
		(end 49.155096 -157.41904)
		(width 0.127)
		(layer "In5.Cu")
		(net "COMP_PWR_EN")
	)
	(segment
		(start 91.136978 -149.215856)
		(end 92.1893 -148.163534)
		(width 0.127)
		(layer "In5.Cu")
		(net "COMP_PWR_EN")
	)
	(segment
		(start 78.725522 -151.20874)
		(end 79.4004 -150.533862)
		(width 0.127)
		(layer "In5.Cu")
		(net "COMP_PWR_EN")
	)
	(segment
		(start 55.8292 -155.702)
		(end 57.8866 -157.7594)
		(width 0.127)
		(layer "In5.Cu")
		(net "COMP_PWR_EN")
	)
	(segment
		(start 57.8866 -157.7594)
		(end 62.272164 -157.7594)
		(width 0.127)
		(layer "In5.Cu")
		(net "COMP_PWR_EN")
	)
	(segment
		(start 83.691984 -150.338536)
		(end 83.852512 -150.178008)
		(width 0.127)
		(layer "In5.Cu")
		(net "COMP_PWR_EN")
	)
	(segment
		(start 77.834236 -151.20874)
		(end 78.725522 -151.20874)
		(width 0.127)
		(layer "In5.Cu")
		(net "COMP_PWR_EN")
	)
	(segment
		(start 17.960848 -154.110436)
		(end 23.635462 -154.110436)
		(width 0.127)
		(layer "In5.Cu")
		(net "COMP_PWR_EN")
	)
	(segment
		(start 10.4775 -125.6284)
		(end 10.4775 -129.490724)
		(width 0.127)
		(layer "In5.Cu")
		(net "COMP_PWR_EN")
	)
	(segment
		(start 36.0934 -132.9309)
		(end 36.0934 -134.0104)
		(width 0.127)
		(layer "F.Cu")
		(net "CLKIN_24M_BMC")
	)
	(segment
		(start 36.0934 -134.0104)
		(end 36.449 -134.366)
		(width 0.127)
		(layer "F.Cu")
		(net "CLKIN_24M_BMC")
	)
	(segment
		(start 41.3004 -139.400534)
		(end 41.699942 -139.800076)
		(width 0.127)
		(layer "F.Cu")
		(net "CLKIN_24M_BMC")
	)
	(segment
		(start 41.300146 -139.400534)
		(end 41.3004 -139.400534)
		(width 0.127)
		(layer "F.Cu")
		(net "CLKIN_24M_BMC")
	)
	(via
		(at 36.449 -134.366)
		(size 0.508)
		(drill 0.254)
		(layers "F.Cu" "B.Cu")
		(net "CLKIN_24M_BMC")
	)
	(via
		(at 41.300146 -139.400534)
		(size 0.4572)
		(drill 0.2032)
		(layers "F.Cu" "B.Cu")
		(net "CLKIN_24M_BMC")
	)
	(segment
		(start 41.300146 -139.400534)
		(end 40.905684 -139.794996)
		(width 0.127)
		(layer "In2.Cu")
		(net "CLKIN_24M_BMC")
	)
	(segment
		(start 36.926012 -136.875012)
		(end 36.926012 -134.843012)
		(width 0.127)
		(layer "In2.Cu")
		(net "CLKIN_24M_BMC")
	)
	(segment
		(start 36.926012 -134.843012)
		(end 36.449 -134.366)
		(width 0.127)
		(layer "In2.Cu")
		(net "CLKIN_24M_BMC")
	)
	(segment
		(start 39.845996 -139.794996)
		(end 36.926012 -136.875012)
		(width 0.127)
		(layer "In2.Cu")
		(net "CLKIN_24M_BMC")
	)
	(segment
		(start 40.905684 -139.794996)
		(end 39.845996 -139.794996)
		(width 0.127)
		(layer "In2.Cu")
		(net "CLKIN_24M_BMC")
	)
	(segment
		(start 67.7037 -163.322)
		(end 67.7037 -162.8902)
		(width 0.127)
		(layer "F.Cu")
		(net "BMC_TPM_RST_N")
	)
	(segment
		(start 67.7037 -163.322)
		(end 67.7037 -165.5572)
		(width 0.127)
		(layer "F.Cu")
		(net "BMC_TPM_RST_N")
	)
	(segment
		(start 69.5452 -173.482)
		(end 70.5993 -172.4279)
		(width 0.127)
		(layer "F.Cu")
		(net "BMC_TPM_RST_N")
	)
	(segment
		(start 67.7037 -165.5572)
		(end 67.8815 -165.735)
		(width 0.127)
		(layer "F.Cu")
		(net "BMC_TPM_RST_N")
	)
	(segment
		(start 71.7296 -171.3992)
		(end 71.7804 -171.3484)
		(width 0.127)
		(layer "F.Cu")
		(net "BMC_TPM_RST_N")
	)
	(segment
		(start 69.5452 -174.3329)
		(end 69.5452 -173.482)
		(width 0.127)
		(layer "F.Cu")
		(net "BMC_TPM_RST_N")
	)
	(segment
		(start 70.5993 -172.4279)
		(end 70.5993 -171.79544)
		(width 0.127)
		(layer "F.Cu")
		(net "BMC_TPM_RST_N")
	)
	(segment
		(start 67.8815 -165.735)
		(end 68.4911 -166.3446)
		(width 0.127)
		(layer "F.Cu")
		(net "BMC_TPM_RST_N")
	)
	(segment
		(start 68.4911 -166.3446)
		(end 70.8787 -166.3446)
		(width 0.127)
		(layer "F.Cu")
		(net "BMC_TPM_RST_N")
	)
	(segment
		(start 67.7037 -162.8902)
		(end 68.2879 -162.306)
		(width 0.127)
		(layer "F.Cu")
		(net "BMC_TPM_RST_N")
	)
	(segment
		(start 70.99554 -171.3992)
		(end 71.7296 -171.3992)
		(width 0.127)
		(layer "F.Cu")
		(net "BMC_TPM_RST_N")
	)
	(segment
		(start 70.5993 -171.79544)
		(end 70.99554 -171.3992)
		(width 0.127)
		(layer "F.Cu")
		(net "BMC_TPM_RST_N")
	)
	(segment
		(start 72.644 -168.1099)
		(end 72.644 -170.4848)
		(width 0.127)
		(layer "F.Cu")
		(net "BMC_TPM_RST_N")
	)
	(segment
		(start 72.644 -170.4848)
		(end 71.7804 -171.3484)
		(width 0.127)
		(layer "F.Cu")
		(net "BMC_TPM_RST_N")
	)
	(segment
		(start 70.8787 -166.3446)
		(end 72.644 -168.1099)
		(width 0.127)
		(layer "F.Cu")
		(net "BMC_TPM_RST_N")
	)
	(via
		(at 71.7804 -171.3484)
		(size 0.6604)
		(drill 0.3302)
		(layers "F.Cu" "B.Cu")
		(net "BMC_TPM_RST_N")
	)
	(segment
		(start 53.151024 -118.473728)
		(end 53.438552 -118.1862)
		(width 0.127)
		(layer "F.Cu")
		(net "BMC_SPI_MOSI_R")
	)
	(segment
		(start 36.703 -124.333)
		(end 35.539934 -123.169934)
		(width 0.127)
		(layer "F.Cu")
		(net "BMC_SPI_MOSI_R")
	)
	(segment
		(start 33.493456 -118.185946)
		(end 32.05099 -118.185946)
		(width 0.127)
		(layer "F.Cu")
		(net "BMC_SPI_MOSI_R")
	)
	(segment
		(start 53.151024 -118.858284)
		(end 53.151024 -118.473728)
		(width 0.127)
		(layer "F.Cu")
		(net "BMC_SPI_MOSI_R")
	)
	(segment
		(start 35.539934 -120.232424)
		(end 33.493456 -118.185946)
		(width 0.127)
		(layer "F.Cu")
		(net "BMC_SPI_MOSI_R")
	)
	(segment
		(start 35.539934 -123.169934)
		(end 35.539934 -120.232424)
		(width 0.127)
		(layer "F.Cu")
		(net "BMC_SPI_MOSI_R")
	)
	(segment
		(start 53.438552 -118.1862)
		(end 56.012334 -118.1862)
		(width 0.127)
		(layer "F.Cu")
		(net "BMC_SPI_MOSI_R")
	)
	(via
		(at 36.703 -124.333)
		(size 0.508)
		(drill 0.254)
		(layers "F.Cu" "B.Cu")
		(net "BMC_SPI_MOSI_R")
	)
	(via
		(at 43.579034 -123.708414)
		(size 0.6096)
		(drill 0.3048)
		(layers "F.Cu" "B.Cu")
		(net "BMC_SPI_MOSI_R")
	)
	(via
		(at 53.151024 -118.858284)
		(size 0.508)
		(drill 0.254)
		(layers "F.Cu" "B.Cu")
		(net "BMC_SPI_MOSI_R")
	)
	(segment
		(start 53.151024 -118.858284)
		(end 53.151024 -120.813576)
		(width 0.127)
		(layer "B.Cu")
		(net "BMC_SPI_MOSI_R")
	)
	(segment
		(start 36.703 -124.333)
		(end 37.538914 -124.333)
		(width 0.127)
		(layer "B.Cu")
		(net "BMC_SPI_MOSI_R")
	)
	(segment
		(start 48.1838 -121.9708)
		(end 46.446186 -123.708414)
		(width 0.127)
		(layer "B.Cu")
		(net "BMC_SPI_MOSI_R")
	)
	(segment
		(start 36.703 -124.333)
		(end 36.4617 -124.5743)
		(width 0.127)
		(layer "B.Cu")
		(net "BMC_SPI_MOSI_R")
	)
	(segment
		(start 36.87064 -128.3589)
		(end 37.44976 -128.3589)
		(width 0.127)
		(layer "B.Cu")
		(net "BMC_SPI_MOSI_R")
	)
	(segment
		(start 37.631878 -128.176782)
		(end 41.237662 -128.176782)
		(width 0.127)
		(layer "B.Cu")
		(net "BMC_SPI_MOSI_R")
	)
	(segment
		(start 36.4617 -124.5743)
		(end 36.4617 -127.94996)
		(width 0.127)
		(layer "B.Cu")
		(net "BMC_SPI_MOSI_R")
	)
	(segment
		(start 53.151024 -120.813576)
		(end 51.9938 -121.9708)
		(width 0.127)
		(layer "B.Cu")
		(net "BMC_SPI_MOSI_R")
	)
	(segment
		(start 40.015414 -123.708414)
		(end 43.579034 -123.708414)
		(width 0.127)
		(layer "B.Cu")
		(net "BMC_SPI_MOSI_R")
	)
	(segment
		(start 51.9938 -121.9708)
		(end 48.1838 -121.9708)
		(width 0.127)
		(layer "B.Cu")
		(net "BMC_SPI_MOSI_R")
	)
	(segment
		(start 37.538914 -124.333)
		(end 38.667436 -123.204478)
		(width 0.127)
		(layer "B.Cu")
		(net "BMC_SPI_MOSI_R")
	)
	(segment
		(start 38.667436 -123.204478)
		(end 39.511478 -123.204478)
		(width 0.127)
		(layer "B.Cu")
		(net "BMC_SPI_MOSI_R")
	)
	(segment
		(start 39.511478 -123.204478)
		(end 40.015414 -123.708414)
		(width 0.127)
		(layer "B.Cu")
		(net "BMC_SPI_MOSI_R")
	)
	(segment
		(start 37.44976 -128.3589)
		(end 37.631878 -128.176782)
		(width 0.127)
		(layer "B.Cu")
		(net "BMC_SPI_MOSI_R")
	)
	(segment
		(start 41.665652 -128.604772)
		(end 41.665652 -130.578352)
		(width 0.127)
		(layer "B.Cu")
		(net "BMC_SPI_MOSI_R")
	)
	(segment
		(start 41.237662 -128.176782)
		(end 41.665652 -128.604772)
		(width 0.127)
		(layer "B.Cu")
		(net "BMC_SPI_MOSI_R")
	)
	(segment
		(start 46.446186 -123.708414)
		(end 43.579034 -123.708414)
		(width 0.127)
		(layer "B.Cu")
		(net "BMC_SPI_MOSI_R")
	)
	(segment
		(start 36.4617 -127.94996)
		(end 36.87064 -128.3589)
		(width 0.127)
		(layer "B.Cu")
		(net "BMC_SPI_MOSI_R")
	)
	(segment
		(start 41.665652 -130.578352)
		(end 42.418 -131.3307)
		(width 0.127)
		(layer "B.Cu")
		(net "BMC_SPI_MOSI_R")
	)
	(segment
		(start 43.299888 -140.599922)
		(end 42.900092 -140.200126)
		(width 0.127)
		(layer "F.Cu")
		(net "BMC_SPI_MOSI")
	)
	(via
		(at 42.1386 -133.1214)
		(size 0.508)
		(drill 0.254)
		(layers "F.Cu" "B.Cu")
		(net "BMC_SPI_MOSI")
	)
	(via
		(at 42.900092 -140.200126)
		(size 0.4572)
		(drill 0.2032)
		(layers "F.Cu" "B.Cu")
		(net "BMC_SPI_MOSI")
	)
	(segment
		(start 42.418 -132.2197)
		(end 42.418 -132.842)
		(width 0.127)
		(layer "B.Cu")
		(net "BMC_SPI_MOSI")
	)
	(segment
		(start 42.418 -132.842)
		(end 42.1386 -133.1214)
		(width 0.127)
		(layer "B.Cu")
		(net "BMC_SPI_MOSI")
	)
	(segment
		(start 41.3258 -132.2197)
		(end 42.418 -132.2197)
		(width 0.127)
		(layer "B.Cu")
		(net "BMC_SPI_MOSI")
	)
	(segment
		(start 41.706546 -137.963148)
		(end 41.944798 -138.2014)
		(width 0.127)
		(layer "In2.Cu")
		(net "BMC_SPI_MOSI")
	)
	(segment
		(start 41.706546 -134.874254)
		(end 41.706546 -137.963148)
		(width 0.127)
		(layer "In2.Cu")
		(net "BMC_SPI_MOSI")
	)
	(segment
		(start 41.944798 -138.2014)
		(end 42.258742 -138.2014)
		(width 0.127)
		(layer "In2.Cu")
		(net "BMC_SPI_MOSI")
	)
	(segment
		(start 42.1259 -133.1341)
		(end 42.1259 -134.4549)
		(width 0.127)
		(layer "In2.Cu")
		(net "BMC_SPI_MOSI")
	)
	(segment
		(start 42.1259 -134.4549)
		(end 41.706546 -134.874254)
		(width 0.127)
		(layer "In2.Cu")
		(net "BMC_SPI_MOSI")
	)
	(segment
		(start 42.506392 -138.44905)
		(end 42.506392 -139.762992)
		(width 0.127)
		(layer "In2.Cu")
		(net "BMC_SPI_MOSI")
	)
	(segment
		(start 42.900092 -140.156692)
		(end 42.900092 -140.200126)
		(width 0.0889)
		(layer "In2.Cu")
		(net "BMC_SPI_MOSI")
	)
	(segment
		(start 42.258742 -138.2014)
		(end 42.506392 -138.44905)
		(width 0.127)
		(layer "In2.Cu")
		(net "BMC_SPI_MOSI")
	)
	(segment
		(start 42.506392 -139.762992)
		(end 42.900092 -140.156692)
		(width 0.0889)
		(layer "In2.Cu")
		(net "BMC_SPI_MOSI")
	)
	(segment
		(start 42.1386 -133.1214)
		(end 42.1259 -133.1341)
		(width 0.127)
		(layer "In2.Cu")
		(net "BMC_SPI_MOSI")
	)
	(segment
		(start 41.498012 -125.816868)
		(end 41.48709 -125.805946)
		(width 0.127)
		(layer "F.Cu")
		(net "BMC_SPI_MISO_TPM")
	)
	(segment
		(start 43.434254 -125.91034)
		(end 43.340782 -125.816868)
		(width 0.127)
		(layer "F.Cu")
		(net "BMC_SPI_MISO_TPM")
	)
	(segment
		(start 43.340782 -125.816868)
		(end 41.498012 -125.816868)
		(width 0.127)
		(layer "F.Cu")
		(net "BMC_SPI_MISO_TPM")
	)
	(segment
		(start 44.269914 -125.91034)
		(end 43.434254 -125.91034)
		(width 0.127)
		(layer "F.Cu")
		(net "BMC_SPI_MISO_TPM")
	)
	(segment
		(start 63.40856 -125.75032)
		(end 63.41872 -125.75032)
		(width 0.127)
		(layer "F.Cu")
		(net "BMC_SPI_MISO_R")
	)
	(segment
		(start 63.4746 -125.8062)
		(end 65.62725 -125.8062)
		(width 0.127)
		(layer "F.Cu")
		(net "BMC_SPI_MISO_R")
	)
	(segment
		(start 63.41872 -125.75032)
		(end 63.4746 -125.8062)
		(width 0.127)
		(layer "F.Cu")
		(net "BMC_SPI_MISO_R")
	)
	(via
		(at 43.4086 -127)
		(size 0.508)
		(drill 0.254)
		(layers "F.Cu" "B.Cu")
		(net "BMC_SPI_MISO_R")
	)
	(via
		(at 63.40856 -125.75032)
		(size 0.508)
		(drill 0.254)
		(layers "F.Cu" "B.Cu")
		(net "BMC_SPI_MISO_R")
	)
	(segment
		(start 43.3832 -127.7747)
		(end 43.3832 -127.0508)
		(width 0.127)
		(layer "B.Cu")
		(net "BMC_SPI_MISO_R")
	)
	(segment
		(start 43.4086 -127.0254)
		(end 43.4086 -127)
		(width 0.127)
		(layer "B.Cu")
		(net "BMC_SPI_MISO_R")
	)
	(segment
		(start 43.3832 -127.0508)
		(end 43.4086 -127.0254)
		(width 0.127)
		(layer "B.Cu")
		(net "BMC_SPI_MISO_R")
	)
	(segment
		(start 63.331598 -125.827282)
		(end 63.40856 -125.75032)
		(width 0.127)
		(layer "In5.Cu")
		(net "BMC_SPI_MISO_R")
	)
	(segment
		(start 43.9166 -127.508)
		(end 50.927254 -127.508)
		(width 0.127)
		(layer "In5.Cu")
		(net "BMC_SPI_MISO_R")
	)
	(segment
		(start 51.820318 -126.614936)
		(end 54.69763 -126.614936)
		(width 0.127)
		(layer "In5.Cu")
		(net "BMC_SPI_MISO_R")
	)
	(segment
		(start 50.927254 -127.508)
		(end 51.820318 -126.614936)
		(width 0.127)
		(layer "In5.Cu")
		(net "BMC_SPI_MISO_R")
	)
	(segment
		(start 54.69763 -126.614936)
		(end 55.485284 -125.827282)
		(width 0.127)
		(layer "In5.Cu")
		(net "BMC_SPI_MISO_R")
	)
	(segment
		(start 55.485284 -125.827282)
		(end 63.331598 -125.827282)
		(width 0.127)
		(layer "In5.Cu")
		(net "BMC_SPI_MISO_R")
	)
	(segment
		(start 43.4086 -127)
		(end 43.9166 -127.508)
		(width 0.127)
		(layer "In5.Cu")
		(net "BMC_SPI_MISO_R")
	)
	(segment
		(start 45.974508 -127.730758)
		(end 44.216066 -129.4892)
		(width 0.127)
		(layer "F.Cu")
		(net "BMC_SPI_MISO")
	)
	(segment
		(start 44.099988 -139.800076)
		(end 43.699938 -139.400026)
		(width 0.127)
		(layer "F.Cu")
		(net "BMC_SPI_MISO")
	)
	(segment
		(start 45.158914 -125.91034)
		(end 45.974508 -126.725934)
		(width 0.127)
		(layer "F.Cu")
		(net "BMC_SPI_MISO")
	)
	(segment
		(start 45.974508 -126.725934)
		(end 45.974508 -127.730758)
		(width 0.127)
		(layer "F.Cu")
		(net "BMC_SPI_MISO")
	)
	(segment
		(start 44.216066 -129.4892)
		(end 43.3578 -129.4892)
		(width 0.127)
		(layer "F.Cu")
		(net "BMC_SPI_MISO")
	)
	(via
		(at 43.3578 -129.4892)
		(size 0.508)
		(drill 0.254)
		(layers "F.Cu" "B.Cu")
		(net "BMC_SPI_MISO")
	)
	(via
		(at 43.699938 -139.400026)
		(size 0.4572)
		(drill 0.2032)
		(layers "F.Cu" "B.Cu")
		(net "BMC_SPI_MISO")
	)
	(segment
		(start 43.3578 -128.6891)
		(end 43.3578 -129.4892)
		(width 0.127)
		(layer "B.Cu")
		(net "BMC_SPI_MISO")
	)
	(segment
		(start 43.3832 -128.6637)
		(end 43.3578 -128.6891)
		(width 0.127)
		(layer "B.Cu")
		(net "BMC_SPI_MISO")
	)
	(segment
		(start 44.4246 -128.6637)
		(end 43.3832 -128.6637)
		(width 0.127)
		(layer "B.Cu")
		(net "BMC_SPI_MISO")
	)
	(segment
		(start 43.699938 -139.400026)
		(end 44.074588 -139.025376)
		(width 0.0889)
		(layer "In2.Cu")
		(net "BMC_SPI_MISO")
	)
	(segment
		(start 43.7134 -132.56768)
		(end 42.8879 -131.74218)
		(width 0.127)
		(layer "In2.Cu")
		(net "BMC_SPI_MISO")
	)
	(segment
		(start 42.8879 -131.74218)
		(end 42.8879 -130.0099)
		(width 0.127)
		(layer "In2.Cu")
		(net "BMC_SPI_MISO")
	)
	(segment
		(start 44.074588 -137.4394)
		(end 44.074588 -135.158988)
		(width 0.127)
		(layer "In2.Cu")
		(net "BMC_SPI_MISO")
	)
	(segment
		(start 44.074588 -139.025376)
		(end 44.074588 -137.4394)
		(width 0.0889)
		(layer "In2.Cu")
		(net "BMC_SPI_MISO")
	)
	(segment
		(start 44.074588 -135.158988)
		(end 43.7134 -134.7978)
		(width 0.127)
		(layer "In2.Cu")
		(net "BMC_SPI_MISO")
	)
	(segment
		(start 43.3578 -129.54)
		(end 43.3578 -129.4892)
		(width 0.127)
		(layer "In2.Cu")
		(net "BMC_SPI_MISO")
	)
	(segment
		(start 42.8879 -130.0099)
		(end 43.3578 -129.54)
		(width 0.127)
		(layer "In2.Cu")
		(net "BMC_SPI_MISO")
	)
	(segment
		(start 43.7134 -134.7978)
		(end 43.7134 -132.56768)
		(width 0.127)
		(layer "In2.Cu")
		(net "BMC_SPI_MISO")
	)
	(segment
		(start 29.591 -121.158)
		(end 29.591 -117.569488)
		(width 0.127)
		(layer "F.Cu")
		(net "BMC_SPI_CLK_R")
	)
	(segment
		(start 29.591 -117.569488)
		(end 30.244542 -116.915946)
		(width 0.127)
		(layer "F.Cu")
		(net "BMC_SPI_CLK_R")
	)
	(segment
		(start 32.2453 -135.7884)
		(end 31.2928 -135.7884)
		(width 0.127)
		(layer "F.Cu")
		(net "BMC_SPI_CLK_R")
	)
	(segment
		(start 52.201064 -118.424452)
		(end 53.709316 -116.9162)
		(width 0.127)
		(layer "F.Cu")
		(net "BMC_SPI_CLK_R")
	)
	(segment
		(start 53.709316 -116.9162)
		(end 56.012334 -116.9162)
		(width 0.127)
		(layer "F.Cu")
		(net "BMC_SPI_CLK_R")
	)
	(segment
		(start 52.201064 -118.863872)
		(end 52.201064 -118.424452)
		(width 0.127)
		(layer "F.Cu")
		(net "BMC_SPI_CLK_R")
	)
	(segment
		(start 30.244542 -116.915946)
		(end 31.872174 -116.915946)
		(width 0.127)
		(layer "F.Cu")
		(net "BMC_SPI_CLK_R")
	)
	(via
		(at 29.591 -121.158)
		(size 0.508)
		(drill 0.254)
		(layers "F.Cu" "B.Cu")
		(net "BMC_SPI_CLK_R")
	)
	(via
		(at 35.841178 -122.936)
		(size 0.6096)
		(drill 0.3048)
		(layers "F.Cu" "B.Cu")
		(net "BMC_SPI_CLK_R")
	)
	(via
		(at 31.2928 -135.7884)
		(size 0.508)
		(drill 0.254)
		(layers "F.Cu" "B.Cu")
		(net "BMC_SPI_CLK_R")
	)
	(via
		(at 52.201064 -118.863872)
		(size 0.508)
		(drill 0.254)
		(layers "F.Cu" "B.Cu")
		(net "BMC_SPI_CLK_R")
	)
	(segment
		(start 47.973234 -121.4628)
		(end 46.296834 -123.1392)
		(width 0.127)
		(layer "B.Cu")
		(net "BMC_SPI_CLK_R")
	)
	(segment
		(start 52.201064 -118.863872)
		(end 52.4002 -119.063008)
		(width 0.127)
		(layer "B.Cu")
		(net "BMC_SPI_CLK_R")
	)
	(segment
		(start 46.296834 -123.1392)
		(end 40.164766 -123.1392)
		(width 0.127)
		(layer "B.Cu")
		(net "BMC_SPI_CLK_R")
	)
	(segment
		(start 52.4002 -119.063008)
		(end 52.4002 -120.8278)
		(width 0.127)
		(layer "B.Cu")
		(net "BMC_SPI_CLK_R")
	)
	(segment
		(start 38.217348 -122.936)
		(end 35.841178 -122.936)
		(width 0.127)
		(layer "B.Cu")
		(net "BMC_SPI_CLK_R")
	)
	(segment
		(start 30.6324 -122.1994)
		(end 34.0868 -122.1994)
		(width 0.127)
		(layer "B.Cu")
		(net "BMC_SPI_CLK_R")
	)
	(segment
		(start 34.8234 -122.936)
		(end 35.841178 -122.936)
		(width 0.127)
		(layer "B.Cu")
		(net "BMC_SPI_CLK_R")
	)
	(segment
		(start 39.286688 -122.681746)
		(end 39.271956 -122.696478)
		(width 0.127)
		(layer "B.Cu")
		(net "BMC_SPI_CLK_R")
	)
	(segment
		(start 39.707312 -122.681746)
		(end 39.286688 -122.681746)
		(width 0.127)
		(layer "B.Cu")
		(net "BMC_SPI_CLK_R")
	)
	(segment
		(start 52.4002 -120.8278)
		(end 51.7652 -121.4628)
		(width 0.127)
		(layer "B.Cu")
		(net "BMC_SPI_CLK_R")
	)
	(segment
		(start 34.0868 -122.1994)
		(end 34.8234 -122.936)
		(width 0.127)
		(layer "B.Cu")
		(net "BMC_SPI_CLK_R")
	)
	(segment
		(start 29.591 -121.158)
		(end 30.6324 -122.1994)
		(width 0.127)
		(layer "B.Cu")
		(net "BMC_SPI_CLK_R")
	)
	(segment
		(start 39.271956 -122.696478)
		(end 38.45687 -122.696478)
		(width 0.127)
		(layer "B.Cu")
		(net "BMC_SPI_CLK_R")
	)
	(segment
		(start 51.7652 -121.4628)
		(end 47.973234 -121.4628)
		(width 0.127)
		(layer "B.Cu")
		(net "BMC_SPI_CLK_R")
	)
	(segment
		(start 38.45687 -122.696478)
		(end 38.217348 -122.936)
		(width 0.127)
		(layer "B.Cu")
		(net "BMC_SPI_CLK_R")
	)
	(segment
		(start 40.164766 -123.1392)
		(end 39.707312 -122.681746)
		(width 0.127)
		(layer "B.Cu")
		(net "BMC_SPI_CLK_R")
	)
	(segment
		(start 31.2928 -135.7122)
		(end 31.2928 -135.7884)
		(width 0.127)
		(layer "In2.Cu")
		(net "BMC_SPI_CLK_R")
	)
	(segment
		(start 29.591 -134.0104)
		(end 31.2928 -135.7122)
		(width 0.127)
		(layer "In2.Cu")
		(net "BMC_SPI_CLK_R")
	)
	(segment
		(start 29.591 -128.17729)
		(end 29.591 -134.0104)
		(width 0.127)
		(layer "In2.Cu")
		(net "BMC_SPI_CLK_R")
	)
	(segment
		(start 30.607 -127.16129)
		(end 29.591 -128.17729)
		(width 0.127)
		(layer "In2.Cu")
		(net "BMC_SPI_CLK_R")
	)
	(segment
		(start 29.591 -121.158)
		(end 30.607 -122.174)
		(width 0.127)
		(layer "In2.Cu")
		(net "BMC_SPI_CLK_R")
	)
	(segment
		(start 30.607 -122.174)
		(end 30.607 -127.16129)
		(width 0.127)
		(layer "In2.Cu")
		(net "BMC_SPI_CLK_R")
	)
	(segment
		(start 33.723834 -134.6962)
		(end 34.181034 -135.1534)
		(width 0.127)
		(layer "F.Cu")
		(net "BMC_SPI_CLK")
	)
	(segment
		(start 34.181034 -135.1534)
		(end 35.41649 -135.1534)
		(width 0.127)
		(layer "F.Cu")
		(net "BMC_SPI_CLK")
	)
	(segment
		(start 36.212018 -137.758424)
		(end 36.833048 -138.379454)
		(width 0.127)
		(layer "F.Cu")
		(net "BMC_SPI_CLK")
	)
	(segment
		(start 39.467282 -139.3952)
		(end 39.872158 -139.800076)
		(width 0.127)
		(layer "F.Cu")
		(net "BMC_SPI_CLK")
	)
	(segment
		(start 39.872158 -139.800076)
		(end 40.099996 -139.800076)
		(width 0.127)
		(layer "F.Cu")
		(net "BMC_SPI_CLK")
	)
	(segment
		(start 33.1343 -134.6962)
		(end 33.723834 -134.6962)
		(width 0.127)
		(layer "F.Cu")
		(net "BMC_SPI_CLK")
	)
	(segment
		(start 35.41649 -135.1534)
		(end 36.212018 -135.948928)
		(width 0.127)
		(layer "F.Cu")
		(net "BMC_SPI_CLK")
	)
	(segment
		(start 36.212018 -135.948928)
		(end 36.212018 -137.758424)
		(width 0.127)
		(layer "F.Cu")
		(net "BMC_SPI_CLK")
	)
	(segment
		(start 39.191438 -139.3952)
		(end 39.467282 -139.3952)
		(width 0.127)
		(layer "F.Cu")
		(net "BMC_SPI_CLK")
	)
	(segment
		(start 33.1343 -135.7884)
		(end 33.1343 -134.6962)
		(width 0.127)
		(layer "F.Cu")
		(net "BMC_SPI_CLK")
	)
	(segment
		(start 37.457126 -139.003532)
		(end 38.79977 -139.003532)
		(width 0.127)
		(layer "F.Cu")
		(net "BMC_SPI_CLK")
	)
	(segment
		(start 36.833048 -138.379454)
		(end 37.457126 -139.003532)
		(width 0.127)
		(layer "F.Cu")
		(net "BMC_SPI_CLK")
	)
	(segment
		(start 38.79977 -139.003532)
		(end 39.191438 -139.3952)
		(width 0.127)
		(layer "F.Cu")
		(net "BMC_SPI_CLK")
	)
	(via
		(at 36.833048 -138.379454)
		(size 0.6604)
		(drill 0.3302)
		(layers "F.Cu" "B.Cu")
		(net "BMC_SPI_CLK")
	)
	(segment
		(start 54.899814 -152.199848)
		(end 54.500018 -152.599644)
		(width 0.127)
		(layer "F.Cu")
		(net "BMC_RGMII_C2_C3_D1_D2_E6")
	)
	(segment
		(start 54.500018 -151.800052)
		(end 54.899814 -152.199848)
		(width 0.127)
		(layer "F.Cu")
		(net "BMC_RGMII_C2_C3_D1_D2_E6")
	)
	(segment
		(start 53.699918 -152.599898)
		(end 54.500018 -152.599898)
		(width 0.127)
		(layer "F.Cu")
		(net "BMC_RGMII_C2_C3_D1_D2_E6")
	)
	(segment
		(start 52.500022 -149.799802)
		(end 52.899818 -149.400006)
		(width 0.127)
		(layer "F.Cu")
		(net "BMC_RGMII_C2_C3_D1_D2_E6")
	)
	(segment
		(start 52.499768 -149.799802)
		(end 52.500022 -149.799802)
		(width 0.127)
		(layer "F.Cu")
		(net "BMC_RGMII_C2_C3_D1_D2_E6")
	)
	(segment
		(start 53.699918 -153.399998)
		(end 53.699918 -152.599898)
		(width 0.127)
		(layer "F.Cu")
		(net "BMC_RGMII_C2_C3_D1_D2_E6")
	)
	(segment
		(start 54.500018 -152.599644)
		(end 54.500018 -152.599898)
		(width 0.127)
		(layer "F.Cu")
		(net "BMC_RGMII_C2_C3_D1_D2_E6")
	)
	(via
		(at 54.899814 -152.199848)
		(size 0.4572)
		(drill 0.2032)
		(layers "F.Cu" "B.Cu")
		(net "BMC_RGMII_C2_C3_D1_D2_E6")
	)
	(via
		(at 55.617872 -152.56129)
		(size 0.6096)
		(drill 0.3048)
		(layers "F.Cu" "B.Cu")
		(net "BMC_RGMII_C2_C3_D1_D2_E6")
	)
	(via
		(at 52.499768 -149.799802)
		(size 0.4572)
		(drill 0.2032)
		(layers "F.Cu" "B.Cu")
		(net "BMC_RGMII_C2_C3_D1_D2_E6")
	)
	(segment
		(start 54.262782 -151.806148)
		(end 53.450236 -150.993602)
		(width 0.127)
		(layer "B.Cu")
		(net "BMC_RGMII_C2_C3_D1_D2_E6")
	)
	(segment
		(start 55.25643 -152.199848)
		(end 55.617872 -152.56129)
		(width 0.127)
		(layer "B.Cu")
		(net "BMC_RGMII_C2_C3_D1_D2_E6")
	)
	(segment
		(start 54.441852 -151.819864)
		(end 54.428136 -151.806148)
		(width 0.127)
		(layer "B.Cu")
		(net "BMC_RGMII_C2_C3_D1_D2_E6")
	)
	(segment
		(start 52.499768 -149.908768)
		(end 52.499768 -149.799802)
		(width 0.127)
		(layer "B.Cu")
		(net "BMC_RGMII_C2_C3_D1_D2_E6")
	)
	(segment
		(start 52.905914 -150.314914)
		(end 52.499768 -149.908768)
		(width 0.127)
		(layer "B.Cu")
		(net "BMC_RGMII_C2_C3_D1_D2_E6")
	)
	(segment
		(start 61.07684 -154.45994)
		(end 61.9506 -154.45994)
		(width 0.127)
		(layer "B.Cu")
		(net "BMC_RGMII_C2_C3_D1_D2_E6")
	)
	(segment
		(start 53.450236 -150.993602)
		(end 53.136292 -150.993602)
		(width 0.127)
		(layer "B.Cu")
		(net "BMC_RGMII_C2_C3_D1_D2_E6")
	)
	(segment
		(start 53.136292 -150.993602)
		(end 52.905914 -150.763224)
		(width 0.127)
		(layer "B.Cu")
		(net "BMC_RGMII_C2_C3_D1_D2_E6")
	)
	(segment
		(start 58.258964 -153.5176)
		(end 58.551064 -153.8097)
		(width 0.127)
		(layer "B.Cu")
		(net "BMC_RGMII_C2_C3_D1_D2_E6")
	)
	(segment
		(start 54.899814 -152.199848)
		(end 54.51983 -151.819864)
		(width 0.127)
		(layer "B.Cu")
		(net "BMC_RGMII_C2_C3_D1_D2_E6")
	)
	(segment
		(start 58.763662 -153.8097)
		(end 59.492642 -154.53868)
		(width 0.127)
		(layer "B.Cu")
		(net "BMC_RGMII_C2_C3_D1_D2_E6")
	)
	(segment
		(start 56.30037 -152.56129)
		(end 57.25668 -153.5176)
		(width 0.127)
		(layer "B.Cu")
		(net "BMC_RGMII_C2_C3_D1_D2_E6")
	)
	(segment
		(start 54.428136 -151.806148)
		(end 54.262782 -151.806148)
		(width 0.127)
		(layer "B.Cu")
		(net "BMC_RGMII_C2_C3_D1_D2_E6")
	)
	(segment
		(start 60.9981 -154.53868)
		(end 61.07684 -154.45994)
		(width 0.127)
		(layer "B.Cu")
		(net "BMC_RGMII_C2_C3_D1_D2_E6")
	)
	(segment
		(start 54.899814 -152.199848)
		(end 55.25643 -152.199848)
		(width 0.127)
		(layer "B.Cu")
		(net "BMC_RGMII_C2_C3_D1_D2_E6")
	)
	(segment
		(start 59.492642 -154.53868)
		(end 60.9981 -154.53868)
		(width 0.127)
		(layer "B.Cu")
		(net "BMC_RGMII_C2_C3_D1_D2_E6")
	)
	(segment
		(start 57.25668 -153.5176)
		(end 58.258964 -153.5176)
		(width 0.127)
		(layer "B.Cu")
		(net "BMC_RGMII_C2_C3_D1_D2_E6")
	)
	(segment
		(start 58.551064 -153.8097)
		(end 58.763662 -153.8097)
		(width 0.127)
		(layer "B.Cu")
		(net "BMC_RGMII_C2_C3_D1_D2_E6")
	)
	(segment
		(start 54.51983 -151.819864)
		(end 54.441852 -151.819864)
		(width 0.127)
		(layer "B.Cu")
		(net "BMC_RGMII_C2_C3_D1_D2_E6")
	)
	(segment
		(start 61.9506 -154.45994)
		(end 62.4205 -153.99004)
		(width 0.127)
		(layer "B.Cu")
		(net "BMC_RGMII_C2_C3_D1_D2_E6")
	)
	(segment
		(start 52.905914 -150.763224)
		(end 52.905914 -150.314914)
		(width 0.127)
		(layer "B.Cu")
		(net "BMC_RGMII_C2_C3_D1_D2_E6")
	)
	(segment
		(start 55.617872 -152.56129)
		(end 56.30037 -152.56129)
		(width 0.127)
		(layer "B.Cu")
		(net "BMC_RGMII_C2_C3_D1_D2_E6")
	)
	(segment
		(start 54.099968 -153.000202)
		(end 54.499764 -153.399998)
		(width 0.127)
		(layer "F.Cu")
		(net "BMC_RGMII_A4_D3")
	)
	(segment
		(start 55.157624 -150.657052)
		(end 55.442104 -150.657052)
		(width 0.127)
		(layer "F.Cu")
		(net "BMC_RGMII_A4_D3")
	)
	(segment
		(start 54.657752 -151.422354)
		(end 54.956964 -151.123142)
		(width 0.127)
		(layer "F.Cu")
		(net "BMC_RGMII_A4_D3")
	)
	(segment
		(start 54.956964 -150.857712)
		(end 55.157624 -150.657052)
		(width 0.127)
		(layer "F.Cu")
		(net "BMC_RGMII_A4_D3")
	)
	(segment
		(start 55.785004 -150.999952)
		(end 56.099964 -150.999952)
		(width 0.127)
		(layer "F.Cu")
		(net "BMC_RGMII_A4_D3")
	)
	(segment
		(start 54.099714 -152.199848)
		(end 53.699918 -151.800052)
		(width 0.127)
		(layer "F.Cu")
		(net "BMC_RGMII_A4_D3")
	)
	(segment
		(start 55.442104 -150.657052)
		(end 55.785004 -150.999952)
		(width 0.127)
		(layer "F.Cu")
		(net "BMC_RGMII_A4_D3")
	)
	(segment
		(start 54.07787 -151.422354)
		(end 54.657752 -151.422354)
		(width 0.127)
		(layer "F.Cu")
		(net "BMC_RGMII_A4_D3")
	)
	(segment
		(start 54.499764 -153.399998)
		(end 54.500018 -153.399998)
		(width 0.127)
		(layer "F.Cu")
		(net "BMC_RGMII_A4_D3")
	)
	(segment
		(start 54.956964 -151.123142)
		(end 54.956964 -150.857712)
		(width 0.127)
		(layer "F.Cu")
		(net "BMC_RGMII_A4_D3")
	)
	(segment
		(start 53.699918 -151.800052)
		(end 53.700172 -151.800052)
		(width 0.127)
		(layer "F.Cu")
		(net "BMC_RGMII_A4_D3")
	)
	(segment
		(start 53.700172 -151.800052)
		(end 54.07787 -151.422354)
		(width 0.127)
		(layer "F.Cu")
		(net "BMC_RGMII_A4_D3")
	)
	(via
		(at 54.099714 -152.199848)
		(size 0.4572)
		(drill 0.2032)
		(layers "F.Cu" "B.Cu")
		(net "BMC_RGMII_A4_D3")
	)
	(via
		(at 57.8866 -154.1526)
		(size 0.6096)
		(drill 0.3048)
		(layers "F.Cu" "B.Cu")
		(net "BMC_RGMII_A4_D3")
	)
	(via
		(at 54.099968 -153.000202)
		(size 0.4572)
		(drill 0.2032)
		(layers "F.Cu" "B.Cu")
		(net "BMC_RGMII_A4_D3")
	)
	(segment
		(start 55.118762 -153.000202)
		(end 55.26024 -153.14168)
		(width 0.127)
		(layer "B.Cu")
		(net "BMC_RGMII_A4_D3")
	)
	(segment
		(start 56.51754 -153.14168)
		(end 57.52846 -154.1526)
		(width 0.127)
		(layer "B.Cu")
		(net "BMC_RGMII_A4_D3")
	)
	(segment
		(start 54.099714 -152.199848)
		(end 54.099968 -152.200102)
		(width 0.127)
		(layer "B.Cu")
		(net "BMC_RGMII_A4_D3")
	)
	(segment
		(start 58.6994 -154.1526)
		(end 57.8866 -154.1526)
		(width 0.127)
		(layer "B.Cu")
		(net "BMC_RGMII_A4_D3")
	)
	(segment
		(start 59.70524 -155.15844)
		(end 58.6994 -154.1526)
		(width 0.127)
		(layer "B.Cu")
		(net "BMC_RGMII_A4_D3")
	)
	(segment
		(start 60.4774 -155.15844)
		(end 59.70524 -155.15844)
		(width 0.127)
		(layer "B.Cu")
		(net "BMC_RGMII_A4_D3")
	)
	(segment
		(start 54.099968 -152.200102)
		(end 54.099968 -153.000202)
		(width 0.127)
		(layer "B.Cu")
		(net "BMC_RGMII_A4_D3")
	)
	(segment
		(start 57.52846 -154.1526)
		(end 57.8866 -154.1526)
		(width 0.127)
		(layer "B.Cu")
		(net "BMC_RGMII_A4_D3")
	)
	(segment
		(start 55.26024 -153.14168)
		(end 56.51754 -153.14168)
		(width 0.127)
		(layer "B.Cu")
		(net "BMC_RGMII_A4_D3")
	)
	(segment
		(start 54.099968 -153.000202)
		(end 55.118762 -153.000202)
		(width 0.127)
		(layer "B.Cu")
		(net "BMC_RGMII_A4_D3")
	)
	(segment
		(start 26.021792 -128.867408)
		(end 26.0858 -128.8034)
		(width 0.127)
		(layer "F.Cu")
		(net "BMC_HBLED")
	)
	(segment
		(start 23.777956 -128.867408)
		(end 26.021792 -128.867408)
		(width 0.127)
		(layer "F.Cu")
		(net "BMC_HBLED")
	)
	(segment
		(start 40.500046 -139.400534)
		(end 40.5003 -139.400534)
		(width 0.127)
		(layer "F.Cu")
		(net "BMC_HBLED")
	)
	(segment
		(start 40.5003 -139.400534)
		(end 40.899842 -139.800076)
		(width 0.127)
		(layer "F.Cu")
		(net "BMC_HBLED")
	)
	(via
		(at 26.0858 -128.8034)
		(size 0.508)
		(drill 0.254)
		(layers "F.Cu" "B.Cu")
		(net "BMC_HBLED")
	)
	(via
		(at 40.500046 -139.400534)
		(size 0.4572)
		(drill 0.2032)
		(layers "F.Cu" "B.Cu")
		(net "BMC_HBLED")
	)
	(via
		(at 37.952426 -136.056116)
		(size 0.508)
		(drill 0.254)
		(layers "F.Cu" "B.Cu")
		(net "BMC_HBLED")
	)
	(segment
		(start 39.536624 -138.994134)
		(end 39.831264 -138.994134)
		(width 0.127)
		(layer "In2.Cu")
		(net "BMC_HBLED")
	)
	(segment
		(start 37.952426 -137.409936)
		(end 39.536624 -138.994134)
		(width 0.127)
		(layer "In2.Cu")
		(net "BMC_HBLED")
	)
	(segment
		(start 40.237664 -139.400534)
		(end 40.500046 -139.400534)
		(width 0.127)
		(layer "In2.Cu")
		(net "BMC_HBLED")
	)
	(segment
		(start 39.831264 -138.994134)
		(end 40.237664 -139.400534)
		(width 0.127)
		(layer "In2.Cu")
		(net "BMC_HBLED")
	)
	(segment
		(start 37.952426 -136.056116)
		(end 37.952426 -137.409936)
		(width 0.127)
		(layer "In2.Cu")
		(net "BMC_HBLED")
	)
	(segment
		(start 34.7472 -134.239)
		(end 34.2773 -133.7691)
		(width 0.127)
		(layer "In5.Cu")
		(net "BMC_HBLED")
	)
	(segment
		(start 35.554412 -134.239)
		(end 34.7472 -134.239)
		(width 0.127)
		(layer "In5.Cu")
		(net "BMC_HBLED")
	)
	(segment
		(start 26.206196 -128.923796)
		(end 26.0858 -128.8034)
		(width 0.127)
		(layer "In5.Cu")
		(net "BMC_HBLED")
	)
	(segment
		(start 37.371528 -136.056116)
		(end 35.554412 -134.239)
		(width 0.127)
		(layer "In5.Cu")
		(net "BMC_HBLED")
	)
	(segment
		(start 33.1597 -133.7691)
		(end 28.314396 -128.923796)
		(width 0.127)
		(layer "In5.Cu")
		(net "BMC_HBLED")
	)
	(segment
		(start 28.314396 -128.923796)
		(end 26.206196 -128.923796)
		(width 0.127)
		(layer "In5.Cu")
		(net "BMC_HBLED")
	)
	(segment
		(start 37.952426 -136.056116)
		(end 37.371528 -136.056116)
		(width 0.127)
		(layer "In5.Cu")
		(net "BMC_HBLED")
	)
	(segment
		(start 34.2773 -133.7691)
		(end 33.1597 -133.7691)
		(width 0.127)
		(layer "In5.Cu")
		(net "BMC_HBLED")
	)
	(segment
		(start 41.699942 -137.40003)
		(end 41.32453 -137.024618)
		(width 0.127)
		(layer "F.Cu")
		(net "BMC_GPIOZ7")
	)
	(segment
		(start 39.721536 -134.3533)
		(end 39.374064 -134.3533)
		(width 0.127)
		(layer "F.Cu")
		(net "BMC_GPIOZ7")
	)
	(segment
		(start 39.36746 -134.359904)
		(end 38.044882 -134.359904)
		(width 0.127)
		(layer "F.Cu")
		(net "BMC_GPIOZ7")
	)
	(segment
		(start 37.6936 -132.8674)
		(end 37.112448 -132.286248)
		(width 0.127)
		(layer "F.Cu")
		(net "BMC_GPIOZ7")
	)
	(segment
		(start 38.044882 -134.359904)
		(end 37.6936 -134.008622)
		(width 0.127)
		(layer "F.Cu")
		(net "BMC_GPIOZ7")
	)
	(segment
		(start 41.32453 -136.395714)
		(end 40.05453 -135.125714)
		(width 0.127)
		(layer "F.Cu")
		(net "BMC_GPIOZ7")
	)
	(segment
		(start 37.112448 -132.286248)
		(end 37.112448 -131.203192)
		(width 0.127)
		(layer "F.Cu")
		(net "BMC_GPIOZ7")
	)
	(segment
		(start 37.6936 -134.008622)
		(end 37.6936 -132.8674)
		(width 0.127)
		(layer "F.Cu")
		(net "BMC_GPIOZ7")
	)
	(segment
		(start 40.05453 -134.686294)
		(end 39.721536 -134.3533)
		(width 0.127)
		(layer "F.Cu")
		(net "BMC_GPIOZ7")
	)
	(segment
		(start 39.374064 -134.3533)
		(end 39.36746 -134.359904)
		(width 0.127)
		(layer "F.Cu")
		(net "BMC_GPIOZ7")
	)
	(segment
		(start 41.32453 -137.024618)
		(end 41.32453 -136.395714)
		(width 0.127)
		(layer "F.Cu")
		(net "BMC_GPIOZ7")
	)
	(segment
		(start 40.05453 -135.125714)
		(end 40.05453 -134.686294)
		(width 0.127)
		(layer "F.Cu")
		(net "BMC_GPIOZ7")
	)
	(segment
		(start 39.807134 -132.771134)
		(end 40.1574 -133.1214)
		(width 0.127)
		(layer "F.Cu")
		(net "BMC_GPIOZ6")
	)
	(segment
		(start 40.903144 -134.298944)
		(end 40.903144 -134.773162)
		(width 0.127)
		(layer "F.Cu")
		(net "BMC_GPIOZ6")
	)
	(segment
		(start 40.1574 -133.5532)
		(end 40.903144 -134.298944)
		(width 0.127)
		(layer "F.Cu")
		(net "BMC_GPIOZ6")
	)
	(segment
		(start 40.903144 -134.773162)
		(end 42.500042 -136.37006)
		(width 0.127)
		(layer "F.Cu")
		(net "BMC_GPIOZ6")
	)
	(segment
		(start 40.1574 -133.1214)
		(end 40.1574 -133.5532)
		(width 0.127)
		(layer "F.Cu")
		(net "BMC_GPIOZ6")
	)
	(segment
		(start 42.500042 -136.37006)
		(end 42.500042 -136.59993)
		(width 0.127)
		(layer "F.Cu")
		(net "BMC_GPIOZ6")
	)
	(segment
		(start 39.807134 -132.141468)
		(end 39.807134 -132.771134)
		(width 0.127)
		(layer "F.Cu")
		(net "BMC_GPIOZ6")
	)
	(via
		(at 40.1574 -133.1214)
		(size 0.6604)
		(drill 0.3302)
		(layers "F.Cu" "B.Cu")
		(net "BMC_GPIOZ6")
	)
	(segment
		(start 39.752778 -134.0612)
		(end 39.290244 -134.0612)
		(width 0.127)
		(layer "F.Cu")
		(net "BMC_GPIOZ5")
	)
	(segment
		(start 40.382952 -134.691374)
		(end 39.752778 -134.0612)
		(width 0.127)
		(layer "F.Cu")
		(net "BMC_GPIOZ5")
	)
	(segment
		(start 40.382952 -134.982966)
		(end 40.382952 -134.691374)
		(width 0.127)
		(layer "F.Cu")
		(net "BMC_GPIOZ5")
	)
	(segment
		(start 38.128448 -131.203192)
		(end 38.128448 -131.295648)
		(width 0.127)
		(layer "F.Cu")
		(net "BMC_GPIOZ5")
	)
	(segment
		(start 38.480746 -133.233922)
		(end 39.068248 -133.821424)
		(width 0.127)
		(layer "F.Cu")
		(net "BMC_GPIOZ5")
	)
	(segment
		(start 38.480746 -131.647946)
		(end 38.480746 -133.233922)
		(width 0.127)
		(layer "F.Cu")
		(net "BMC_GPIOZ5")
	)
	(segment
		(start 38.128448 -131.295648)
		(end 38.480746 -131.647946)
		(width 0.127)
		(layer "F.Cu")
		(net "BMC_GPIOZ5")
	)
	(segment
		(start 39.290244 -134.0612)
		(end 39.068248 -133.839204)
		(width 0.127)
		(layer "F.Cu")
		(net "BMC_GPIOZ5")
	)
	(segment
		(start 41.699942 -136.299956)
		(end 40.382952 -134.982966)
		(width 0.127)
		(layer "F.Cu")
		(net "BMC_GPIOZ5")
	)
	(segment
		(start 39.068248 -133.821424)
		(end 39.068248 -133.839204)
		(width 0.127)
		(layer "F.Cu")
		(net "BMC_GPIOZ5")
	)
	(segment
		(start 41.699942 -136.59993)
		(end 41.699942 -136.299956)
		(width 0.127)
		(layer "F.Cu")
		(net "BMC_GPIOZ5")
	)
	(via
		(at 39.068248 -133.839204)
		(size 0.6604)
		(drill 0.3302)
		(layers "F.Cu" "B.Cu")
		(net "BMC_GPIOZ5")
	)
	(segment
		(start 40.700198 -132.891784)
		(end 40.7035 -132.895086)
		(width 0.127)
		(layer "F.Cu")
		(net "BMC_GPIOZ4")
	)
	(segment
		(start 42.8752 -136.420352)
		(end 42.8752 -136.975342)
		(width 0.127)
		(layer "F.Cu")
		(net "BMC_GPIOZ4")
	)
	(segment
		(start 40.824658 -132.149088)
		(end 40.824658 -132.767324)
		(width 0.127)
		(layer "F.Cu")
		(net "BMC_GPIOZ4")
	)
	(segment
		(start 41.721024 -135.266176)
		(end 42.8752 -136.420352)
		(width 0.127)
		(layer "F.Cu")
		(net "BMC_GPIOZ4")
	)
	(segment
		(start 41.721024 -134.380224)
		(end 41.721024 -135.266176)
		(width 0.127)
		(layer "F.Cu")
		(net "BMC_GPIOZ4")
	)
	(segment
		(start 41.3512 -134.0104)
		(end 41.721024 -134.380224)
		(width 0.127)
		(layer "F.Cu")
		(net "BMC_GPIOZ4")
	)
	(segment
		(start 40.824658 -132.767324)
		(end 40.700198 -132.891784)
		(width 0.127)
		(layer "F.Cu")
		(net "BMC_GPIOZ4")
	)
	(segment
		(start 40.7035 -132.895086)
		(end 40.7035 -133.3627)
		(width 0.127)
		(layer "F.Cu")
		(net "BMC_GPIOZ4")
	)
	(segment
		(start 42.8752 -136.975342)
		(end 43.299888 -137.40003)
		(width 0.127)
		(layer "F.Cu")
		(net "BMC_GPIOZ4")
	)
	(segment
		(start 40.7035 -133.3627)
		(end 41.3512 -134.0104)
		(width 0.127)
		(layer "F.Cu")
		(net "BMC_GPIOZ4")
	)
	(via
		(at 41.3512 -134.0104)
		(size 0.6604)
		(drill 0.3302)
		(layers "F.Cu" "B.Cu")
		(net "BMC_GPIOZ4")
	)
	(segment
		(start 46.099984 -137.80008)
		(end 45.699934 -137.40003)
		(width 0.127)
		(layer "F.Cu")
		(net "BMC_GPIOY3")
	)
	(segment
		(start 46.449996 -132.192014)
		(end 46.449996 -132.99186)
		(width 0.127)
		(layer "F.Cu")
		(net "BMC_GPIOY3")
	)
	(via
		(at 46.449996 -132.99186)
		(size 0.508)
		(drill 0.254)
		(layers "F.Cu" "B.Cu")
		(net "BMC_GPIOY3")
	)
	(via
		(at 46.099984 -137.80008)
		(size 0.4572)
		(drill 0.2032)
		(layers "F.Cu" "B.Cu")
		(net "BMC_GPIOY3")
	)
	(segment
		(start 46.4312 -137.1346)
		(end 46.4312 -133.010656)
		(width 0.127)
		(layer "In2.Cu")
		(net "BMC_GPIOY3")
	)
	(segment
		(start 46.099984 -137.465816)
		(end 46.4312 -137.1346)
		(width 0.127)
		(layer "In2.Cu")
		(net "BMC_GPIOY3")
	)
	(segment
		(start 46.4312 -133.010656)
		(end 46.449996 -132.99186)
		(width 0.127)
		(layer "In2.Cu")
		(net "BMC_GPIOY3")
	)
	(segment
		(start 46.099984 -137.80008)
		(end 46.099984 -137.465816)
		(width 0.127)
		(layer "In2.Cu")
		(net "BMC_GPIOY3")
	)
	(segment
		(start 46.228 -135.203184)
		(end 46.228 -133.949948)
		(width 0.127)
		(layer "F.Cu")
		(net "BMC_GPIOY2")
	)
	(segment
		(start 45.699934 -136.59993)
		(end 45.699934 -135.73125)
		(width 0.127)
		(layer "F.Cu")
		(net "BMC_GPIOY2")
	)
	(segment
		(start 45.699934 -135.73125)
		(end 46.228 -135.203184)
		(width 0.127)
		(layer "F.Cu")
		(net "BMC_GPIOY2")
	)
	(segment
		(start 46.228 -133.434582)
		(end 46.228 -133.949948)
		(width 0.127)
		(layer "F.Cu")
		(net "BMC_GPIOY2")
	)
	(segment
		(start 45.432726 -132.192522)
		(end 45.980096 -132.739892)
		(width 0.127)
		(layer "F.Cu")
		(net "BMC_GPIOY2")
	)
	(segment
		(start 45.980096 -133.186678)
		(end 46.228 -133.434582)
		(width 0.127)
		(layer "F.Cu")
		(net "BMC_GPIOY2")
	)
	(segment
		(start 45.980096 -132.739892)
		(end 45.980096 -133.186678)
		(width 0.127)
		(layer "F.Cu")
		(net "BMC_GPIOY2")
	)
	(via
		(at 46.228 -133.949948)
		(size 0.6604)
		(drill 0.3302)
		(layers "F.Cu" "B.Cu")
		(net "BMC_GPIOY2")
	)
	(segment
		(start 43.564302 -135.13054)
		(end 44.44873 -136.014968)
		(width 0.127)
		(layer "F.Cu")
		(net "BMC_GPIOY1")
	)
	(segment
		(start 42.98061 -132.759704)
		(end 42.98061 -133.70941)
		(width 0.127)
		(layer "F.Cu")
		(net "BMC_GPIOY1")
	)
	(segment
		(start 42.3164 -132.1943)
		(end 42.415206 -132.1943)
		(width 0.127)
		(layer "F.Cu")
		(net "BMC_GPIOY1")
	)
	(segment
		(start 42.415206 -132.1943)
		(end 42.98061 -132.759704)
		(width 0.127)
		(layer "F.Cu")
		(net "BMC_GPIOY1")
	)
	(segment
		(start 43.564302 -134.293102)
		(end 43.564302 -135.13054)
		(width 0.127)
		(layer "F.Cu")
		(net "BMC_GPIOY1")
	)
	(segment
		(start 42.98061 -133.70941)
		(end 43.2308 -133.9596)
		(width 0.127)
		(layer "F.Cu")
		(net "BMC_GPIOY1")
	)
	(segment
		(start 44.44873 -136.014968)
		(end 44.44873 -136.948926)
		(width 0.127)
		(layer "F.Cu")
		(net "BMC_GPIOY1")
	)
	(segment
		(start 44.44873 -136.948926)
		(end 44.899834 -137.40003)
		(width 0.127)
		(layer "F.Cu")
		(net "BMC_GPIOY1")
	)
	(segment
		(start 43.2308 -133.9596)
		(end 43.564302 -134.293102)
		(width 0.127)
		(layer "F.Cu")
		(net "BMC_GPIOY1")
	)
	(via
		(at 43.2308 -133.9596)
		(size 0.6604)
		(drill 0.3302)
		(layers "F.Cu" "B.Cu")
		(net "BMC_GPIOY1")
	)
	(segment
		(start 43.3578 -132.1943)
		(end 43.3578 -132.588)
		(width 0.127)
		(layer "F.Cu")
		(net "BMC_GPIOY0")
	)
	(segment
		(start 43.9928 -133.223)
		(end 43.9928 -134.8994)
		(width 0.127)
		(layer "F.Cu")
		(net "BMC_GPIOY0")
	)
	(segment
		(start 43.3578 -132.588)
		(end 43.8912 -133.1214)
		(width 0.127)
		(layer "F.Cu")
		(net "BMC_GPIOY0")
	)
	(segment
		(start 44.899834 -135.806434)
		(end 44.899834 -136.59993)
		(width 0.127)
		(layer "F.Cu")
		(net "BMC_GPIOY0")
	)
	(segment
		(start 43.8912 -133.1214)
		(end 43.9928 -133.223)
		(width 0.127)
		(layer "F.Cu")
		(net "BMC_GPIOY0")
	)
	(segment
		(start 43.9928 -134.8994)
		(end 44.899834 -135.806434)
		(width 0.127)
		(layer "F.Cu")
		(net "BMC_GPIOY0")
	)
	(via
		(at 43.8912 -133.1214)
		(size 0.6604)
		(drill 0.3302)
		(layers "F.Cu" "B.Cu")
		(net "BMC_GPIOY0")
	)
	(segment
		(start 39.700454 -137.800334)
		(end 40.099996 -138.199876)
		(width 0.127)
		(layer "F.Cu")
		(net "BMC_GPIOS7")
	)
	(segment
		(start 39.699946 -137.800334)
		(end 39.700454 -137.800334)
		(width 0.127)
		(layer "F.Cu")
		(net "BMC_GPIOS7")
	)
	(via
		(at 39.699946 -137.800334)
		(size 0.4572)
		(drill 0.2032)
		(layers "F.Cu" "B.Cu")
		(net "BMC_GPIOS7")
	)
	(via
		(at 40.469058 -137.028936)
		(size 0.6096)
		(drill 0.3048)
		(layers "F.Cu" "B.Cu")
		(net "BMC_GPIOS7")
	)
	(segment
		(start 40.469058 -137.031222)
		(end 40.469058 -137.028936)
		(width 0.127)
		(layer "B.Cu")
		(net "BMC_GPIOS7")
	)
	(segment
		(start 40.4622 -134.5565)
		(end 40.469058 -134.563358)
		(width 0.127)
		(layer "B.Cu")
		(net "BMC_GPIOS7")
	)
	(segment
		(start 39.699946 -137.800334)
		(end 40.469058 -137.031222)
		(width 0.127)
		(layer "B.Cu")
		(net "BMC_GPIOS7")
	)
	(segment
		(start 40.469058 -134.563358)
		(end 40.469058 -137.028936)
		(width 0.127)
		(layer "B.Cu")
		(net "BMC_GPIOS7")
	)
	(segment
		(start 42.900092 -137.799826)
		(end 43.299888 -138.199622)
		(width 0.127)
		(layer "F.Cu")
		(net "BMC_GPIOS6")
	)
	(segment
		(start 43.299888 -138.199622)
		(end 43.299888 -138.199876)
		(width 0.127)
		(layer "F.Cu")
		(net "BMC_GPIOS6")
	)
	(via
		(at 42.9768 -135.8646)
		(size 0.6096)
		(drill 0.3048)
		(layers "F.Cu" "B.Cu")
		(net "BMC_GPIOS6")
	)
	(via
		(at 42.900092 -137.799826)
		(size 0.4572)
		(drill 0.2032)
		(layers "F.Cu" "B.Cu")
		(net "BMC_GPIOS6")
	)
	(segment
		(start 42.77233 -137.672064)
		(end 42.900092 -137.799826)
		(width 0.127)
		(layer "B.Cu")
		(net "BMC_GPIOS6")
	)
	(segment
		(start 43.4086 -133.6421)
		(end 43.4848 -133.5659)
		(width 0.127)
		(layer "B.Cu")
		(net "BMC_GPIOS6")
	)
	(segment
		(start 42.77233 -136.06907)
		(end 42.77233 -137.672064)
		(width 0.127)
		(layer "B.Cu")
		(net "BMC_GPIOS6")
	)
	(segment
		(start 42.9768 -135.8646)
		(end 42.77233 -136.06907)
		(width 0.127)
		(layer "B.Cu")
		(net "BMC_GPIOS6")
	)
	(segment
		(start 42.9768 -135.8646)
		(end 43.4086 -135.4328)
		(width 0.127)
		(layer "B.Cu")
		(net "BMC_GPIOS6")
	)
	(segment
		(start 43.4086 -135.4328)
		(end 43.4086 -133.6421)
		(width 0.127)
		(layer "B.Cu")
		(net "BMC_GPIOS6")
	)
	(segment
		(start 41.699942 -138.199622)
		(end 41.699942 -138.199876)
		(width 0.127)
		(layer "F.Cu")
		(net "BMC_GPIOS5")
	)
	(segment
		(start 41.300146 -137.799826)
		(end 41.699942 -138.199622)
		(width 0.127)
		(layer "F.Cu")
		(net "BMC_GPIOS5")
	)
	(via
		(at 41.300146 -137.799826)
		(size 0.4572)
		(drill 0.2032)
		(layers "F.Cu" "B.Cu")
		(net "BMC_GPIOS5")
	)
	(via
		(at 41.93159 -135.166862)
		(size 0.6096)
		(drill 0.3048)
		(layers "F.Cu" "B.Cu")
		(net "BMC_GPIOS5")
	)
	(segment
		(start 41.93159 -135.166862)
		(end 41.93159 -135.872474)
		(width 0.127)
		(layer "B.Cu")
		(net "BMC_GPIOS5")
	)
	(segment
		(start 42.4307 -134.0358)
		(end 41.93159 -134.53491)
		(width 0.127)
		(layer "B.Cu")
		(net "BMC_GPIOS5")
	)
	(segment
		(start 41.93159 -135.872474)
		(end 41.300146 -136.503918)
		(width 0.127)
		(layer "B.Cu")
		(net "BMC_GPIOS5")
	)
	(segment
		(start 41.93159 -134.53491)
		(end 41.93159 -135.166862)
		(width 0.127)
		(layer "B.Cu")
		(net "BMC_GPIOS5")
	)
	(segment
		(start 41.300146 -136.503918)
		(end 41.300146 -137.799826)
		(width 0.127)
		(layer "B.Cu")
		(net "BMC_GPIOS5")
	)
	(segment
		(start 44.500292 -138.600434)
		(end 44.899834 -138.999976)
		(width 0.127)
		(layer "F.Cu")
		(net "BMC_GPIOS4")
	)
	(segment
		(start 44.500038 -138.600434)
		(end 44.500292 -138.600434)
		(width 0.127)
		(layer "F.Cu")
		(net "BMC_GPIOS4")
	)
	(via
		(at 44.500038 -138.600434)
		(size 0.4572)
		(drill 0.2032)
		(layers "F.Cu" "B.Cu")
		(net "BMC_GPIOS4")
	)
	(via
		(at 44.58843 -137.083546)
		(size 0.6096)
		(drill 0.3048)
		(layers "F.Cu" "B.Cu")
		(net "BMC_GPIOS4")
	)
	(segment
		(start 44.323 -136.1059)
		(end 44.323 -136.818116)
		(width 0.127)
		(layer "B.Cu")
		(net "BMC_GPIOS4")
	)
	(segment
		(start 44.500038 -138.600434)
		(end 44.893738 -138.206734)
		(width 0.127)
		(layer "B.Cu")
		(net "BMC_GPIOS4")
	)
	(segment
		(start 44.893738 -138.206734)
		(end 44.893738 -137.388854)
		(width 0.127)
		(layer "B.Cu")
		(net "BMC_GPIOS4")
	)
	(segment
		(start 44.323 -136.818116)
		(end 44.58843 -137.083546)
		(width 0.127)
		(layer "B.Cu")
		(net "BMC_GPIOS4")
	)
	(segment
		(start 44.893738 -137.388854)
		(end 44.58843 -137.083546)
		(width 0.127)
		(layer "B.Cu")
		(net "BMC_GPIOS4")
	)
	(segment
		(start 42.500042 -139.799822)
		(end 42.500042 -139.800076)
		(width 0.127)
		(layer "F.Cu")
		(net "BMC_EXTRST_N")
	)
	(segment
		(start 42.100246 -139.400026)
		(end 42.500042 -139.799822)
		(width 0.127)
		(layer "F.Cu")
		(net "BMC_EXTRST_N")
	)
	(via
		(at 41.28262 -127.2413)
		(size 0.6096)
		(drill 0.3048)
		(layers "F.Cu" "B.Cu")
		(net "BMC_EXTRST_N")
	)
	(via
		(at 40.20566 -127.60452)
		(size 0.508)
		(drill 0.254)
		(layers "F.Cu" "B.Cu")
		(net "BMC_EXTRST_N")
	)
	(via
		(at 42.100246 -139.400026)
		(size 0.4572)
		(drill 0.2032)
		(layers "F.Cu" "B.Cu")
		(net "BMC_EXTRST_N")
	)
	(segment
		(start 39.37 -126.9619)
		(end 40.108886 -126.9619)
		(width 0.127)
		(layer "B.Cu")
		(net "BMC_EXTRST_N")
	)
	(segment
		(start 41.28262 -127.2413)
		(end 41.28262 -127.493776)
		(width 0.127)
		(layer "B.Cu")
		(net "BMC_EXTRST_N")
	)
	(segment
		(start 41.155366 -127.62103)
		(end 40.22217 -127.62103)
		(width 0.127)
		(layer "B.Cu")
		(net "BMC_EXTRST_N")
	)
	(segment
		(start 40.108886 -126.9619)
		(end 40.261286 -127.1143)
		(width 0.127)
		(layer "B.Cu")
		(net "BMC_EXTRST_N")
	)
	(segment
		(start 39.36492 -126.95682)
		(end 39.37 -126.9619)
		(width 0.127)
		(layer "B.Cu")
		(net "BMC_EXTRST_N")
	)
	(segment
		(start 41.15562 -127.1143)
		(end 41.28262 -127.2413)
		(width 0.127)
		(layer "B.Cu")
		(net "BMC_EXTRST_N")
	)
	(segment
		(start 41.28262 -127.493776)
		(end 41.155366 -127.62103)
		(width 0.127)
		(layer "B.Cu")
		(net "BMC_EXTRST_N")
	)
	(segment
		(start 38.227 -126.95682)
		(end 39.36492 -126.95682)
		(width 0.127)
		(layer "B.Cu")
		(net "BMC_EXTRST_N")
	)
	(segment
		(start 40.22217 -127.62103)
		(end 40.20566 -127.60452)
		(width 0.127)
		(layer "B.Cu")
		(net "BMC_EXTRST_N")
	)
	(segment
		(start 40.261286 -127.1143)
		(end 41.15562 -127.1143)
		(width 0.127)
		(layer "B.Cu")
		(net "BMC_EXTRST_N")
	)
	(segment
		(start 41.18356 -132.408422)
		(end 41.18356 -128.58242)
		(width 0.127)
		(layer "In2.Cu")
		(net "BMC_EXTRST_N")
	)
	(segment
		(start 41.693846 -138.391646)
		(end 41.495726 -138.193526)
		(width 0.127)
		(layer "In2.Cu")
		(net "BMC_EXTRST_N")
	)
	(segment
		(start 42.100246 -139.179046)
		(end 41.693846 -138.772646)
		(width 0.127)
		(layer "In2.Cu")
		(net "BMC_EXTRST_N")
	)
	(segment
		(start 40.906446 -132.685536)
		(end 41.18356 -132.408422)
		(width 0.127)
		(layer "In2.Cu")
		(net "BMC_EXTRST_N")
	)
	(segment
		(start 41.136824 -138.193526)
		(end 40.906446 -137.963148)
		(width 0.127)
		(layer "In2.Cu")
		(net "BMC_EXTRST_N")
	)
	(segment
		(start 40.906446 -137.963148)
		(end 40.906446 -132.685536)
		(width 0.127)
		(layer "In2.Cu")
		(net "BMC_EXTRST_N")
	)
	(segment
		(start 42.100246 -139.400026)
		(end 42.100246 -139.179046)
		(width 0.127)
		(layer "In2.Cu")
		(net "BMC_EXTRST_N")
	)
	(segment
		(start 41.693846 -138.772646)
		(end 41.693846 -138.391646)
		(width 0.127)
		(layer "In2.Cu")
		(net "BMC_EXTRST_N")
	)
	(segment
		(start 41.18356 -128.58242)
		(end 40.20566 -127.60452)
		(width 0.127)
		(layer "In2.Cu")
		(net "BMC_EXTRST_N")
	)
	(segment
		(start 41.495726 -138.193526)
		(end 41.136824 -138.193526)
		(width 0.127)
		(layer "In2.Cu")
		(net "BMC_EXTRST_N")
	)
	(segment
		(start 49.299876 -152.200102)
		(end 48.899826 -151.800052)
		(width 0.127)
		(layer "F.Cu")
		(net "BMC_ENTEST")
	)
	(via
		(at 51.054 -153.3144)
		(size 0.6096)
		(drill 0.3048)
		(layers "F.Cu" "B.Cu")
		(net "BMC_ENTEST")
	)
	(via
		(at 49.299876 -152.200102)
		(size 0.4572)
		(drill 0.2032)
		(layers "F.Cu" "B.Cu")
		(net "BMC_ENTEST")
	)
	(segment
		(start 51.054 -153.7208)
		(end 51.63058 -154.29738)
		(width 0.127)
		(layer "B.Cu")
		(net "BMC_ENTEST")
	)
	(segment
		(start 51.293522 -151.23668)
		(end 51.293522 -152.71242)
		(width 0.127)
		(layer "B.Cu")
		(net "BMC_ENTEST")
	)
	(segment
		(start 49.693322 -150.763224)
		(end 49.693322 -150.44928)
		(width 0.127)
		(layer "B.Cu")
		(net "BMC_ENTEST")
	)
	(segment
		(start 50.506122 -150.763224)
		(end 50.7492 -151.006302)
		(width 0.127)
		(layer "B.Cu")
		(net "BMC_ENTEST")
	)
	(segment
		(start 48.905922 -151.806148)
		(end 48.905922 -151.23668)
		(width 0.127)
		(layer "B.Cu")
		(net "BMC_ENTEST")
	)
	(segment
		(start 50.506122 -150.44928)
		(end 50.506122 -150.763224)
		(width 0.127)
		(layer "B.Cu")
		(net "BMC_ENTEST")
	)
	(segment
		(start 50.7492 -151.006302)
		(end 51.063144 -151.006302)
		(width 0.127)
		(layer "B.Cu")
		(net "BMC_ENTEST")
	)
	(segment
		(start 51.63058 -154.29738)
		(end 51.63058 -155.05176)
		(width 0.127)
		(layer "B.Cu")
		(net "BMC_ENTEST")
	)
	(segment
		(start 51.054 -152.951942)
		(end 51.054 -153.3144)
		(width 0.127)
		(layer "B.Cu")
		(net "BMC_ENTEST")
	)
	(segment
		(start 49.299876 -152.200102)
		(end 48.905922 -151.806148)
		(width 0.127)
		(layer "B.Cu")
		(net "BMC_ENTEST")
	)
	(segment
		(start 49.9364 -150.206202)
		(end 50.263044 -150.206202)
		(width 0.127)
		(layer "B.Cu")
		(net "BMC_ENTEST")
	)
	(segment
		(start 49.1363 -151.006302)
		(end 49.450244 -151.006302)
		(width 0.127)
		(layer "B.Cu")
		(net "BMC_ENTEST")
	)
	(segment
		(start 51.293522 -152.71242)
		(end 51.054 -152.951942)
		(width 0.127)
		(layer "B.Cu")
		(net "BMC_ENTEST")
	)
	(segment
		(start 49.450244 -151.006302)
		(end 49.693322 -150.763224)
		(width 0.127)
		(layer "B.Cu")
		(net "BMC_ENTEST")
	)
	(segment
		(start 51.054 -153.3144)
		(end 51.054 -153.7208)
		(width 0.127)
		(layer "B.Cu")
		(net "BMC_ENTEST")
	)
	(segment
		(start 49.693322 -150.44928)
		(end 49.9364 -150.206202)
		(width 0.127)
		(layer "B.Cu")
		(net "BMC_ENTEST")
	)
	(segment
		(start 51.063144 -151.006302)
		(end 51.293522 -151.23668)
		(width 0.127)
		(layer "B.Cu")
		(net "BMC_ENTEST")
	)
	(segment
		(start 48.905922 -151.23668)
		(end 49.1363 -151.006302)
		(width 0.127)
		(layer "B.Cu")
		(net "BMC_ENTEST")
	)
	(segment
		(start 51.63058 -155.05176)
		(end 52.07508 -155.49626)
		(width 0.127)
		(layer "B.Cu")
		(net "BMC_ENTEST")
	)
	(segment
		(start 50.263044 -150.206202)
		(end 50.506122 -150.44928)
		(width 0.127)
		(layer "B.Cu")
		(net "BMC_ENTEST")
	)
	(segment
		(start 185.1152 -124.2314)
		(end 185.25871 -124.08789)
		(width 0.254)
		(layer "F.Cu")
		(net "AGND_P0V975")
	)
	(segment
		(start 184.1246 -125.476)
		(end 185.1152 -124.4854)
		(width 0.254)
		(layer "F.Cu")
		(net "AGND_P0V975")
	)
	(segment
		(start 185.25871 -124.08789)
		(end 186.085734 -123.260866)
		(width 0.254)
		(layer "F.Cu")
		(net "AGND_P0V975")
	)
	(segment
		(start 181.883812 -125.052836)
		(end 181.883812 -125.224032)
		(width 0.254)
		(layer "F.Cu")
		(net "AGND_P0V975")
	)
	(segment
		(start 184.1246 -125.476)
		(end 182.9308 -125.476)
		(width 0.254)
		(layer "F.Cu")
		(net "AGND_P0V975")
	)
	(segment
		(start 186.085734 -123.260866)
		(end 186.795156 -123.260866)
		(width 0.254)
		(layer "F.Cu")
		(net "AGND_P0V975")
	)
	(segment
		(start 181.883812 -125.224032)
		(end 182.13578 -125.476)
		(width 0.254)
		(layer "F.Cu")
		(net "AGND_P0V975")
	)
	(segment
		(start 185.1152 -124.4854)
		(end 185.1152 -124.2314)
		(width 0.254)
		(layer "F.Cu")
		(net "AGND_P0V975")
	)
	(segment
		(start 182.13578 -125.476)
		(end 182.9308 -125.476)
		(width 0.254)
		(layer "F.Cu")
		(net "AGND_P0V975")
	)
	(via
		(at 181.883812 -125.052836)
		(size 0.508)
		(drill 0.254)
		(layers "F.Cu" "B.Cu")
		(net "AGND_P0V975")
	)
	(via
		(at 185.25871 -124.08789)
		(size 0.6604)
		(drill 0.3302)
		(layers "F.Cu" "B.Cu")
		(net "AGND_P0V975")
	)
	(segment
		(start 184.667906 -125.052836)
		(end 181.883812 -125.052836)
		(width 0.254)
		(layer "B.Cu")
		(net "AGND_P0V975")
	)
	(segment
		(start 185.96356 -123.757182)
		(end 184.667906 -125.052836)
		(width 0.254)
		(layer "B.Cu")
		(net "AGND_P0V975")
	)
	(segment
		(start 51.5366 -163.3093)
		(end 52.8066 -162.0393)
		(width 0.127)
		(layer "F.Cu")
		(net "ADC_P3V3")
	)
	(segment
		(start 54.0766 -158.0388)
		(end 54.2798 -158.242)
		(width 0.127)
		(layer "F.Cu")
		(net "ADC_P3V3")
	)
	(segment
		(start 54.8132 -159.4612)
		(end 54.8132 -160.997392)
		(width 0.127)
		(layer "F.Cu")
		(net "ADC_P3V3")
	)
	(segment
		(start 51.299872 -151.000206)
		(end 51.699668 -151.400002)
		(width 0.127)
		(layer "F.Cu")
		(net "ADC_P3V3")
	)
	(segment
		(start 51.0159 -163.3093)
		(end 51.5366 -163.3093)
		(width 0.127)
		(layer "F.Cu")
		(net "ADC_P3V3")
	)
	(segment
		(start 52.8066 -162.0393)
		(end 53.771292 -162.0393)
		(width 0.127)
		(layer "F.Cu")
		(net "ADC_P3V3")
	)
	(segment
		(start 54.8132 -160.997392)
		(end 53.773324 -162.037268)
		(width 0.127)
		(layer "F.Cu")
		(net "ADC_P3V3")
	)
	(segment
		(start 54.2798 -158.9278)
		(end 54.483 -159.131)
		(width 0.127)
		(layer "F.Cu")
		(net "ADC_P3V3")
	)
	(segment
		(start 51.299872 -150.999952)
		(end 51.299872 -151.000206)
		(width 0.127)
		(layer "F.Cu")
		(net "ADC_P3V3")
	)
	(segment
		(start 54.483 -159.131)
		(end 54.8132 -159.4612)
		(width 0.127)
		(layer "F.Cu")
		(net "ADC_P3V3")
	)
	(segment
		(start 53.771292 -162.0393)
		(end 53.773324 -162.037268)
		(width 0.127)
		(layer "F.Cu")
		(net "ADC_P3V3")
	)
	(segment
		(start 54.2798 -158.242)
		(end 54.2798 -158.9278)
		(width 0.127)
		(layer "F.Cu")
		(net "ADC_P3V3")
	)
	(segment
		(start 54.0766 -157.277054)
		(end 54.0766 -158.0388)
		(width 0.127)
		(layer "F.Cu")
		(net "ADC_P3V3")
	)
	(via
		(at 51.699668 -151.400002)
		(size 0.4572)
		(drill 0.2032)
		(layers "F.Cu" "B.Cu")
		(net "ADC_P3V3")
	)
	(via
		(at 54.0766 -157.277054)
		(size 0.508)
		(drill 0.254)
		(layers "F.Cu" "B.Cu")
		(net "ADC_P3V3")
	)
	(via
		(at 54.483 -159.131)
		(size 0.6604)
		(drill 0.3302)
		(layers "F.Cu" "B.Cu")
		(net "ADC_P3V3")
	)
	(segment
		(start 51.942746 -151.400002)
		(end 51.699668 -151.400002)
		(width 0.127)
		(layer "In2.Cu")
		(net "ADC_P3V3")
	)
	(segment
		(start 52.893468 -153.207974)
		(end 52.893468 -152.03678)
		(width 0.127)
		(layer "In2.Cu")
		(net "ADC_P3V3")
	)
	(segment
		(start 54.0766 -154.987498)
		(end 53.337714 -154.248612)
		(width 0.127)
		(layer "In2.Cu")
		(net "ADC_P3V3")
	)
	(segment
		(start 52.65039 -151.793702)
		(end 52.336446 -151.793702)
		(width 0.127)
		(layer "In2.Cu")
		(net "ADC_P3V3")
	)
	(segment
		(start 53.337714 -154.248612)
		(end 53.337714 -153.65222)
		(width 0.127)
		(layer "In2.Cu")
		(net "ADC_P3V3")
	)
	(segment
		(start 54.0766 -157.277054)
		(end 54.0766 -154.987498)
		(width 0.127)
		(layer "In2.Cu")
		(net "ADC_P3V3")
	)
	(segment
		(start 53.337714 -153.65222)
		(end 52.893468 -153.207974)
		(width 0.127)
		(layer "In2.Cu")
		(net "ADC_P3V3")
	)
	(segment
		(start 52.336446 -151.793702)
		(end 51.942746 -151.400002)
		(width 0.127)
		(layer "In2.Cu")
		(net "ADC_P3V3")
	)
	(segment
		(start 52.893468 -152.03678)
		(end 52.65039 -151.793702)
		(width 0.127)
		(layer "In2.Cu")
		(net "ADC_P3V3")
	)
	(segment
		(start 52.499768 -152.999948)
		(end 52.499768 -152.999694)
		(width 0.127)
		(layer "F.Cu")
		(net "ADC_P1V8")
	)
	(segment
		(start 52.499768 -152.999694)
		(end 52.099972 -152.599898)
		(width 0.127)
		(layer "F.Cu")
		(net "ADC_P1V8")
	)
	(via
		(at 61.1886 -161.3408)
		(size 0.6096)
		(drill 0.3048)
		(layers "F.Cu" "B.Cu")
		(net "ADC_P1V8")
	)
	(via
		(at 52.499768 -152.999948)
		(size 0.4572)
		(drill 0.2032)
		(layers "F.Cu" "B.Cu")
		(net "ADC_P1V8")
	)
	(via
		(at 58.293 -160.401)
		(size 0.508)
		(drill 0.254)
		(layers "F.Cu" "B.Cu")
		(net "ADC_P1V8")
	)
	(segment
		(start 60.0329 -161.0106)
		(end 60.0329 -160.9471)
		(width 0.127)
		(layer "B.Cu")
		(net "ADC_P1V8")
	)
	(segment
		(start 60.9346 -162.0266)
		(end 60.0075 -162.0266)
		(width 0.127)
		(layer "B.Cu")
		(net "ADC_P1V8")
	)
	(segment
		(start 61.1886 -161.3408)
		(end 61.1886 -161.7726)
		(width 0.127)
		(layer "B.Cu")
		(net "ADC_P1V8")
	)
	(segment
		(start 60.8584 -161.0106)
		(end 61.1886 -161.3408)
		(width 0.127)
		(layer "B.Cu")
		(net "ADC_P1V8")
	)
	(segment
		(start 61.1886 -161.7726)
		(end 60.9346 -162.0266)
		(width 0.127)
		(layer "B.Cu")
		(net "ADC_P1V8")
	)
	(segment
		(start 60.0329 -161.0106)
		(end 60.8584 -161.0106)
		(width 0.127)
		(layer "B.Cu")
		(net "ADC_P1V8")
	)
	(segment
		(start 59.4868 -160.401)
		(end 58.293 -160.401)
		(width 0.127)
		(layer "B.Cu")
		(net "ADC_P1V8")
	)
	(segment
		(start 59.1185 -163.1442)
		(end 59.1185 -162.9156)
		(width 0.127)
		(layer "B.Cu")
		(net "ADC_P1V8")
	)
	(segment
		(start 59.1185 -162.9156)
		(end 60.0075 -162.0266)
		(width 0.127)
		(layer "B.Cu")
		(net "ADC_P1V8")
	)
	(segment
		(start 60.0329 -160.9471)
		(end 59.4868 -160.401)
		(width 0.127)
		(layer "B.Cu")
		(net "ADC_P1V8")
	)
	(segment
		(start 52.499768 -153.159968)
		(end 52.90566 -153.56586)
		(width 0.127)
		(layer "In2.Cu")
		(net "ADC_P1V8")
	)
	(segment
		(start 53.4289 -160.64611)
		(end 53.88229 -161.0995)
		(width 0.127)
		(layer "In2.Cu")
		(net "ADC_P1V8")
	)
	(segment
		(start 54.626256 -161.0995)
		(end 54.865016 -160.86074)
		(width 0.127)
		(layer "In2.Cu")
		(net "ADC_P1V8")
	)
	(segment
		(start 52.499768 -152.999948)
		(end 52.499768 -153.159968)
		(width 0.127)
		(layer "In2.Cu")
		(net "ADC_P1V8")
	)
	(segment
		(start 57.83326 -160.86074)
		(end 58.293 -160.401)
		(width 0.127)
		(layer "In2.Cu")
		(net "ADC_P1V8")
	)
	(segment
		(start 54.865016 -160.86074)
		(end 57.83326 -160.86074)
		(width 0.127)
		(layer "In2.Cu")
		(net "ADC_P1V8")
	)
	(segment
		(start 53.6067 -159.030924)
		(end 53.4289 -159.208724)
		(width 0.127)
		(layer "In2.Cu")
		(net "ADC_P1V8")
	)
	(segment
		(start 52.90566 -154.712924)
		(end 53.6067 -155.413964)
		(width 0.127)
		(layer "In2.Cu")
		(net "ADC_P1V8")
	)
	(segment
		(start 53.88229 -161.0995)
		(end 54.626256 -161.0995)
		(width 0.127)
		(layer "In2.Cu")
		(net "ADC_P1V8")
	)
	(segment
		(start 53.4289 -159.208724)
		(end 53.4289 -160.64611)
		(width 0.127)
		(layer "In2.Cu")
		(net "ADC_P1V8")
	)
	(segment
		(start 53.6067 -155.413964)
		(end 53.6067 -159.030924)
		(width 0.127)
		(layer "In2.Cu")
		(net "ADC_P1V8")
	)
	(segment
		(start 52.90566 -153.56586)
		(end 52.90566 -154.712924)
		(width 0.127)
		(layer "In2.Cu")
		(net "ADC_P1V8")
	)
	(segment
		(start 51.299872 -151.800306)
		(end 51.299872 -151.800052)
		(width 0.127)
		(layer "F.Cu")
		(net "ADC_P1V5")
	)
	(segment
		(start 51.699668 -152.200102)
		(end 51.299872 -151.800306)
		(width 0.127)
		(layer "F.Cu")
		(net "ADC_P1V5")
	)
	(via
		(at 51.699668 -152.200102)
		(size 0.4572)
		(drill 0.2032)
		(layers "F.Cu" "B.Cu")
		(net "ADC_P1V5")
	)
	(via
		(at 53.109622 -156.425646)
		(size 0.508)
		(drill 0.254)
		(layers "F.Cu" "B.Cu")
		(net "ADC_P1V5")
	)
	(via
		(at 52.722526 -159.9565)
		(size 0.6096)
		(drill 0.3048)
		(layers "F.Cu" "B.Cu")
		(net "ADC_P1V5")
	)
	(segment
		(start 53.622194 -159.061912)
		(end 52.727606 -159.9565)
		(width 0.127)
		(layer "B.Cu")
		(net "ADC_P1V5")
	)
	(segment
		(start 52.63896 -161.8615)
		(end 52.63896 -160.91154)
		(width 0.127)
		(layer "B.Cu")
		(net "ADC_P1V5")
	)
	(segment
		(start 52.63896 -160.91154)
		(end 52.6542 -160.8963)
		(width 0.127)
		(layer "B.Cu")
		(net "ADC_P1V5")
	)
	(segment
		(start 52.727606 -159.9565)
		(end 52.722526 -159.9565)
		(width 0.127)
		(layer "B.Cu")
		(net "ADC_P1V5")
	)
	(segment
		(start 52.722526 -159.96158)
		(end 52.722526 -159.9565)
		(width 0.127)
		(layer "B.Cu")
		(net "ADC_P1V5")
	)
	(segment
		(start 52.6542 -160.029906)
		(end 52.722526 -159.96158)
		(width 0.127)
		(layer "B.Cu")
		(net "ADC_P1V5")
	)
	(segment
		(start 52.6161 -162.88258)
		(end 52.6161 -161.88436)
		(width 0.127)
		(layer "B.Cu")
		(net "ADC_P1V5")
	)
	(segment
		(start 53.622194 -158.242254)
		(end 53.622194 -159.061912)
		(width 0.127)
		(layer "B.Cu")
		(net "ADC_P1V5")
	)
	(segment
		(start 52.6161 -161.88436)
		(end 52.63896 -161.8615)
		(width 0.127)
		(layer "B.Cu")
		(net "ADC_P1V5")
	)
	(segment
		(start 53.109622 -156.425646)
		(end 53.109622 -157.729682)
		(width 0.127)
		(layer "B.Cu")
		(net "ADC_P1V5")
	)
	(segment
		(start 52.6542 -160.8963)
		(end 52.6542 -160.029906)
		(width 0.127)
		(layer "B.Cu")
		(net "ADC_P1V5")
	)
	(segment
		(start 53.109622 -157.729682)
		(end 53.622194 -158.242254)
		(width 0.127)
		(layer "B.Cu")
		(net "ADC_P1V5")
	)
	(segment
		(start 52.67706 -153.734262)
		(end 52.106068 -153.16327)
		(width 0.127)
		(layer "In2.Cu")
		(net "ADC_P1V5")
	)
	(segment
		(start 51.877468 -152.377902)
		(end 51.699668 -152.200102)
		(width 0.127)
		(layer "In2.Cu")
		(net "ADC_P1V5")
	)
	(segment
		(start 53.109622 -156.425646)
		(end 52.67706 -155.993084)
		(width 0.127)
		(layer "In2.Cu")
		(net "ADC_P1V5")
	)
	(segment
		(start 51.877468 -152.458166)
		(end 51.877468 -152.377902)
		(width 0.127)
		(layer "In2.Cu")
		(net "ADC_P1V5")
	)
	(segment
		(start 52.106068 -153.16327)
		(end 52.106068 -152.686766)
		(width 0.127)
		(layer "In2.Cu")
		(net "ADC_P1V5")
	)
	(segment
		(start 52.106068 -152.686766)
		(end 51.877468 -152.458166)
		(width 0.127)
		(layer "In2.Cu")
		(net "ADC_P1V5")
	)
	(segment
		(start 52.67706 -155.993084)
		(end 52.67706 -153.734262)
		(width 0.127)
		(layer "In2.Cu")
		(net "ADC_P1V5")
	)
	(segment
		(start 51.699668 -152.999948)
		(end 51.699668 -152.999694)
		(width 0.127)
		(layer "F.Cu")
		(net "ADC_P0V975")
	)
	(segment
		(start 51.699668 -152.999694)
		(end 51.299872 -152.599898)
		(width 0.127)
		(layer "F.Cu")
		(net "ADC_P0V975")
	)
	(via
		(at 54.142894 -158.2674)
		(size 0.6096)
		(drill 0.3048)
		(layers "F.Cu" "B.Cu")
		(net "ADC_P0V975")
	)
	(via
		(at 51.699668 -152.999948)
		(size 0.4572)
		(drill 0.2032)
		(layers "F.Cu" "B.Cu")
		(net "ADC_P0V975")
	)
	(segment
		(start 53.271674 -160.05302)
		(end 53.271674 -163.782756)
		(width 0.127)
		(layer "B.Cu")
		(net "ADC_P0V975")
	)
	(segment
		(start 53.2765 -164.177218)
		(end 53.271166 -164.182552)
		(width 0.127)
		(layer "B.Cu")
		(net "ADC_P0V975")
	)
	(segment
		(start 53.2765 -163.787582)
		(end 53.2765 -164.177218)
		(width 0.127)
		(layer "B.Cu")
		(net "ADC_P0V975")
	)
	(segment
		(start 53.271166 -164.612066)
		(end 53.6321 -164.973)
		(width 0.127)
		(layer "B.Cu")
		(net "ADC_P0V975")
	)
	(segment
		(start 53.6067 -156.2735)
		(end 52.51958 -155.18638)
		(width 0.127)
		(layer "B.Cu")
		(net "ADC_P0V975")
	)
	(segment
		(start 53.608732 -165.936676)
		(end 52.538376 -165.936676)
		(width 0.127)
		(layer "B.Cu")
		(net "ADC_P0V975")
	)
	(segment
		(start 52.51958 -155.18638)
		(end 52.51958 -154.031188)
		(width 0.127)
		(layer "B.Cu")
		(net "ADC_P0V975")
	)
	(segment
		(start 51.699668 -153.211276)
		(end 51.699668 -152.999948)
		(width 0.127)
		(layer "B.Cu")
		(net "ADC_P0V975")
	)
	(segment
		(start 53.271674 -163.782756)
		(end 53.2765 -163.787582)
		(width 0.127)
		(layer "B.Cu")
		(net "ADC_P0V975")
	)
	(segment
		(start 54.142894 -158.2674)
		(end 54.142894 -158.223966)
		(width 0.127)
		(layer "B.Cu")
		(net "ADC_P0V975")
	)
	(segment
		(start 54.142894 -158.2674)
		(end 54.142894 -159.1818)
		(width 0.127)
		(layer "B.Cu")
		(net "ADC_P0V975")
	)
	(segment
		(start 52.51958 -154.031188)
		(end 51.699668 -153.211276)
		(width 0.127)
		(layer "B.Cu")
		(net "ADC_P0V975")
	)
	(segment
		(start 52.538376 -165.936676)
		(end 52.4891 -165.8874)
		(width 0.127)
		(layer "B.Cu")
		(net "ADC_P0V975")
	)
	(segment
		(start 53.271166 -164.182552)
		(end 53.271166 -164.612066)
		(width 0.127)
		(layer "B.Cu")
		(net "ADC_P0V975")
	)
	(segment
		(start 53.6321 -164.973)
		(end 53.608732 -164.996368)
		(width 0.127)
		(layer "B.Cu")
		(net "ADC_P0V975")
	)
	(segment
		(start 53.608732 -164.996368)
		(end 53.608732 -165.936676)
		(width 0.127)
		(layer "B.Cu")
		(net "ADC_P0V975")
	)
	(segment
		(start 53.6067 -157.687772)
		(end 53.6067 -156.2735)
		(width 0.127)
		(layer "B.Cu")
		(net "ADC_P0V975")
	)
	(segment
		(start 54.142894 -158.223966)
		(end 53.6067 -157.687772)
		(width 0.127)
		(layer "B.Cu")
		(net "ADC_P0V975")
	)
	(segment
		(start 54.142894 -159.1818)
		(end 53.271674 -160.05302)
		(width 0.127)
		(layer "B.Cu")
		(net "ADC_P0V975")
	)
	(segment
		(start 202.776328 -125.661928)
		(end 202.3618 -125.2474)
		(width 0.254)
		(layer "F.Cu")
		(net "TPS74801_1V5_SS")
	)
	(segment
		(start 201.5998 -125.3236)
		(end 201.5998 -126.1999)
		(width 0.254)
		(layer "F.Cu")
		(net "TPS74801_1V5_SS")
	)
	(segment
		(start 202.3618 -125.2474)
		(end 201.676 -125.2474)
		(width 0.254)
		(layer "F.Cu")
		(net "TPS74801_1V5_SS")
	)
	(segment
		(start 201.676 -125.2474)
		(end 201.5998 -125.3236)
		(width 0.254)
		(layer "F.Cu")
		(net "TPS74801_1V5_SS")
	)
	(segment
		(start 203.319634 -125.661928)
		(end 202.776328 -125.661928)
		(width 0.254)
		(layer "F.Cu")
		(net "TPS74801_1V5_SS")
	)
	(segment
		(start 201.5998 -126.1999)
		(end 201.803 -126.4031)
		(width 0.254)
		(layer "F.Cu")
		(net "TPS74801_1V5_SS")
	)
	(via
		(at 201.5998 -125.3236)
		(size 0.6604)
		(drill 0.3302)
		(layers "F.Cu" "B.Cu")
		(net "TPS74801_1V5_SS")
	)
	(segment
		(start 202.650852 -129.200148)
		(end 203.319634 -128.531366)
		(width 0.254)
		(layer "F.Cu")
		(net "TPS74801_1V5_EN")
	)
	(segment
		(start 200.29678 -128.464056)
		(end 200.29678 -129.5146)
		(width 0.254)
		(layer "F.Cu")
		(net "TPS74801_1V5_EN")
	)
	(segment
		(start 200.81113 -128.4224)
		(end 201.588878 -129.200148)
		(width 0.254)
		(layer "F.Cu")
		(net "TPS74801_1V5_EN")
	)
	(segment
		(start 200.338436 -128.4224)
		(end 200.29678 -128.464056)
		(width 0.254)
		(layer "F.Cu")
		(net "TPS74801_1V5_EN")
	)
	(segment
		(start 200.29678 -129.5146)
		(end 200.7108 -129.92862)
		(width 0.254)
		(layer "F.Cu")
		(net "TPS74801_1V5_EN")
	)
	(segment
		(start 200.7108 -129.92862)
		(end 200.7108 -130.556)
		(width 0.254)
		(layer "F.Cu")
		(net "TPS74801_1V5_EN")
	)
	(segment
		(start 200.338436 -128.4224)
		(end 200.81113 -128.4224)
		(width 0.254)
		(layer "F.Cu")
		(net "TPS74801_1V5_EN")
	)
	(segment
		(start 199.645016 -130.6449)
		(end 200.6219 -130.6449)
		(width 0.254)
		(layer "F.Cu")
		(net "TPS74801_1V5_EN")
	)
	(segment
		(start 200.6219 -130.6449)
		(end 200.7108 -130.556)
		(width 0.254)
		(layer "F.Cu")
		(net "TPS74801_1V5_EN")
	)
	(segment
		(start 201.588878 -129.200148)
		(end 201.698352 -129.200148)
		(width 0.254)
		(layer "F.Cu")
		(net "TPS74801_1V5_EN")
	)
	(segment
		(start 203.319634 -128.531366)
		(end 203.319634 -128.261872)
		(width 0.254)
		(layer "F.Cu")
		(net "TPS74801_1V5_EN")
	)
	(segment
		(start 201.698352 -129.200148)
		(end 202.650852 -129.200148)
		(width 0.254)
		(layer "F.Cu")
		(net "TPS74801_1V5_EN")
	)
	(via
		(at 200.7108 -130.556)
		(size 0.6604)
		(drill 0.3302)
		(layers "F.Cu" "B.Cu")
		(net "TPS74801_1V5_EN")
	)
	(segment
		(start 202.164188 -131.73456)
		(end 202.541124 -131.357624)
		(width 0.254)
		(layer "F.Cu")
		(net "TPS74801_1V5_BIAS")
	)
	(segment
		(start 202.164188 -132.805932)
		(end 202.164188 -131.73456)
		(width 0.254)
		(layer "F.Cu")
		(net "TPS74801_1V5_BIAS")
	)
	(segment
		(start 203.298552 -131.357624)
		(end 204.494384 -130.161792)
		(width 0.254)
		(layer "F.Cu")
		(net "TPS74801_1V5_BIAS")
	)
	(segment
		(start 202.541124 -131.357624)
		(end 203.298552 -131.357624)
		(width 0.254)
		(layer "F.Cu")
		(net "TPS74801_1V5_BIAS")
	)
	(segment
		(start 204.494384 -130.161792)
		(end 204.494384 -129.436622)
		(width 0.254)
		(layer "F.Cu")
		(net "TPS74801_1V5_BIAS")
	)
	(via
		(at 202.164188 -131.73456)
		(size 0.6604)
		(drill 0.3302)
		(layers "F.Cu" "B.Cu")
		(net "TPS74801_1V5_BIAS")
	)
	(segment
		(start 52.899818 -138.999976)
		(end 53.299868 -138.599926)
		(width 0.127)
		(layer "F.Cu")
		(net "SLOTID_1")
	)
	(via
		(at 53.299868 -138.599926)
		(size 0.4572)
		(drill 0.2032)
		(layers "F.Cu" "B.Cu")
		(net "SLOTID_1")
	)
	(via
		(at 95.186754 -123.351544)
		(size 0.508)
		(drill 0.254)
		(layers "F.Cu" "B.Cu")
		(net "SLOTID_1")
	)
	(via
		(at 52.183538 -123.891548)
		(size 0.508)
		(drill 0.254)
		(layers "F.Cu" "B.Cu")
		(net "SLOTID_1")
	)
	(segment
		(start 53.299868 -136.425432)
		(end 53.299868 -138.599926)
		(width 0.127)
		(layer "B.Cu")
		(net "SLOTID_1")
	)
	(segment
		(start 53.5686 -136.1567)
		(end 53.299868 -136.425432)
		(width 0.127)
		(layer "B.Cu")
		(net "SLOTID_1")
	)
	(segment
		(start 54.6354 -136.1567)
		(end 53.5686 -136.1567)
		(width 0.127)
		(layer "B.Cu")
		(net "SLOTID_1")
	)
	(segment
		(start 95.631 -120.574562)
		(end 95.631 -117.801136)
		(width 0.127)
		(layer "In2.Cu")
		(net "SLOTID_1")
	)
	(segment
		(start 95.435166 -123.103132)
		(end 95.435166 -120.770396)
		(width 0.127)
		(layer "In2.Cu")
		(net "SLOTID_1")
	)
	(segment
		(start 97.834958 -54.292754)
		(end 97.834958 -43.2308)
		(width 0.127)
		(layer "In2.Cu")
		(net "SLOTID_1")
	)
	(segment
		(start 118.852442 -44.44746)
		(end 117.899942 -45.39996)
		(width 0.127)
		(layer "In2.Cu")
		(net "SLOTID_1")
	)
	(segment
		(start 52.183538 -123.891548)
		(end 52.183538 -125.868938)
		(width 0.127)
		(layer "In2.Cu")
		(net "SLOTID_1")
	)
	(segment
		(start 96.107504 -117.324632)
		(end 96.107504 -97.131632)
		(width 0.127)
		(layer "In2.Cu")
		(net "SLOTID_1")
	)
	(segment
		(start 104.396286 -25.359106)
		(end 116.435886 -25.359106)
		(width 0.127)
		(layer "In2.Cu")
		(net "SLOTID_1")
	)
	(segment
		(start 52.183538 -125.868938)
		(end 53.299868 -126.985268)
		(width 0.127)
		(layer "In2.Cu")
		(net "SLOTID_1")
	)
	(segment
		(start 99.133914 -30.621478)
		(end 104.396286 -25.359106)
		(width 0.127)
		(layer "In2.Cu")
		(net "SLOTID_1")
	)
	(segment
		(start 96.797114 -96.442022)
		(end 96.797114 -55.330598)
		(width 0.127)
		(layer "In2.Cu")
		(net "SLOTID_1")
	)
	(segment
		(start 95.435166 -120.770396)
		(end 95.631 -120.574562)
		(width 0.127)
		(layer "In2.Cu")
		(net "SLOTID_1")
	)
	(segment
		(start 96.797114 -55.330598)
		(end 97.834958 -54.292754)
		(width 0.127)
		(layer "In2.Cu")
		(net "SLOTID_1")
	)
	(segment
		(start 53.299868 -126.985268)
		(end 53.299868 -138.599926)
		(width 0.127)
		(layer "In2.Cu")
		(net "SLOTID_1")
	)
	(segment
		(start 118.852442 -27.775662)
		(end 118.852442 -44.44746)
		(width 0.127)
		(layer "In2.Cu")
		(net "SLOTID_1")
	)
	(segment
		(start 99.133914 -41.931844)
		(end 99.133914 -30.621478)
		(width 0.127)
		(layer "In2.Cu")
		(net "SLOTID_1")
	)
	(segment
		(start 116.435886 -25.359106)
		(end 118.852442 -27.775662)
		(width 0.127)
		(layer "In2.Cu")
		(net "SLOTID_1")
	)
	(segment
		(start 97.834958 -43.2308)
		(end 99.133914 -41.931844)
		(width 0.127)
		(layer "In2.Cu")
		(net "SLOTID_1")
	)
	(segment
		(start 95.631 -117.801136)
		(end 96.107504 -117.324632)
		(width 0.127)
		(layer "In2.Cu")
		(net "SLOTID_1")
	)
	(segment
		(start 96.107504 -97.131632)
		(end 96.797114 -96.442022)
		(width 0.127)
		(layer "In2.Cu")
		(net "SLOTID_1")
	)
	(segment
		(start 95.186754 -123.351544)
		(end 95.435166 -123.103132)
		(width 0.127)
		(layer "In2.Cu")
		(net "SLOTID_1")
	)
	(segment
		(start 95.170498 -123.3678)
		(end 95.186754 -123.351544)
		(width 0.127)
		(layer "In5.Cu")
		(net "SLOTID_1")
	)
	(segment
		(start 52.841144 -123.233942)
		(end 55.503572 -123.233942)
		(width 0.127)
		(layer "In5.Cu")
		(net "SLOTID_1")
	)
	(segment
		(start 71.181722 -122.936)
		(end 74.22007 -125.974348)
		(width 0.127)
		(layer "In5.Cu")
		(net "SLOTID_1")
	)
	(segment
		(start 55.801514 -122.936)
		(end 71.181722 -122.936)
		(width 0.127)
		(layer "In5.Cu")
		(net "SLOTID_1")
	)
	(segment
		(start 52.183538 -123.891548)
		(end 52.841144 -123.233942)
		(width 0.127)
		(layer "In5.Cu")
		(net "SLOTID_1")
	)
	(segment
		(start 86.4108 -123.3678)
		(end 95.170498 -123.3678)
		(width 0.127)
		(layer "In5.Cu")
		(net "SLOTID_1")
	)
	(segment
		(start 83.804252 -125.974348)
		(end 86.4108 -123.3678)
		(width 0.127)
		(layer "In5.Cu")
		(net "SLOTID_1")
	)
	(segment
		(start 74.22007 -125.974348)
		(end 83.804252 -125.974348)
		(width 0.127)
		(layer "In5.Cu")
		(net "SLOTID_1")
	)
	(segment
		(start 55.503572 -123.233942)
		(end 55.801514 -122.936)
		(width 0.127)
		(layer "In5.Cu")
		(net "SLOTID_1")
	)
	(segment
		(start 58.538364 -136.6774)
		(end 56.215788 -138.999976)
		(width 0.127)
		(layer "F.Cu")
		(net "SLOTID_0")
	)
	(segment
		(start 63.6778 -134.747)
		(end 63.6778 -134.3152)
		(width 0.127)
		(layer "F.Cu")
		(net "SLOTID_0")
	)
	(segment
		(start 60.84824 -136.433306)
		(end 60.604146 -136.6774)
		(width 0.127)
		(layer "F.Cu")
		(net "SLOTID_0")
	)
	(segment
		(start 61.611764 -135.331708)
		(end 61.529722 -135.331708)
		(width 0.127)
		(layer "F.Cu")
		(net "SLOTID_0")
	)
	(segment
		(start 63.6778 -134.747)
		(end 63.6778 -135.14959)
		(width 0.127)
		(layer "F.Cu")
		(net "SLOTID_0")
	)
	(segment
		(start 63.6778 -135.14959)
		(end 62.998096 -135.829294)
		(width 0.127)
		(layer "F.Cu")
		(net "SLOTID_0")
	)
	(segment
		(start 60.84824 -136.01319)
		(end 61.529722 -135.331708)
		(width 0.127)
		(layer "F.Cu")
		(net "SLOTID_0")
	)
	(segment
		(start 60.84824 -136.433306)
		(end 60.84824 -136.01319)
		(width 0.127)
		(layer "F.Cu")
		(net "SLOTID_0")
	)
	(segment
		(start 63.6778 -134.3152)
		(end 63.2587 -133.8961)
		(width 0.127)
		(layer "F.Cu")
		(net "SLOTID_0")
	)
	(segment
		(start 60.604146 -136.6774)
		(end 58.538364 -136.6774)
		(width 0.127)
		(layer "F.Cu")
		(net "SLOTID_0")
	)
	(segment
		(start 62.998096 -135.829294)
		(end 62.10935 -135.829294)
		(width 0.127)
		(layer "F.Cu")
		(net "SLOTID_0")
	)
	(segment
		(start 62.10935 -135.829294)
		(end 61.611764 -135.331708)
		(width 0.127)
		(layer "F.Cu")
		(net "SLOTID_0")
	)
	(segment
		(start 56.215788 -138.999976)
		(end 56.099964 -138.999976)
		(width 0.127)
		(layer "F.Cu")
		(net "SLOTID_0")
	)
	(via
		(at 63.6778 -134.747)
		(size 0.6604)
		(drill 0.3302)
		(layers "F.Cu" "B.Cu")
		(net "SLOTID_0")
	)
	(via
		(at 97.024444 -130.970274)
		(size 0.508)
		(drill 0.254)
		(layers "F.Cu" "B.Cu")
		(net "SLOTID_0")
	)
	(via
		(at 63.2587 -133.8961)
		(size 0.508)
		(drill 0.254)
		(layers "F.Cu" "B.Cu")
		(net "SLOTID_0")
	)
	(segment
		(start 117.899942 -44.000166)
		(end 118.471442 -43.428666)
		(width 0.127)
		(layer "In2.Cu")
		(net "SLOTID_0")
	)
	(segment
		(start 96.197166 -130.142996)
		(end 97.024444 -130.970274)
		(width 0.127)
		(layer "In2.Cu")
		(net "SLOTID_0")
	)
	(segment
		(start 98.215958 -83.209384)
		(end 97.869502 -83.55584)
		(width 0.127)
		(layer "In2.Cu")
		(net "SLOTID_0")
	)
	(segment
		(start 104.554274 -25.740106)
		(end 99.514914 -30.779466)
		(width 0.127)
		(layer "In2.Cu")
		(net "SLOTID_0")
	)
	(segment
		(start 98.215958 -43.388788)
		(end 98.215958 -83.209384)
		(width 0.127)
		(layer "In2.Cu")
		(net "SLOTID_0")
	)
	(segment
		(start 95.55861 -124.726446)
		(end 95.55861 -126.15418)
		(width 0.127)
		(layer "In2.Cu")
		(net "SLOTID_0")
	)
	(segment
		(start 99.514914 -30.779466)
		(end 99.514914 -42.089832)
		(width 0.127)
		(layer "In2.Cu")
		(net "SLOTID_0")
	)
	(segment
		(start 96.488504 -113.465864)
		(end 96.488504 -117.48262)
		(width 0.127)
		(layer "In2.Cu")
		(net "SLOTID_0")
	)
	(segment
		(start 97.869502 -112.084866)
		(end 96.488504 -113.465864)
		(width 0.127)
		(layer "In2.Cu")
		(net "SLOTID_0")
	)
	(segment
		(start 97.869502 -83.55584)
		(end 97.869502 -112.084866)
		(width 0.127)
		(layer "In2.Cu")
		(net "SLOTID_0")
	)
	(segment
		(start 96.012 -120.73255)
		(end 95.816166 -120.928384)
		(width 0.127)
		(layer "In2.Cu")
		(net "SLOTID_0")
	)
	(segment
		(start 118.471442 -43.428666)
		(end 118.471442 -27.93365)
		(width 0.127)
		(layer "In2.Cu")
		(net "SLOTID_0")
	)
	(segment
		(start 95.55861 -126.15418)
		(end 96.197166 -126.792736)
		(width 0.127)
		(layer "In2.Cu")
		(net "SLOTID_0")
	)
	(segment
		(start 95.816166 -120.928384)
		(end 95.816166 -124.46889)
		(width 0.127)
		(layer "In2.Cu")
		(net "SLOTID_0")
	)
	(segment
		(start 116.277898 -25.740106)
		(end 104.554274 -25.740106)
		(width 0.127)
		(layer "In2.Cu")
		(net "SLOTID_0")
	)
	(segment
		(start 118.471442 -27.93365)
		(end 116.277898 -25.740106)
		(width 0.127)
		(layer "In2.Cu")
		(net "SLOTID_0")
	)
	(segment
		(start 95.816166 -124.46889)
		(end 95.55861 -124.726446)
		(width 0.127)
		(layer "In2.Cu")
		(net "SLOTID_0")
	)
	(segment
		(start 96.012 -117.959124)
		(end 96.012 -120.73255)
		(width 0.127)
		(layer "In2.Cu")
		(net "SLOTID_0")
	)
	(segment
		(start 96.197166 -126.792736)
		(end 96.197166 -130.142996)
		(width 0.127)
		(layer "In2.Cu")
		(net "SLOTID_0")
	)
	(segment
		(start 99.514914 -42.089832)
		(end 98.215958 -43.388788)
		(width 0.127)
		(layer "In2.Cu")
		(net "SLOTID_0")
	)
	(segment
		(start 96.488504 -117.48262)
		(end 96.012 -117.959124)
		(width 0.127)
		(layer "In2.Cu")
		(net "SLOTID_0")
	)
	(segment
		(start 92.777818 -132.94614)
		(end 92.780612 -132.948934)
		(width 0.127)
		(layer "In5.Cu")
		(net "SLOTID_0")
	)
	(segment
		(start 94.063312 -133.162294)
		(end 95.181674 -133.162294)
		(width 0.127)
		(layer "In5.Cu")
		(net "SLOTID_0")
	)
	(segment
		(start 63.2587 -133.8961)
		(end 64.590676 -133.8961)
		(width 0.127)
		(layer "In5.Cu")
		(net "SLOTID_0")
	)
	(segment
		(start 92.172028 -133.162294)
		(end 92.388182 -132.94614)
		(width 0.127)
		(layer "In5.Cu")
		(net "SLOTID_0")
	)
	(segment
		(start 97.066862 -131.277106)
		(end 97.066862 -131.012692)
		(width 0.127)
		(layer "In5.Cu")
		(net "SLOTID_0")
	)
	(segment
		(start 93.849952 -132.948934)
		(end 94.063312 -133.162294)
		(width 0.127)
		(layer "In5.Cu")
		(net "SLOTID_0")
	)
	(segment
		(start 95.181674 -133.162294)
		(end 97.066862 -131.277106)
		(width 0.127)
		(layer "In5.Cu")
		(net "SLOTID_0")
	)
	(segment
		(start 65.708276 -132.7785)
		(end 66.226182 -132.7785)
		(width 0.127)
		(layer "In5.Cu")
		(net "SLOTID_0")
	)
	(segment
		(start 74.000868 -133.75132)
		(end 79.844646 -133.75132)
		(width 0.127)
		(layer "In5.Cu")
		(net "SLOTID_0")
	)
	(segment
		(start 66.294508 -132.710174)
		(end 72.959722 -132.710174)
		(width 0.127)
		(layer "In5.Cu")
		(net "SLOTID_0")
	)
	(segment
		(start 92.388182 -132.94614)
		(end 92.777818 -132.94614)
		(width 0.127)
		(layer "In5.Cu")
		(net "SLOTID_0")
	)
	(segment
		(start 66.226182 -132.7785)
		(end 66.294508 -132.710174)
		(width 0.127)
		(layer "In5.Cu")
		(net "SLOTID_0")
	)
	(segment
		(start 97.066862 -131.012692)
		(end 97.024444 -130.970274)
		(width 0.127)
		(layer "In5.Cu")
		(net "SLOTID_0")
	)
	(segment
		(start 92.780612 -132.948934)
		(end 93.849952 -132.948934)
		(width 0.127)
		(layer "In5.Cu")
		(net "SLOTID_0")
	)
	(segment
		(start 72.959722 -132.710174)
		(end 74.000868 -133.75132)
		(width 0.127)
		(layer "In5.Cu")
		(net "SLOTID_0")
	)
	(segment
		(start 79.844646 -133.75132)
		(end 80.433672 -133.162294)
		(width 0.127)
		(layer "In5.Cu")
		(net "SLOTID_0")
	)
	(segment
		(start 80.433672 -133.162294)
		(end 92.172028 -133.162294)
		(width 0.127)
		(layer "In5.Cu")
		(net "SLOTID_0")
	)
	(segment
		(start 64.590676 -133.8961)
		(end 65.708276 -132.7785)
		(width 0.127)
		(layer "In5.Cu")
		(net "SLOTID_0")
	)
	(segment
		(start 191.413384 -73.102216)
		(end 191.185292 -73.330308)
		(width 0.2032)
		(layer "F.Cu")
		(net "PCE_VDDH")
	)
	(segment
		(start 191.998092 -73.102216)
		(end 191.413384 -73.102216)
		(width 0.2032)
		(layer "F.Cu")
		(net "PCE_VDDH")
	)
	(segment
		(start 192.39992 -72.700388)
		(end 191.998092 -73.102216)
		(width 0.254)
		(layer "F.Cu")
		(net "PCE_VDDH")
	)
	(segment
		(start 191.185292 -73.914508)
		(end 190.799974 -74.299826)
		(width 0.2032)
		(layer "F.Cu")
		(net "PCE_VDDH")
	)
	(segment
		(start 195.600066 -72.69988)
		(end 195.999862 -73.099676)
		(width 0.3048)
		(layer "F.Cu")
		(net "PCE_VDDH")
	)
	(segment
		(start 193.209418 -75.099926)
		(end 193.20002 -75.099926)
		(width 0.3048)
		(layer "F.Cu")
		(net "PCE_VDDH")
	)
	(segment
		(start 198.799958 -72.69988)
		(end 199.199754 -73.099676)
		(width 0.3048)
		(layer "F.Cu")
		(net "PCE_VDDH")
	)
	(segment
		(start 193.999866 -72.69988)
		(end 194.399662 -73.099676)
		(width 0.3048)
		(layer "F.Cu")
		(net "PCE_VDDH")
	)
	(segment
		(start 197.200012 -72.69988)
		(end 197.599808 -73.099676)
		(width 0.3048)
		(layer "F.Cu")
		(net "PCE_VDDH")
	)
	(segment
		(start 198.396352 -74.699876)
		(end 197.999858 -74.303382)
		(width 0.3048)
		(layer "F.Cu")
		(net "PCE_VDDH")
	)
	(segment
		(start 193.60515 -75.495658)
		(end 193.209418 -75.099926)
		(width 0.3048)
		(layer "F.Cu")
		(net "PCE_VDDH")
	)
	(segment
		(start 192.39992 -72.69988)
		(end 192.39992 -72.700388)
		(width 0.254)
		(layer "F.Cu")
		(net "PCE_VDDH")
	)
	(segment
		(start 197.999858 -74.303382)
		(end 197.999858 -74.299826)
		(width 0.3048)
		(layer "F.Cu")
		(net "PCE_VDDH")
	)
	(segment
		(start 195.600066 -74.299826)
		(end 195.999862 -74.699622)
		(width 0.3048)
		(layer "F.Cu")
		(net "PCE_VDDH")
	)
	(segment
		(start 191.185292 -73.330308)
		(end 191.185292 -73.914508)
		(width 0.2032)
		(layer "F.Cu")
		(net "PCE_VDDH")
	)
	(via
		(at 198.396352 -74.699876)
		(size 0.4572)
		(drill 0.2032)
		(layers "F.Cu" "B.Cu")
		(net "PCE_VDDH")
	)
	(via
		(at 193.60515 -75.495658)
		(size 0.508)
		(drill 0.254)
		(layers "F.Cu" "B.Cu")
		(net "PCE_VDDH")
	)
	(via
		(at 202.783186 -89.321386)
		(size 0.7112)
		(drill 0.4064)
		(layers "F.Cu" "B.Cu")
		(net "PCE_VDDH")
	)
	(via
		(at 194.399662 -73.099676)
		(size 0.508)
		(drill 0.254)
		(layers "F.Cu" "B.Cu")
		(net "PCE_VDDH")
	)
	(via
		(at 195.999862 -74.699622)
		(size 0.4572)
		(drill 0.2032)
		(layers "F.Cu" "B.Cu")
		(net "PCE_VDDH")
	)
	(via
		(at 191.998092 -73.102216)
		(size 0.508)
		(drill 0.254)
		(layers "F.Cu" "B.Cu")
		(net "PCE_VDDH")
	)
	(via
		(at 201.979022 -90.30716)
		(size 0.7112)
		(drill 0.4064)
		(layers "F.Cu" "B.Cu")
		(net "PCE_VDDH")
	)
	(via
		(at 201.113644 -91.186254)
		(size 0.7112)
		(drill 0.4064)
		(layers "F.Cu" "B.Cu")
		(net "PCE_VDDH")
	)
	(via
		(at 199.199754 -73.099676)
		(size 0.508)
		(drill 0.254)
		(layers "F.Cu" "B.Cu")
		(net "PCE_VDDH")
	)
	(via
		(at 203.67752 -90.291666)
		(size 0.6096)
		(drill 0.3048)
		(layers "F.Cu" "B.Cu")
		(net "PCE_VDDH")
	)
	(via
		(at 197.599808 -73.099676)
		(size 0.508)
		(drill 0.254)
		(layers "F.Cu" "B.Cu")
		(net "PCE_VDDH")
	)
	(via
		(at 195.999862 -73.099676)
		(size 0.508)
		(drill 0.254)
		(layers "F.Cu" "B.Cu")
		(net "PCE_VDDH")
	)
	(segment
		(start 191.897508 -73.2028)
		(end 191.998092 -73.102216)
		(width 0.254)
		(layer "B.Cu")
		(net "PCE_VDDH")
	)
	(segment
		(start 199.718422 -72.5932)
		(end 199.211946 -73.099676)
		(width 0.254)
		(layer "B.Cu")
		(net "PCE_VDDH")
	)
	(segment
		(start 191.008 -73.2028)
		(end 191.897508 -73.2028)
		(width 0.254)
		(layer "B.Cu")
		(net "PCE_VDDH")
	)
	(segment
		(start 197.07606 -72.575928)
		(end 197.599808 -73.099676)
		(width 0.3048)
		(layer "B.Cu")
		(net "PCE_VDDH")
	)
	(segment
		(start 194.558666 -72.380856)
		(end 194.558666 -72.940672)
		(width 0.3048)
		(layer "B.Cu")
		(net "PCE_VDDH")
	)
	(segment
		(start 194.558666 -72.940672)
		(end 194.399662 -73.099676)
		(width 0.3048)
		(layer "B.Cu")
		(net "PCE_VDDH")
	)
	(segment
		(start 199.211946 -73.099676)
		(end 199.199754 -73.099676)
		(width 0.254)
		(layer "B.Cu")
		(net "PCE_VDDH")
	)
	(segment
		(start 197.07606 -72.34428)
		(end 197.07606 -72.575928)
		(width 0.3048)
		(layer "B.Cu")
		(net "PCE_VDDH")
	)
	(segment
		(start 117.6528 -15.0241)
		(end 117.6528 -17.267936)
		(width 0.508)
		(layer "F.Cu")
		(net "P12V_IOM")
	)
	(segment
		(start 121.992898 -20.32762)
		(end 122.696478 -21.0312)
		(width 0.508)
		(layer "F.Cu")
		(net "P12V_IOM")
	)
	(segment
		(start 120.712484 -20.32762)
		(end 121.992898 -20.32762)
		(width 0.508)
		(layer "F.Cu")
		(net "P12V_IOM")
	)
	(segment
		(start 127.0635 -21.0312)
		(end 127.9017 -20.193)
		(width 0.508)
		(layer "F.Cu")
		(net "P12V_IOM")
	)
	(segment
		(start 117.6528 -17.267936)
		(end 120.712484 -20.32762)
		(width 0.508)
		(layer "F.Cu")
		(net "P12V_IOM")
	)
	(segment
		(start 122.696478 -21.0312)
		(end 127.0635 -21.0312)
		(width 0.508)
		(layer "F.Cu")
		(net "P12V_IOM")
	)
	(via
		(at 129.8194 -17.79524)
		(size 0.7112)
		(drill 0.4064)
		(layers "F.Cu" "B.Cu")
		(net "P12V_IOM")
	)
	(via
		(at 127.9017 -20.193)
		(size 0.7112)
		(drill 0.4064)
		(layers "F.Cu" "B.Cu")
		(net "P12V_IOM")
	)
	(via
		(at 129.201672 -20.220178)
		(size 0.7112)
		(drill 0.4064)
		(layers "F.Cu" "B.Cu")
		(net "P12V_IOM")
	)
	(via
		(at 133.4008 -18.14576)
		(size 0.7112)
		(drill 0.4064)
		(layers "F.Cu" "B.Cu")
		(net "P12V_IOM")
	)
	(via
		(at 131.223512 -18.238724)
		(size 0.7112)
		(drill 0.4064)
		(layers "F.Cu" "B.Cu")
		(net "P12V_IOM")
	)
	(via
		(at 130.8608 -16.87576)
		(size 0.7112)
		(drill 0.4064)
		(layers "F.Cu" "B.Cu")
		(net "P12V_IOM")
	)
	(via
		(at 132.08 -16.1036)
		(size 0.7112)
		(drill 0.4064)
		(layers "F.Cu" "B.Cu")
		(net "P12V_IOM")
	)
	(via
		(at 125.6792 -18.8214)
		(size 0.6096)
		(drill 0.3048)
		(layers "F.Cu" "B.Cu")
		(net "P12V_IOM")
	)
	(via
		(at 132.22859 -17.360392)
		(size 0.7112)
		(drill 0.4064)
		(layers "F.Cu" "B.Cu")
		(net "P12V_IOM")
	)
	(via
		(at 129.8194 -19.06524)
		(size 0.7112)
		(drill 0.4064)
		(layers "F.Cu" "B.Cu")
		(net "P12V_IOM")
	)
	(via
		(at 128.5494 -19.06524)
		(size 0.7112)
		(drill 0.4064)
		(layers "F.Cu" "B.Cu")
		(net "P12V_IOM")
	)
	(segment
		(start 91.567 -87.2998)
		(end 91.567 -67.180968)
		(width 0.127)
		(layer "F.Cu")
		(net "P12V_A_PGOOD")
	)
	(segment
		(start 129.819654 -42.119804)
		(end 130.499866 -42.800016)
		(width 0.127)
		(layer "F.Cu")
		(net "P12V_A_PGOOD")
	)
	(segment
		(start 128.208024 -26.133298)
		(end 129.819654 -27.744928)
		(width 0.127)
		(layer "F.Cu")
		(net "P12V_A_PGOOD")
	)
	(segment
		(start 92.7354 -88.4682)
		(end 91.567 -87.2998)
		(width 0.127)
		(layer "F.Cu")
		(net "P12V_A_PGOOD")
	)
	(segment
		(start 129.819654 -27.744928)
		(end 129.819654 -42.119804)
		(width 0.127)
		(layer "F.Cu")
		(net "P12V_A_PGOOD")
	)
	(segment
		(start 121.886726 -26.133298)
		(end 128.208024 -26.133298)
		(width 0.127)
		(layer "F.Cu")
		(net "P12V_A_PGOOD")
	)
	(segment
		(start 121.703338 -25.94991)
		(end 121.886726 -26.133298)
		(width 0.127)
		(layer "F.Cu")
		(net "P12V_A_PGOOD")
	)
	(segment
		(start 89.098628 -64.712596)
		(end 88.260428 -64.712596)
		(width 0.127)
		(layer "F.Cu")
		(net "P12V_A_PGOOD")
	)
	(segment
		(start 91.567 -67.180968)
		(end 89.098628 -64.712596)
		(width 0.127)
		(layer "F.Cu")
		(net "P12V_A_PGOOD")
	)
	(via
		(at 110.783116 -18.40738)
		(size 0.6096)
		(drill 0.3048)
		(layers "F.Cu" "B.Cu")
		(net "P12V_A_PGOOD")
	)
	(via
		(at 92.7354 -88.4682)
		(size 0.508)
		(drill 0.254)
		(layers "F.Cu" "B.Cu")
		(net "P12V_A_PGOOD")
	)
	(via
		(at 121.703338 -25.94991)
		(size 0.508)
		(drill 0.254)
		(layers "F.Cu" "B.Cu")
		(net "P12V_A_PGOOD")
	)
	(via
		(at 53.2892 -121.539)
		(size 0.508)
		(drill 0.254)
		(layers "F.Cu" "B.Cu")
		(net "P12V_A_PGOOD")
	)
	(via
		(at 98.894646 -121.9454)
		(size 0.508)
		(drill 0.254)
		(layers "F.Cu" "B.Cu")
		(net "P12V_A_PGOOD")
	)
	(via
		(at 88.260428 -64.712596)
		(size 0.508)
		(drill 0.254)
		(layers "F.Cu" "B.Cu")
		(net "P12V_A_PGOOD")
	)
	(segment
		(start 121.703338 -25.94991)
		(end 121.267474 -25.514046)
		(width 0.127)
		(layer "B.Cu")
		(net "P12V_A_PGOOD")
	)
	(segment
		(start 115.3033 -8.5344)
		(end 114.92357 -8.91413)
		(width 0.127)
		(layer "B.Cu")
		(net "P12V_A_PGOOD")
	)
	(segment
		(start 112.004856 -19.62912)
		(end 110.783116 -18.40738)
		(width 0.127)
		(layer "B.Cu")
		(net "P12V_A_PGOOD")
	)
	(segment
		(start 98.894646 -121.9454)
		(end 100.358448 -120.481598)
		(width 0.127)
		(layer "B.Cu")
		(net "P12V_A_PGOOD")
	)
	(segment
		(start 53.2892 -121.539)
		(end 52.0065 -122.8217)
		(width 0.127)
		(layer "B.Cu")
		(net "P12V_A_PGOOD")
	)
	(segment
		(start 51.8033 -122.8217)
		(end 50.30978 -124.31522)
		(width 0.127)
		(layer "B.Cu")
		(net "P12V_A_PGOOD")
	)
	(segment
		(start 109.384846 -17.00911)
		(end 110.783116 -18.40738)
		(width 0.127)
		(layer "B.Cu")
		(net "P12V_A_PGOOD")
	)
	(segment
		(start 93.88729 -89.62009)
		(end 92.7354 -88.4682)
		(width 0.127)
		(layer "B.Cu")
		(net "P12V_A_PGOOD")
	)
	(segment
		(start 100.358448 -93.433392)
		(end 96.545146 -89.62009)
		(width 0.127)
		(layer "B.Cu")
		(net "P12V_A_PGOOD")
	)
	(segment
		(start 121.267474 -25.514046)
		(end 121.267474 -24.226012)
		(width 0.127)
		(layer "B.Cu")
		(net "P12V_A_PGOOD")
	)
	(segment
		(start 121.267474 -24.226012)
		(end 116.670582 -19.62912)
		(width 0.127)
		(layer "B.Cu")
		(net "P12V_A_PGOOD")
	)
	(segment
		(start 50.30978 -125.35408)
		(end 50.772568 -125.816868)
		(width 0.127)
		(layer "B.Cu")
		(net "P12V_A_PGOOD")
	)
	(segment
		(start 52.0065 -122.8217)
		(end 51.8033 -122.8217)
		(width 0.127)
		(layer "B.Cu")
		(net "P12V_A_PGOOD")
	)
	(segment
		(start 109.384846 -15.807436)
		(end 109.384846 -17.00911)
		(width 0.127)
		(layer "B.Cu")
		(net "P12V_A_PGOOD")
	)
	(segment
		(start 114.0714 -13.2588)
		(end 111.933482 -13.2588)
		(width 0.127)
		(layer "B.Cu")
		(net "P12V_A_PGOOD")
	)
	(segment
		(start 50.772568 -125.816868)
		(end 50.772568 -126.891288)
		(width 0.127)
		(layer "B.Cu")
		(net "P12V_A_PGOOD")
	)
	(segment
		(start 114.92357 -12.40663)
		(end 114.0714 -13.2588)
		(width 0.127)
		(layer "B.Cu")
		(net "P12V_A_PGOOD")
	)
	(segment
		(start 114.92357 -8.91413)
		(end 114.92357 -12.40663)
		(width 0.127)
		(layer "B.Cu")
		(net "P12V_A_PGOOD")
	)
	(segment
		(start 96.545146 -89.62009)
		(end 93.88729 -89.62009)
		(width 0.127)
		(layer "B.Cu")
		(net "P12V_A_PGOOD")
	)
	(segment
		(start 111.933482 -13.2588)
		(end 109.384846 -15.807436)
		(width 0.127)
		(layer "B.Cu")
		(net "P12V_A_PGOOD")
	)
	(segment
		(start 116.670582 -19.62912)
		(end 112.004856 -19.62912)
		(width 0.127)
		(layer "B.Cu")
		(net "P12V_A_PGOOD")
	)
	(segment
		(start 50.30978 -124.31522)
		(end 50.30978 -125.35408)
		(width 0.127)
		(layer "B.Cu")
		(net "P12V_A_PGOOD")
	)
	(segment
		(start 100.358448 -120.481598)
		(end 100.358448 -93.433392)
		(width 0.127)
		(layer "B.Cu")
		(net "P12V_A_PGOOD")
	)
	(segment
		(start 118.216172 -25.201372)
		(end 103.241602 -25.201372)
		(width 0.127)
		(layer "In5.Cu")
		(net "P12V_A_PGOOD")
	)
	(segment
		(start 54.6608 -121.539)
		(end 55.207916 -120.991884)
		(width 0.127)
		(layer "In5.Cu")
		(net "P12V_A_PGOOD")
	)
	(segment
		(start 53.2892 -121.539)
		(end 54.6608 -121.539)
		(width 0.127)
		(layer "In5.Cu")
		(net "P12V_A_PGOOD")
	)
	(segment
		(start 103.241602 -25.201372)
		(end 92.419424 -32.361124)
		(width 0.127)
		(layer "In5.Cu")
		(net "P12V_A_PGOOD")
	)
	(segment
		(start 118.96471 -25.94991)
		(end 118.216172 -25.201372)
		(width 0.127)
		(layer "In5.Cu")
		(net "P12V_A_PGOOD")
	)
	(segment
		(start 68.704206 -121.3739)
		(end 68.704714 -121.374154)
		(width 0.127)
		(layer "In5.Cu")
		(net "P12V_A_PGOOD")
	)
	(segment
		(start 71.958962 -121.3739)
		(end 75.79741 -125.212348)
		(width 0.127)
		(layer "In5.Cu")
		(net "P12V_A_PGOOD")
	)
	(segment
		(start 97.343468 -121.811034)
		(end 97.477834 -121.9454)
		(width 0.127)
		(layer "In5.Cu")
		(net "P12V_A_PGOOD")
	)
	(segment
		(start 68.32219 -120.991884)
		(end 68.704206 -121.3739)
		(width 0.127)
		(layer "In5.Cu")
		(net "P12V_A_PGOOD")
	)
	(segment
		(start 75.79741 -125.212348)
		(end 82.879184 -125.212348)
		(width 0.127)
		(layer "In5.Cu")
		(net "P12V_A_PGOOD")
	)
	(segment
		(start 69.020182 -121.374154)
		(end 69.020436 -121.3739)
		(width 0.127)
		(layer "In5.Cu")
		(net "P12V_A_PGOOD")
	)
	(segment
		(start 69.020436 -121.3739)
		(end 71.958962 -121.3739)
		(width 0.127)
		(layer "In5.Cu")
		(net "P12V_A_PGOOD")
	)
	(segment
		(start 87.784686 -64.236854)
		(end 88.260428 -64.712596)
		(width 0.127)
		(layer "In5.Cu")
		(net "P12V_A_PGOOD")
	)
	(segment
		(start 68.704714 -121.374154)
		(end 69.020182 -121.374154)
		(width 0.127)
		(layer "In5.Cu")
		(net "P12V_A_PGOOD")
	)
	(segment
		(start 82.879184 -125.212348)
		(end 85.739732 -122.3518)
		(width 0.127)
		(layer "In5.Cu")
		(net "P12V_A_PGOOD")
	)
	(segment
		(start 55.207916 -120.991884)
		(end 68.32219 -120.991884)
		(width 0.127)
		(layer "In5.Cu")
		(net "P12V_A_PGOOD")
	)
	(segment
		(start 121.703338 -25.94991)
		(end 118.96471 -25.94991)
		(width 0.127)
		(layer "In5.Cu")
		(net "P12V_A_PGOOD")
	)
	(segment
		(start 90.081862 -35.855656)
		(end 88.371426 -44.41698)
		(width 0.127)
		(layer "In5.Cu")
		(net "P12V_A_PGOOD")
	)
	(segment
		(start 85.739732 -122.3518)
		(end 93.5736 -122.3518)
		(width 0.127)
		(layer "In5.Cu")
		(net "P12V_A_PGOOD")
	)
	(segment
		(start 93.5736 -122.3518)
		(end 94.114366 -121.811034)
		(width 0.127)
		(layer "In5.Cu")
		(net "P12V_A_PGOOD")
	)
	(segment
		(start 97.477834 -121.9454)
		(end 98.894646 -121.9454)
		(width 0.127)
		(layer "In5.Cu")
		(net "P12V_A_PGOOD")
	)
	(segment
		(start 87.784686 -45.00372)
		(end 87.784686 -64.236854)
		(width 0.127)
		(layer "In5.Cu")
		(net "P12V_A_PGOOD")
	)
	(segment
		(start 92.419424 -32.361124)
		(end 90.081862 -35.855656)
		(width 0.127)
		(layer "In5.Cu")
		(net "P12V_A_PGOOD")
	)
	(segment
		(start 94.114366 -121.811034)
		(end 97.343468 -121.811034)
		(width 0.127)
		(layer "In5.Cu")
		(net "P12V_A_PGOOD")
	)
	(segment
		(start 88.371426 -44.41698)
		(end 87.784686 -45.00372)
		(width 0.127)
		(layer "In5.Cu")
		(net "P12V_A_PGOOD")
	)
	(segment
		(start 46.49978 -138.999976)
		(end 46.500034 -138.999976)
		(width 0.127)
		(layer "F.Cu")
		(net "IOM_LOC_INS_N")
	)
	(segment
		(start 46.100238 -138.600434)
		(end 46.49978 -138.999976)
		(width 0.127)
		(layer "F.Cu")
		(net "IOM_LOC_INS_N")
	)
	(via
		(at 45.432726 -129.487422)
		(size 0.508)
		(drill 0.254)
		(layers "F.Cu" "B.Cu")
		(net "IOM_LOC_INS_N")
	)
	(via
		(at 46.100238 -138.600434)
		(size 0.4572)
		(drill 0.2032)
		(layers "F.Cu" "B.Cu")
		(net "IOM_LOC_INS_N")
	)
	(via
		(at 44.704 -116.8908)
		(size 0.508)
		(drill 0.254)
		(layers "F.Cu" "B.Cu")
		(net "IOM_LOC_INS_N")
	)
	(via
		(at 88.011 -110.5408)
		(size 0.508)
		(drill 0.254)
		(layers "F.Cu" "B.Cu")
		(net "IOM_LOC_INS_N")
	)
	(segment
		(start 45.466 -129.454148)
		(end 45.432726 -129.487422)
		(width 0.127)
		(layer "B.Cu")
		(net "IOM_LOC_INS_N")
	)
	(segment
		(start 45.466 -128.6637)
		(end 45.466 -129.454148)
		(width 0.127)
		(layer "B.Cu")
		(net "IOM_LOC_INS_N")
	)
	(segment
		(start 97.020634 -15.388844)
		(end 97.020888 -15.38859)
		(width 0.127)
		(layer "In2.Cu")
		(net "IOM_LOC_INS_N")
	)
	(segment
		(start 89.105232 -109.446568)
		(end 89.105232 -64.36614)
		(width 0.127)
		(layer "In2.Cu")
		(net "IOM_LOC_INS_N")
	)
	(segment
		(start 119.227854 -21.32457)
		(end 120.85574 -21.32457)
		(width 0.127)
		(layer "In2.Cu")
		(net "IOM_LOC_INS_N")
	)
	(segment
		(start 134.671562 -40.028622)
		(end 134.100062 -40.600122)
		(width 0.127)
		(layer "In2.Cu")
		(net "IOM_LOC_INS_N")
	)
	(segment
		(start 126.631192 -24.552402)
		(end 129.58699 -27.5082)
		(width 0.127)
		(layer "In2.Cu")
		(net "IOM_LOC_INS_N")
	)
	(segment
		(start 45.2882 -132.075174)
		(end 45.2882 -133.865366)
		(width 0.127)
		(layer "In2.Cu")
		(net "IOM_LOC_INS_N")
	)
	(segment
		(start 87.434928 -62.695836)
		(end 87.434928 -44.510706)
		(width 0.127)
		(layer "In2.Cu")
		(net "IOM_LOC_INS_N")
	)
	(segment
		(start 95.187262 -11.146282)
		(end 95.187262 -13.87094)
		(width 0.127)
		(layer "In2.Cu")
		(net "IOM_LOC_INS_N")
	)
	(segment
		(start 88.011 -110.5408)
		(end 89.105232 -109.446568)
		(width 0.127)
		(layer "In2.Cu")
		(net "IOM_LOC_INS_N")
	)
	(segment
		(start 89.00033 -36.383976)
		(end 82.54238 -29.926026)
		(width 0.127)
		(layer "In2.Cu")
		(net "IOM_LOC_INS_N")
	)
	(segment
		(start 89.00033 -42.945304)
		(end 89.00033 -36.383976)
		(width 0.127)
		(layer "In2.Cu")
		(net "IOM_LOC_INS_N")
	)
	(segment
		(start 129.58699 -27.5082)
		(end 131.516374 -27.5082)
		(width 0.127)
		(layer "In2.Cu")
		(net "IOM_LOC_INS_N")
	)
	(segment
		(start 84.493862 -9.057386)
		(end 86.377018 -9.057386)
		(width 0.127)
		(layer "In2.Cu")
		(net "IOM_LOC_INS_N")
	)
	(segment
		(start 93.09862 -9.05764)
		(end 95.187262 -11.146282)
		(width 0.127)
		(layer "In2.Cu")
		(net "IOM_LOC_INS_N")
	)
	(segment
		(start 97.664778 -15.38859)
		(end 102.173024 -19.896836)
		(width 0.127)
		(layer "In2.Cu")
		(net "IOM_LOC_INS_N")
	)
	(segment
		(start 126.631192 -24.552148)
		(end 126.631192 -24.552402)
		(width 0.127)
		(layer "In2.Cu")
		(net "IOM_LOC_INS_N")
	)
	(segment
		(start 45.9359 -118.1227)
		(end 44.704 -116.8908)
		(width 0.127)
		(layer "In2.Cu")
		(net "IOM_LOC_INS_N")
	)
	(segment
		(start 125.772418 -23.693374)
		(end 126.631192 -24.552148)
		(width 0.127)
		(layer "In2.Cu")
		(net "IOM_LOC_INS_N")
	)
	(segment
		(start 82.54238 -11.008868)
		(end 84.493862 -9.057386)
		(width 0.127)
		(layer "In2.Cu")
		(net "IOM_LOC_INS_N")
	)
	(segment
		(start 45.432726 -129.487422)
		(end 44.962826 -129.957322)
		(width 0.127)
		(layer "In2.Cu")
		(net "IOM_LOC_INS_N")
	)
	(segment
		(start 97.020888 -15.38859)
		(end 97.664778 -15.38859)
		(width 0.127)
		(layer "In2.Cu")
		(net "IOM_LOC_INS_N")
	)
	(segment
		(start 89.105232 -64.36614)
		(end 87.434928 -62.695836)
		(width 0.127)
		(layer "In2.Cu")
		(net "IOM_LOC_INS_N")
	)
	(segment
		(start 44.962826 -131.7498)
		(end 45.2882 -132.075174)
		(width 0.127)
		(layer "In2.Cu")
		(net "IOM_LOC_INS_N")
	)
	(segment
		(start 120.85574 -21.32457)
		(end 123.224544 -23.693374)
		(width 0.127)
		(layer "In2.Cu")
		(net "IOM_LOC_INS_N")
	)
	(segment
		(start 82.54238 -29.926026)
		(end 82.54238 -11.008868)
		(width 0.127)
		(layer "In2.Cu")
		(net "IOM_LOC_INS_N")
	)
	(segment
		(start 86.377018 -9.057386)
		(end 86.377272 -9.05764)
		(width 0.127)
		(layer "In2.Cu")
		(net "IOM_LOC_INS_N")
	)
	(segment
		(start 44.962826 -129.957322)
		(end 44.962826 -131.7498)
		(width 0.127)
		(layer "In2.Cu")
		(net "IOM_LOC_INS_N")
	)
	(segment
		(start 87.434928 -44.510706)
		(end 89.00033 -42.945304)
		(width 0.127)
		(layer "In2.Cu")
		(net "IOM_LOC_INS_N")
	)
	(segment
		(start 46.074076 -138.600434)
		(end 46.100238 -138.600434)
		(width 0.127)
		(layer "In2.Cu")
		(net "IOM_LOC_INS_N")
	)
	(segment
		(start 45.432726 -129.487422)
		(end 45.9359 -128.984248)
		(width 0.127)
		(layer "In2.Cu")
		(net "IOM_LOC_INS_N")
	)
	(segment
		(start 45.2882 -133.865366)
		(end 45.41139 -133.988556)
		(width 0.127)
		(layer "In2.Cu")
		(net "IOM_LOC_INS_N")
	)
	(segment
		(start 45.41139 -137.937748)
		(end 46.074076 -138.600434)
		(width 0.127)
		(layer "In2.Cu")
		(net "IOM_LOC_INS_N")
	)
	(segment
		(start 102.173024 -19.896836)
		(end 117.80012 -19.896836)
		(width 0.127)
		(layer "In2.Cu")
		(net "IOM_LOC_INS_N")
	)
	(segment
		(start 95.187262 -13.87094)
		(end 96.705166 -15.388844)
		(width 0.127)
		(layer "In2.Cu")
		(net "IOM_LOC_INS_N")
	)
	(segment
		(start 123.224544 -23.693374)
		(end 125.772418 -23.693374)
		(width 0.127)
		(layer "In2.Cu")
		(net "IOM_LOC_INS_N")
	)
	(segment
		(start 96.705166 -15.388844)
		(end 97.020634 -15.388844)
		(width 0.127)
		(layer "In2.Cu")
		(net "IOM_LOC_INS_N")
	)
	(segment
		(start 131.516374 -27.5082)
		(end 134.671562 -30.663388)
		(width 0.127)
		(layer "In2.Cu")
		(net "IOM_LOC_INS_N")
	)
	(segment
		(start 134.671562 -30.663388)
		(end 134.671562 -40.028622)
		(width 0.127)
		(layer "In2.Cu")
		(net "IOM_LOC_INS_N")
	)
	(segment
		(start 45.41139 -133.988556)
		(end 45.41139 -137.937748)
		(width 0.127)
		(layer "In2.Cu")
		(net "IOM_LOC_INS_N")
	)
	(segment
		(start 86.377272 -9.05764)
		(end 93.09862 -9.05764)
		(width 0.127)
		(layer "In2.Cu")
		(net "IOM_LOC_INS_N")
	)
	(segment
		(start 45.9359 -128.984248)
		(end 45.9359 -118.1227)
		(width 0.127)
		(layer "In2.Cu")
		(net "IOM_LOC_INS_N")
	)
	(segment
		(start 117.80012 -19.896836)
		(end 119.227854 -21.32457)
		(width 0.127)
		(layer "In2.Cu")
		(net "IOM_LOC_INS_N")
	)
	(segment
		(start 61.7728 -114.1222)
		(end 61.341 -114.554)
		(width 0.127)
		(layer "In5.Cu")
		(net "IOM_LOC_INS_N")
	)
	(segment
		(start 69.893434 -114.1222)
		(end 61.7728 -114.1222)
		(width 0.127)
		(layer "In5.Cu")
		(net "IOM_LOC_INS_N")
	)
	(segment
		(start 56.063896 -114.274346)
		(end 47.320454 -114.274346)
		(width 0.127)
		(layer "In5.Cu")
		(net "IOM_LOC_INS_N")
	)
	(segment
		(start 87.249 -109.7788)
		(end 77.6986 -109.7788)
		(width 0.127)
		(layer "In5.Cu")
		(net "IOM_LOC_INS_N")
	)
	(segment
		(start 70.50913 -113.506504)
		(end 69.893434 -114.1222)
		(width 0.127)
		(layer "In5.Cu")
		(net "IOM_LOC_INS_N")
	)
	(segment
		(start 73.970896 -113.506504)
		(end 70.50913 -113.506504)
		(width 0.127)
		(layer "In5.Cu")
		(net "IOM_LOC_INS_N")
	)
	(segment
		(start 88.011 -110.5408)
		(end 87.249 -109.7788)
		(width 0.127)
		(layer "In5.Cu")
		(net "IOM_LOC_INS_N")
	)
	(segment
		(start 47.320454 -114.274346)
		(end 44.704 -116.8908)
		(width 0.127)
		(layer "In5.Cu")
		(net "IOM_LOC_INS_N")
	)
	(segment
		(start 77.6986 -109.7788)
		(end 73.970896 -113.506504)
		(width 0.127)
		(layer "In5.Cu")
		(net "IOM_LOC_INS_N")
	)
	(segment
		(start 56.34355 -114.554)
		(end 56.063896 -114.274346)
		(width 0.127)
		(layer "In5.Cu")
		(net "IOM_LOC_INS_N")
	)
	(segment
		(start 61.341 -114.554)
		(end 56.34355 -114.554)
		(width 0.127)
		(layer "In5.Cu")
		(net "IOM_LOC_INS_N")
	)
	(segment
		(start 65.278 -145.2118)
		(end 65.1637 -145.3261)
		(width 0.127)
		(layer "F.Cu")
		(net "I2C_SCC_SDA_OUT")
	)
	(segment
		(start 62.98946 -145.58264)
		(end 62.9031 -145.669)
		(width 0.127)
		(layer "F.Cu")
		(net "I2C_SCC_SDA_OUT")
	)
	(segment
		(start 65.1637 -145.3261)
		(end 64.28486 -145.3261)
		(width 0.127)
		(layer "F.Cu")
		(net "I2C_SCC_SDA_OUT")
	)
	(segment
		(start 81.97215 -144.99844)
		(end 84.05368 -144.99844)
		(width 0.127)
		(layer "F.Cu")
		(net "I2C_SCC_SDA_OUT")
	)
	(segment
		(start 62.98946 -145.48358)
		(end 62.98946 -145.58264)
		(width 0.127)
		(layer "F.Cu")
		(net "I2C_SCC_SDA_OUT")
	)
	(segment
		(start 64.28486 -145.3261)
		(end 64.005206 -145.046446)
		(width 0.127)
		(layer "F.Cu")
		(net "I2C_SCC_SDA_OUT")
	)
	(segment
		(start 84.370418 -145.315178)
		(end 85.349334 -145.315178)
		(width 0.127)
		(layer "F.Cu")
		(net "I2C_SCC_SDA_OUT")
	)
	(segment
		(start 63.426594 -145.046446)
		(end 62.98946 -145.48358)
		(width 0.127)
		(layer "F.Cu")
		(net "I2C_SCC_SDA_OUT")
	)
	(segment
		(start 84.05368 -144.99844)
		(end 84.370418 -145.315178)
		(width 0.127)
		(layer "F.Cu")
		(net "I2C_SCC_SDA_OUT")
	)
	(segment
		(start 64.005206 -145.046446)
		(end 63.426594 -145.046446)
		(width 0.127)
		(layer "F.Cu")
		(net "I2C_SCC_SDA_OUT")
	)
	(segment
		(start 81.522316 -145.448274)
		(end 81.97215 -144.99844)
		(width 0.127)
		(layer "F.Cu")
		(net "I2C_SCC_SDA_OUT")
	)
	(segment
		(start 62.9031 -145.669)
		(end 61.911738 -145.669)
		(width 0.127)
		(layer "F.Cu")
		(net "I2C_SCC_SDA_OUT")
	)
	(segment
		(start 61.911738 -145.669)
		(end 61.739272 -145.496534)
		(width 0.127)
		(layer "F.Cu")
		(net "I2C_SCC_SDA_OUT")
	)
	(via
		(at 65.278 -145.2118)
		(size 0.508)
		(drill 0.254)
		(layers "F.Cu" "B.Cu")
		(net "I2C_SCC_SDA_OUT")
	)
	(via
		(at 81.522316 -145.448274)
		(size 0.508)
		(drill 0.254)
		(layers "F.Cu" "B.Cu")
		(net "I2C_SCC_SDA_OUT")
	)
	(segment
		(start 67.406012 -145.280126)
		(end 66.83121 -144.705324)
		(width 0.127)
		(layer "In5.Cu")
		(net "I2C_SCC_SDA_OUT")
	)
	(segment
		(start 65.784476 -144.705324)
		(end 65.278 -145.2118)
		(width 0.127)
		(layer "In5.Cu")
		(net "I2C_SCC_SDA_OUT")
	)
	(segment
		(start 81.522316 -145.448274)
		(end 81.51495 -145.45564)
		(width 0.127)
		(layer "In5.Cu")
		(net "I2C_SCC_SDA_OUT")
	)
	(segment
		(start 73.300336 -145.45564)
		(end 73.124822 -145.280126)
		(width 0.127)
		(layer "In5.Cu")
		(net "I2C_SCC_SDA_OUT")
	)
	(segment
		(start 81.51495 -145.45564)
		(end 73.300336 -145.45564)
		(width 0.127)
		(layer "In5.Cu")
		(net "I2C_SCC_SDA_OUT")
	)
	(segment
		(start 73.124822 -145.280126)
		(end 67.406012 -145.280126)
		(width 0.127)
		(layer "In5.Cu")
		(net "I2C_SCC_SDA_OUT")
	)
	(segment
		(start 66.83121 -144.705324)
		(end 65.784476 -144.705324)
		(width 0.127)
		(layer "In5.Cu")
		(net "I2C_SCC_SDA_OUT")
	)
	(segment
		(start 87.122 -124.9934)
		(end 87.122 -119.3292)
		(width 0.127)
		(layer "F.Cu")
		(net "I2C_SCC_SDA")
	)
	(segment
		(start 88.3412 -97.486724)
		(end 87.561928 -98.265996)
		(width 0.127)
		(layer "F.Cu")
		(net "I2C_SCC_SDA")
	)
	(segment
		(start 87.122 -124.9934)
		(end 87.122 -125.222)
		(width 0.127)
		(layer "F.Cu")
		(net "I2C_SCC_SDA")
	)
	(segment
		(start 85.5472 -126.7968)
		(end 85.5472 -126.991618)
		(width 0.127)
		(layer "F.Cu")
		(net "I2C_SCC_SDA")
	)
	(segment
		(start 119.354854 -24.405082)
		(end 119.80672 -24.856948)
		(width 0.127)
		(layer "F.Cu")
		(net "I2C_SCC_SDA")
	)
	(segment
		(start 87.111332 -71.044054)
		(end 87.5284 -71.461122)
		(width 0.127)
		(layer "F.Cu")
		(net "I2C_SCC_SDA")
	)
	(segment
		(start 87.5284 -95.6564)
		(end 88.3412 -96.4692)
		(width 0.127)
		(layer "F.Cu")
		(net "I2C_SCC_SDA")
	)
	(segment
		(start 136.307068 -24.856948)
		(end 138.420348 -26.970228)
		(width 0.127)
		(layer "F.Cu")
		(net "I2C_SCC_SDA")
	)
	(segment
		(start 73.914 -144.98574)
		(end 73.94194 -144.98574)
		(width 0.127)
		(layer "F.Cu")
		(net "I2C_SCC_SDA")
	)
	(segment
		(start 87.122 -125.222)
		(end 85.5472 -126.7968)
		(width 0.127)
		(layer "F.Cu")
		(net "I2C_SCC_SDA")
	)
	(segment
		(start 138.420348 -26.970228)
		(end 138.420348 -40.720518)
		(width 0.127)
		(layer "F.Cu")
		(net "I2C_SCC_SDA")
	)
	(segment
		(start 88.3412 -96.4692)
		(end 88.3412 -97.486724)
		(width 0.127)
		(layer "F.Cu")
		(net "I2C_SCC_SDA")
	)
	(segment
		(start 119.80672 -24.856948)
		(end 136.307068 -24.856948)
		(width 0.127)
		(layer "F.Cu")
		(net "I2C_SCC_SDA")
	)
	(segment
		(start 138.420348 -40.720518)
		(end 139.499848 -41.800018)
		(width 0.127)
		(layer "F.Cu")
		(net "I2C_SCC_SDA")
	)
	(segment
		(start 73.94194 -144.98574)
		(end 74.22388 -144.7038)
		(width 0.127)
		(layer "F.Cu")
		(net "I2C_SCC_SDA")
	)
	(segment
		(start 87.122 -119.3292)
		(end 89.0016 -117.4496)
		(width 0.127)
		(layer "F.Cu")
		(net "I2C_SCC_SDA")
	)
	(segment
		(start 119.354854 -23.887938)
		(end 119.354854 -24.405082)
		(width 0.127)
		(layer "F.Cu")
		(net "I2C_SCC_SDA")
	)
	(segment
		(start 74.22388 -144.7038)
		(end 74.6887 -144.7038)
		(width 0.127)
		(layer "F.Cu")
		(net "I2C_SCC_SDA")
	)
	(segment
		(start 87.5284 -71.461122)
		(end 87.5284 -95.6564)
		(width 0.127)
		(layer "F.Cu")
		(net "I2C_SCC_SDA")
	)
	(via
		(at 95.1611 -116.019834)
		(size 0.508)
		(drill 0.254)
		(layers "F.Cu" "B.Cu")
		(net "I2C_SCC_SDA")
	)
	(via
		(at 85.5472 -126.991618)
		(size 0.508)
		(drill 0.254)
		(layers "F.Cu" "B.Cu")
		(net "I2C_SCC_SDA")
	)
	(via
		(at 87.111332 -71.044054)
		(size 0.508)
		(drill 0.254)
		(layers "F.Cu" "B.Cu")
		(net "I2C_SCC_SDA")
	)
	(via
		(at 87.561928 -98.265996)
		(size 0.508)
		(drill 0.254)
		(layers "F.Cu" "B.Cu")
		(net "I2C_SCC_SDA")
	)
	(via
		(at 119.354854 -23.887938)
		(size 0.508)
		(drill 0.254)
		(layers "F.Cu" "B.Cu")
		(net "I2C_SCC_SDA")
	)
	(via
		(at 87.122 -124.9934)
		(size 0.6604)
		(drill 0.3302)
		(layers "F.Cu" "B.Cu")
		(net "I2C_SCC_SDA")
	)
	(via
		(at 89.0016 -117.4496)
		(size 0.508)
		(drill 0.254)
		(layers "F.Cu" "B.Cu")
		(net "I2C_SCC_SDA")
	)
	(via
		(at 73.914 -144.98574)
		(size 0.508)
		(drill 0.254)
		(layers "F.Cu" "B.Cu")
		(net "I2C_SCC_SDA")
	)
	(segment
		(start 74.757026 -144.98574)
		(end 73.914 -144.98574)
		(width 0.127)
		(layer "B.Cu")
		(net "I2C_SCC_SDA")
	)
	(segment
		(start 78.514194 -133.603238)
		(end 77.6224 -134.495032)
		(width 0.127)
		(layer "B.Cu")
		(net "I2C_SCC_SDA")
	)
	(segment
		(start 95.066866 -115.9256)
		(end 93.5228 -115.9256)
		(width 0.127)
		(layer "B.Cu")
		(net "I2C_SCC_SDA")
	)
	(segment
		(start 86.134194 -130.796538)
		(end 83.736688 -133.194044)
		(width 0.127)
		(layer "B.Cu")
		(net "I2C_SCC_SDA")
	)
	(segment
		(start 77.6224 -139.954)
		(end 77.1144 -140.462)
		(width 0.127)
		(layer "B.Cu")
		(net "I2C_SCC_SDA")
	)
	(segment
		(start 81.467706 -133.194044)
		(end 81.058512 -133.603238)
		(width 0.127)
		(layer "B.Cu")
		(net "I2C_SCC_SDA")
	)
	(segment
		(start 85.5472 -126.991618)
		(end 86.134194 -127.578612)
		(width 0.127)
		(layer "B.Cu")
		(net "I2C_SCC_SDA")
	)
	(segment
		(start 86.134194 -127.578612)
		(end 86.134194 -130.796538)
		(width 0.127)
		(layer "B.Cu")
		(net "I2C_SCC_SDA")
	)
	(segment
		(start 77.1144 -142.628366)
		(end 74.757026 -144.98574)
		(width 0.127)
		(layer "B.Cu")
		(net "I2C_SCC_SDA")
	)
	(segment
		(start 77.6224 -134.495032)
		(end 77.6224 -139.954)
		(width 0.127)
		(layer "B.Cu")
		(net "I2C_SCC_SDA")
	)
	(segment
		(start 95.1611 -116.019834)
		(end 95.066866 -115.9256)
		(width 0.127)
		(layer "B.Cu")
		(net "I2C_SCC_SDA")
	)
	(segment
		(start 89.1286 -117.5766)
		(end 89.0016 -117.4496)
		(width 0.127)
		(layer "B.Cu")
		(net "I2C_SCC_SDA")
	)
	(segment
		(start 83.736688 -133.194044)
		(end 81.467706 -133.194044)
		(width 0.127)
		(layer "B.Cu")
		(net "I2C_SCC_SDA")
	)
	(segment
		(start 91.8718 -117.5766)
		(end 89.1286 -117.5766)
		(width 0.127)
		(layer "B.Cu")
		(net "I2C_SCC_SDA")
	)
	(segment
		(start 81.058512 -133.603238)
		(end 78.514194 -133.603238)
		(width 0.127)
		(layer "B.Cu")
		(net "I2C_SCC_SDA")
	)
	(segment
		(start 77.1144 -140.462)
		(end 77.1144 -142.628366)
		(width 0.127)
		(layer "B.Cu")
		(net "I2C_SCC_SDA")
	)
	(segment
		(start 93.5228 -115.9256)
		(end 91.8718 -117.5766)
		(width 0.127)
		(layer "B.Cu")
		(net "I2C_SCC_SDA")
	)
	(segment
		(start 86.98484 -41.923208)
		(end 85.758782 -43.149266)
		(width 0.127)
		(layer "In5.Cu")
		(net "I2C_SCC_SDA")
	)
	(segment
		(start 119.05742 -24.185372)
		(end 99.853242 -24.185372)
		(width 0.127)
		(layer "In5.Cu")
		(net "I2C_SCC_SDA")
	)
	(segment
		(start 99.853242 -24.185372)
		(end 95.174816 -28.863798)
		(width 0.127)
		(layer "In5.Cu")
		(net "I2C_SCC_SDA")
	)
	(segment
		(start 96.214692 -106.91876)
		(end 96.214692 -114.966242)
		(width 0.127)
		(layer "In5.Cu")
		(net "I2C_SCC_SDA")
	)
	(segment
		(start 89.66073 -31.936436)
		(end 88.115648 -31.936436)
		(width 0.127)
		(layer "In5.Cu")
		(net "I2C_SCC_SDA")
	)
	(segment
		(start 92.733368 -28.863798)
		(end 89.66073 -31.936436)
		(width 0.127)
		(layer "In5.Cu")
		(net "I2C_SCC_SDA")
	)
	(segment
		(start 87.561928 -98.265996)
		(end 96.214692 -106.91876)
		(width 0.127)
		(layer "In5.Cu")
		(net "I2C_SCC_SDA")
	)
	(segment
		(start 88.115648 -31.936436)
		(end 86.98484 -33.067244)
		(width 0.127)
		(layer "In5.Cu")
		(net "I2C_SCC_SDA")
	)
	(segment
		(start 119.354854 -23.887938)
		(end 119.05742 -24.185372)
		(width 0.127)
		(layer "In5.Cu")
		(net "I2C_SCC_SDA")
	)
	(segment
		(start 85.758782 -43.149266)
		(end 85.758782 -69.691504)
		(width 0.127)
		(layer "In5.Cu")
		(net "I2C_SCC_SDA")
	)
	(segment
		(start 86.98484 -33.067244)
		(end 86.98484 -41.923208)
		(width 0.127)
		(layer "In5.Cu")
		(net "I2C_SCC_SDA")
	)
	(segment
		(start 95.174816 -28.863798)
		(end 92.733368 -28.863798)
		(width 0.127)
		(layer "In5.Cu")
		(net "I2C_SCC_SDA")
	)
	(segment
		(start 96.214692 -114.966242)
		(end 95.1611 -116.019834)
		(width 0.127)
		(layer "In5.Cu")
		(net "I2C_SCC_SDA")
	)
	(segment
		(start 85.758782 -69.691504)
		(end 87.111332 -71.044054)
		(width 0.127)
		(layer "In5.Cu")
		(net "I2C_SCC_SDA")
	)
	(segment
		(start 64.215772 -144.538446)
		(end 63.489078 -144.538446)
		(width 0.127)
		(layer "F.Cu")
		(net "I2C_SCC_SCL_OUT")
	)
	(segment
		(start 65.8114 -144.197324)
		(end 65.4558 -144.552924)
		(width 0.127)
		(layer "F.Cu")
		(net "I2C_SCC_SCL_OUT")
	)
	(segment
		(start 64.355726 -144.6784)
		(end 64.215772 -144.538446)
		(width 0.127)
		(layer "F.Cu")
		(net "I2C_SCC_SCL_OUT")
	)
	(segment
		(start 62.560962 -144.480534)
		(end 62.996064 -144.045432)
		(width 0.127)
		(layer "F.Cu")
		(net "I2C_SCC_SCL_OUT")
	)
	(segment
		(start 63.489078 -144.538446)
		(end 62.996064 -144.045432)
		(width 0.127)
		(layer "F.Cu")
		(net "I2C_SCC_SCL_OUT")
	)
	(segment
		(start 65.4558 -144.552924)
		(end 65.01511 -144.552924)
		(width 0.127)
		(layer "F.Cu")
		(net "I2C_SCC_SCL_OUT")
	)
	(segment
		(start 64.889634 -144.6784)
		(end 64.355726 -144.6784)
		(width 0.127)
		(layer "F.Cu")
		(net "I2C_SCC_SCL_OUT")
	)
	(segment
		(start 83.45932 -144.30248)
		(end 83.58124 -144.4244)
		(width 0.127)
		(layer "F.Cu")
		(net "I2C_SCC_SCL_OUT")
	)
	(segment
		(start 84.198206 -144.4244)
		(end 84.438744 -144.664938)
		(width 0.127)
		(layer "F.Cu")
		(net "I2C_SCC_SCL_OUT")
	)
	(segment
		(start 83.58124 -144.4244)
		(end 84.198206 -144.4244)
		(width 0.127)
		(layer "F.Cu")
		(net "I2C_SCC_SCL_OUT")
	)
	(segment
		(start 65.01511 -144.552924)
		(end 64.889634 -144.6784)
		(width 0.127)
		(layer "F.Cu")
		(net "I2C_SCC_SCL_OUT")
	)
	(segment
		(start 61.739272 -144.480534)
		(end 62.560962 -144.480534)
		(width 0.127)
		(layer "F.Cu")
		(net "I2C_SCC_SCL_OUT")
	)
	(segment
		(start 84.438744 -144.664938)
		(end 85.349334 -144.664938)
		(width 0.127)
		(layer "F.Cu")
		(net "I2C_SCC_SCL_OUT")
	)
	(via
		(at 83.45932 -144.30248)
		(size 0.508)
		(drill 0.254)
		(layers "F.Cu" "B.Cu")
		(net "I2C_SCC_SCL_OUT")
	)
	(via
		(at 65.8114 -144.197324)
		(size 0.508)
		(drill 0.254)
		(layers "F.Cu" "B.Cu")
		(net "I2C_SCC_SCL_OUT")
	)
	(segment
		(start 65.894966 -144.173702)
		(end 67.17284 -144.173702)
		(width 0.127)
		(layer "In5.Cu")
		(net "I2C_SCC_SCL_OUT")
	)
	(segment
		(start 65.8114 -144.197324)
		(end 65.871344 -144.197324)
		(width 0.127)
		(layer "In5.Cu")
		(net "I2C_SCC_SCL_OUT")
	)
	(segment
		(start 75.129898 -144.88541)
		(end 82.562446 -144.88541)
		(width 0.127)
		(layer "In5.Cu")
		(net "I2C_SCC_SCL_OUT")
	)
	(segment
		(start 82.562446 -144.88541)
		(end 83.089496 -144.35836)
		(width 0.127)
		(layer "In5.Cu")
		(net "I2C_SCC_SCL_OUT")
	)
	(segment
		(start 67.644264 -144.645126)
		(end 73.02881 -144.645126)
		(width 0.127)
		(layer "In5.Cu")
		(net "I2C_SCC_SCL_OUT")
	)
	(segment
		(start 83.187286 -144.30248)
		(end 83.45932 -144.30248)
		(width 0.127)
		(layer "In5.Cu")
		(net "I2C_SCC_SCL_OUT")
	)
	(segment
		(start 83.089496 -144.35836)
		(end 83.131406 -144.35836)
		(width 0.127)
		(layer "In5.Cu")
		(net "I2C_SCC_SCL_OUT")
	)
	(segment
		(start 74.696574 -144.452086)
		(end 75.129898 -144.88541)
		(width 0.127)
		(layer "In5.Cu")
		(net "I2C_SCC_SCL_OUT")
	)
	(segment
		(start 73.02881 -144.645126)
		(end 73.22185 -144.452086)
		(width 0.127)
		(layer "In5.Cu")
		(net "I2C_SCC_SCL_OUT")
	)
	(segment
		(start 67.17284 -144.173702)
		(end 67.644264 -144.645126)
		(width 0.127)
		(layer "In5.Cu")
		(net "I2C_SCC_SCL_OUT")
	)
	(segment
		(start 83.131406 -144.35836)
		(end 83.187286 -144.30248)
		(width 0.127)
		(layer "In5.Cu")
		(net "I2C_SCC_SCL_OUT")
	)
	(segment
		(start 73.22185 -144.452086)
		(end 74.696574 -144.452086)
		(width 0.127)
		(layer "In5.Cu")
		(net "I2C_SCC_SCL_OUT")
	)
	(segment
		(start 65.871344 -144.197324)
		(end 65.894966 -144.173702)
		(width 0.127)
		(layer "In5.Cu")
		(net "I2C_SCC_SCL_OUT")
	)
	(segment
		(start 120.185688 -24.259032)
		(end 120.275604 -24.348948)
		(width 0.127)
		(layer "F.Cu")
		(net "I2C_SCC_SCL")
	)
	(segment
		(start 87.196676 -70.180454)
		(end 88.106758 -71.090536)
		(width 0.127)
		(layer "F.Cu")
		(net "I2C_SCC_SCL")
	)
	(segment
		(start 87.09279 -70.180454)
		(end 87.196676 -70.180454)
		(width 0.127)
		(layer "F.Cu")
		(net "I2C_SCC_SCL")
	)
	(segment
		(start 86.4362 -119.1514)
		(end 86.4362 -125.036072)
		(width 0.127)
		(layer "F.Cu")
		(net "I2C_SCC_SCL")
	)
	(segment
		(start 86.4362 -125.036072)
		(end 85.7504 -125.721872)
		(width 0.127)
		(layer "F.Cu")
		(net "I2C_SCC_SCL")
	)
	(segment
		(start 88.106758 -71.090536)
		(end 88.106758 -95.179642)
		(width 0.127)
		(layer "F.Cu")
		(net "I2C_SCC_SCL")
	)
	(segment
		(start 89.0016 -116.586)
		(end 86.4362 -119.1514)
		(width 0.127)
		(layer "F.Cu")
		(net "I2C_SCC_SCL")
	)
	(segment
		(start 85.0392 -126.433072)
		(end 85.7504 -125.721872)
		(width 0.127)
		(layer "F.Cu")
		(net "I2C_SCC_SCL")
	)
	(segment
		(start 74.0791 -143.6624)
		(end 73.450704 -143.6624)
		(width 0.127)
		(layer "F.Cu")
		(net "I2C_SCC_SCL")
	)
	(segment
		(start 136.517634 -24.348948)
		(end 138.928348 -26.759662)
		(width 0.127)
		(layer "F.Cu")
		(net "I2C_SCC_SCL")
	)
	(segment
		(start 120.275604 -24.348948)
		(end 136.517634 -24.348948)
		(width 0.127)
		(layer "F.Cu")
		(net "I2C_SCC_SCL")
	)
	(segment
		(start 73.450704 -143.6624)
		(end 73.230486 -143.882618)
		(width 0.127)
		(layer "F.Cu")
		(net "I2C_SCC_SCL")
	)
	(segment
		(start 138.928348 -26.759662)
		(end 138.928348 -39.82847)
		(width 0.127)
		(layer "F.Cu")
		(net "I2C_SCC_SCL")
	)
	(segment
		(start 85.0392 -127.6858)
		(end 85.0392 -126.433072)
		(width 0.127)
		(layer "F.Cu")
		(net "I2C_SCC_SCL")
	)
	(segment
		(start 88.106758 -95.179642)
		(end 88.0364 -95.25)
		(width 0.127)
		(layer "F.Cu")
		(net "I2C_SCC_SCL")
	)
	(segment
		(start 138.928348 -39.82847)
		(end 139.499848 -40.39997)
		(width 0.127)
		(layer "F.Cu")
		(net "I2C_SCC_SCL")
	)
	(segment
		(start 85.4964 -128.143)
		(end 85.0392 -127.6858)
		(width 0.127)
		(layer "F.Cu")
		(net "I2C_SCC_SCL")
	)
	(via
		(at 87.09279 -70.180454)
		(size 0.508)
		(drill 0.254)
		(layers "F.Cu" "B.Cu")
		(net "I2C_SCC_SCL")
	)
	(via
		(at 88.0364 -95.25)
		(size 0.508)
		(drill 0.254)
		(layers "F.Cu" "B.Cu")
		(net "I2C_SCC_SCL")
	)
	(via
		(at 89.0016 -116.586)
		(size 0.508)
		(drill 0.254)
		(layers "F.Cu" "B.Cu")
		(net "I2C_SCC_SCL")
	)
	(via
		(at 85.7504 -125.721872)
		(size 0.6604)
		(drill 0.3302)
		(layers "F.Cu" "B.Cu")
		(net "I2C_SCC_SCL")
	)
	(via
		(at 85.4964 -128.143)
		(size 0.508)
		(drill 0.254)
		(layers "F.Cu" "B.Cu")
		(net "I2C_SCC_SCL")
	)
	(via
		(at 73.230486 -143.882618)
		(size 0.508)
		(drill 0.254)
		(layers "F.Cu" "B.Cu")
		(net "I2C_SCC_SCL")
	)
	(via
		(at 120.185688 -24.259032)
		(size 0.508)
		(drill 0.254)
		(layers "F.Cu" "B.Cu")
		(net "I2C_SCC_SCL")
	)
	(via
		(at 96.800924 -112.075214)
		(size 0.508)
		(drill 0.254)
		(layers "F.Cu" "B.Cu")
		(net "I2C_SCC_SCL")
	)
	(segment
		(start 85.4964 -128.4224)
		(end 85.4964 -128.143)
		(width 0.127)
		(layer "B.Cu")
		(net "I2C_SCC_SCL")
	)
	(segment
		(start 75.141582 -143.882618)
		(end 76.571602 -142.452598)
		(width 0.127)
		(layer "B.Cu")
		(net "I2C_SCC_SCL")
	)
	(segment
		(start 76.571602 -142.452598)
		(end 76.571602 -139.382246)
		(width 0.127)
		(layer "B.Cu")
		(net "I2C_SCC_SCL")
	)
	(segment
		(start 80.875632 -133.055106)
		(end 81.25587 -132.674868)
		(width 0.127)
		(layer "B.Cu")
		(net "I2C_SCC_SCL")
	)
	(segment
		(start 77.1144 -138.839448)
		(end 77.1144 -134.12597)
		(width 0.127)
		(layer "B.Cu")
		(net "I2C_SCC_SCL")
	)
	(segment
		(start 73.230486 -143.882618)
		(end 75.141582 -143.882618)
		(width 0.127)
		(layer "B.Cu")
		(net "I2C_SCC_SCL")
	)
	(segment
		(start 78.185264 -133.055106)
		(end 80.875632 -133.055106)
		(width 0.127)
		(layer "B.Cu")
		(net "I2C_SCC_SCL")
	)
	(segment
		(start 89.0016 -116.6368)
		(end 89.0016 -116.586)
		(width 0.127)
		(layer "B.Cu")
		(net "I2C_SCC_SCL")
	)
	(segment
		(start 93.312234 -115.4176)
		(end 92.093034 -116.6368)
		(width 0.127)
		(layer "B.Cu")
		(net "I2C_SCC_SCL")
	)
	(segment
		(start 81.25587 -132.674868)
		(end 83.537298 -132.674868)
		(width 0.127)
		(layer "B.Cu")
		(net "I2C_SCC_SCL")
	)
	(segment
		(start 77.1144 -134.12597)
		(end 78.185264 -133.055106)
		(width 0.127)
		(layer "B.Cu")
		(net "I2C_SCC_SCL")
	)
	(segment
		(start 95.86976 -113.006378)
		(end 95.86976 -115.02644)
		(width 0.127)
		(layer "B.Cu")
		(net "I2C_SCC_SCL")
	)
	(segment
		(start 85.5345 -130.677666)
		(end 85.5345 -128.4605)
		(width 0.127)
		(layer "B.Cu")
		(net "I2C_SCC_SCL")
	)
	(segment
		(start 96.800924 -112.075214)
		(end 95.86976 -113.006378)
		(width 0.127)
		(layer "B.Cu")
		(net "I2C_SCC_SCL")
	)
	(segment
		(start 92.093034 -116.6368)
		(end 89.0016 -116.6368)
		(width 0.127)
		(layer "B.Cu")
		(net "I2C_SCC_SCL")
	)
	(segment
		(start 76.571602 -139.382246)
		(end 77.1144 -138.839448)
		(width 0.127)
		(layer "B.Cu")
		(net "I2C_SCC_SCL")
	)
	(segment
		(start 83.537298 -132.674868)
		(end 85.5345 -130.677666)
		(width 0.127)
		(layer "B.Cu")
		(net "I2C_SCC_SCL")
	)
	(segment
		(start 95.4786 -115.4176)
		(end 93.312234 -115.4176)
		(width 0.127)
		(layer "B.Cu")
		(net "I2C_SCC_SCL")
	)
	(segment
		(start 95.86976 -115.02644)
		(end 95.4786 -115.4176)
		(width 0.127)
		(layer "B.Cu")
		(net "I2C_SCC_SCL")
	)
	(segment
		(start 85.5345 -128.4605)
		(end 85.4964 -128.4224)
		(width 0.127)
		(layer "B.Cu")
		(net "I2C_SCC_SCL")
	)
	(segment
		(start 119.751348 -24.693372)
		(end 120.185688 -24.259032)
		(width 0.127)
		(layer "In5.Cu")
		(net "I2C_SCC_SCL")
	)
	(segment
		(start 88.3412 -98.2218)
		(end 96.722692 -106.603292)
		(width 0.127)
		(layer "In5.Cu")
		(net "I2C_SCC_SCL")
	)
	(segment
		(start 88.373204 -32.47644)
		(end 89.839292 -32.47644)
		(width 0.127)
		(layer "In5.Cu")
		(net "I2C_SCC_SCL")
	)
	(segment
		(start 86.266782 -43.476418)
		(end 87.49284 -42.25036)
		(width 0.127)
		(layer "In5.Cu")
		(net "I2C_SCC_SCL")
	)
	(segment
		(start 87.09279 -70.180454)
		(end 86.266782 -69.354446)
		(width 0.127)
		(layer "In5.Cu")
		(net "I2C_SCC_SCL")
	)
	(segment
		(start 96.722692 -106.603292)
		(end 96.722692 -111.996982)
		(width 0.127)
		(layer "In5.Cu")
		(net "I2C_SCC_SCL")
	)
	(segment
		(start 86.266782 -69.354446)
		(end 86.266782 -43.476418)
		(width 0.127)
		(layer "In5.Cu")
		(net "I2C_SCC_SCL")
	)
	(segment
		(start 100.063808 -24.693372)
		(end 119.751348 -24.693372)
		(width 0.127)
		(layer "In5.Cu")
		(net "I2C_SCC_SCL")
	)
	(segment
		(start 87.49284 -33.356804)
		(end 88.373204 -32.47644)
		(width 0.127)
		(layer "In5.Cu")
		(net "I2C_SCC_SCL")
	)
	(segment
		(start 89.839292 -32.47644)
		(end 92.943934 -29.371798)
		(width 0.127)
		(layer "In5.Cu")
		(net "I2C_SCC_SCL")
	)
	(segment
		(start 87.49284 -42.25036)
		(end 87.49284 -33.356804)
		(width 0.127)
		(layer "In5.Cu")
		(net "I2C_SCC_SCL")
	)
	(segment
		(start 95.385382 -29.371798)
		(end 100.063808 -24.693372)
		(width 0.127)
		(layer "In5.Cu")
		(net "I2C_SCC_SCL")
	)
	(segment
		(start 88.3412 -95.5548)
		(end 88.3412 -98.2218)
		(width 0.127)
		(layer "In5.Cu")
		(net "I2C_SCC_SCL")
	)
	(segment
		(start 96.722692 -111.996982)
		(end 96.800924 -112.075214)
		(width 0.127)
		(layer "In5.Cu")
		(net "I2C_SCC_SCL")
	)
	(segment
		(start 88.0364 -95.25)
		(end 88.3412 -95.5548)
		(width 0.127)
		(layer "In5.Cu")
		(net "I2C_SCC_SCL")
	)
	(segment
		(start 92.943934 -29.371798)
		(end 95.385382 -29.371798)
		(width 0.127)
		(layer "In5.Cu")
		(net "I2C_SCC_SCL")
	)
	(segment
		(start 65.666112 -141.010894)
		(end 65.666112 -141.043914)
		(width 0.127)
		(layer "F.Cu")
		(net "I2C_EXP_RMT_SDA_OUT")
	)
	(segment
		(start 84.408772 -143.9164)
		(end 83.92287 -143.9164)
		(width 0.127)
		(layer "F.Cu")
		(net "I2C_EXP_RMT_SDA_OUT")
	)
	(segment
		(start 85.349334 -144.014698)
		(end 84.50707 -144.014698)
		(width 0.127)
		(layer "F.Cu")
		(net "I2C_EXP_RMT_SDA_OUT")
	)
	(segment
		(start 62.559438 -143.458692)
		(end 62.998858 -143.019272)
		(width 0.127)
		(layer "F.Cu")
		(net "I2C_EXP_RMT_SDA_OUT")
	)
	(segment
		(start 83.92287 -143.9164)
		(end 83.072986 -143.066516)
		(width 0.127)
		(layer "F.Cu")
		(net "I2C_EXP_RMT_SDA_OUT")
	)
	(segment
		(start 65.659 -141.865604)
		(end 65.318894 -142.20571)
		(width 0.127)
		(layer "F.Cu")
		(net "I2C_EXP_RMT_SDA_OUT")
	)
	(segment
		(start 65.659 -141.051026)
		(end 65.659 -141.865604)
		(width 0.127)
		(layer "F.Cu")
		(net "I2C_EXP_RMT_SDA_OUT")
	)
	(segment
		(start 62.998858 -143.019272)
		(end 63.54953 -142.4686)
		(width 0.127)
		(layer "F.Cu")
		(net "I2C_EXP_RMT_SDA_OUT")
	)
	(segment
		(start 65.666112 -141.043914)
		(end 65.659 -141.051026)
		(width 0.127)
		(layer "F.Cu")
		(net "I2C_EXP_RMT_SDA_OUT")
	)
	(segment
		(start 84.50707 -144.014698)
		(end 84.408772 -143.9164)
		(width 0.127)
		(layer "F.Cu")
		(net "I2C_EXP_RMT_SDA_OUT")
	)
	(segment
		(start 63.54953 -142.4686)
		(end 65.056004 -142.4686)
		(width 0.127)
		(layer "F.Cu")
		(net "I2C_EXP_RMT_SDA_OUT")
	)
	(segment
		(start 65.056004 -142.4686)
		(end 65.318894 -142.20571)
		(width 0.127)
		(layer "F.Cu")
		(net "I2C_EXP_RMT_SDA_OUT")
	)
	(segment
		(start 83.072986 -143.066516)
		(end 83.072986 -141.540738)
		(width 0.127)
		(layer "F.Cu")
		(net "I2C_EXP_RMT_SDA_OUT")
	)
	(segment
		(start 61.987684 -143.458692)
		(end 62.559438 -143.458692)
		(width 0.127)
		(layer "F.Cu")
		(net "I2C_EXP_RMT_SDA_OUT")
	)
	(via
		(at 83.072986 -141.540738)
		(size 0.508)
		(drill 0.254)
		(layers "F.Cu" "B.Cu")
		(net "I2C_EXP_RMT_SDA_OUT")
	)
	(via
		(at 65.666112 -141.010894)
		(size 0.508)
		(drill 0.254)
		(layers "F.Cu" "B.Cu")
		(net "I2C_EXP_RMT_SDA_OUT")
	)
	(via
		(at 65.318894 -142.20571)
		(size 0.6604)
		(drill 0.3302)
		(layers "F.Cu" "B.Cu")
		(net "I2C_EXP_RMT_SDA_OUT")
	)
	(segment
		(start 83.072986 -141.540738)
		(end 82.611468 -141.07922)
		(width 0.127)
		(layer "In5.Cu")
		(net "I2C_EXP_RMT_SDA_OUT")
	)
	(segment
		(start 74.66076 -141.0462)
		(end 67.432936 -141.0462)
		(width 0.127)
		(layer "In5.Cu")
		(net "I2C_EXP_RMT_SDA_OUT")
	)
	(segment
		(start 66.018156 -141.362938)
		(end 65.666112 -141.010894)
		(width 0.127)
		(layer "In5.Cu")
		(net "I2C_EXP_RMT_SDA_OUT")
	)
	(segment
		(start 67.116198 -141.362938)
		(end 66.018156 -141.362938)
		(width 0.127)
		(layer "In5.Cu")
		(net "I2C_EXP_RMT_SDA_OUT")
	)
	(segment
		(start 79.537052 -141.469364)
		(end 75.083924 -141.469364)
		(width 0.127)
		(layer "In5.Cu")
		(net "I2C_EXP_RMT_SDA_OUT")
	)
	(segment
		(start 81.540604 -140.623544)
		(end 80.382872 -140.623544)
		(width 0.127)
		(layer "In5.Cu")
		(net "I2C_EXP_RMT_SDA_OUT")
	)
	(segment
		(start 80.382872 -140.623544)
		(end 79.537052 -141.469364)
		(width 0.127)
		(layer "In5.Cu")
		(net "I2C_EXP_RMT_SDA_OUT")
	)
	(segment
		(start 67.432936 -141.0462)
		(end 67.116198 -141.362938)
		(width 0.127)
		(layer "In5.Cu")
		(net "I2C_EXP_RMT_SDA_OUT")
	)
	(segment
		(start 81.99628 -141.07922)
		(end 81.540604 -140.623544)
		(width 0.127)
		(layer "In5.Cu")
		(net "I2C_EXP_RMT_SDA_OUT")
	)
	(segment
		(start 75.083924 -141.469364)
		(end 74.66076 -141.0462)
		(width 0.127)
		(layer "In5.Cu")
		(net "I2C_EXP_RMT_SDA_OUT")
	)
	(segment
		(start 82.611468 -141.07922)
		(end 81.99628 -141.07922)
		(width 0.127)
		(layer "In5.Cu")
		(net "I2C_EXP_RMT_SDA_OUT")
	)
	(segment
		(start 75.9841 -142.7861)
		(end 75.692 -142.494)
		(width 0.127)
		(layer "F.Cu")
		(net "I2C_EXP_RMT_SDA")
	)
	(segment
		(start 75.9841 -143.3068)
		(end 75.9841 -142.7861)
		(width 0.127)
		(layer "F.Cu")
		(net "I2C_EXP_RMT_SDA")
	)
	(via
		(at 87.695786 -141.621764)
		(size 0.508)
		(drill 0.254)
		(layers "F.Cu" "B.Cu")
		(net "I2C_EXP_RMT_SDA")
	)
	(via
		(at 75.692 -142.494)
		(size 0.508)
		(drill 0.254)
		(layers "F.Cu" "B.Cu")
		(net "I2C_EXP_RMT_SDA")
	)
	(segment
		(start 88.803226 -132.913628)
		(end 88.803226 -139.321286)
		(width 0.127)
		(layer "In2.Cu")
		(net "I2C_EXP_RMT_SDA")
	)
	(segment
		(start 122.382534 -25.725628)
		(end 120.013476 -23.35657)
		(width 0.127)
		(layer "In2.Cu")
		(net "I2C_EXP_RMT_SDA")
	)
	(segment
		(start 88.1126 -127.361188)
		(end 88.658446 -127.907034)
		(width 0.127)
		(layer "In2.Cu")
		(net "I2C_EXP_RMT_SDA")
	)
	(segment
		(start 92.242132 -111.317024)
		(end 88.5317 -115.027456)
		(width 0.127)
		(layer "In2.Cu")
		(net "I2C_EXP_RMT_SDA")
	)
	(segment
		(start 90.917268 -60.005468)
		(end 92.365068 -61.453268)
		(width 0.127)
		(layer "In2.Cu")
		(net "I2C_EXP_RMT_SDA")
	)
	(segment
		(start 100.852478 -21.928836)
		(end 100.295456 -21.371814)
		(width 0.127)
		(layer "In2.Cu")
		(net "I2C_EXP_RMT_SDA")
	)
	(segment
		(start 90.917268 -51.017932)
		(end 90.917268 -60.005468)
		(width 0.127)
		(layer "In2.Cu")
		(net "I2C_EXP_RMT_SDA")
	)
	(segment
		(start 92.99575 -43.824906)
		(end 91.255088 -45.565568)
		(width 0.127)
		(layer "In2.Cu")
		(net "I2C_EXP_RMT_SDA")
	)
	(segment
		(start 88.5317 -123.989084)
		(end 88.1126 -124.408184)
		(width 0.127)
		(layer "In2.Cu")
		(net "I2C_EXP_RMT_SDA")
	)
	(segment
		(start 92.365068 -61.955934)
		(end 92.242132 -62.07887)
		(width 0.127)
		(layer "In2.Cu")
		(net "I2C_EXP_RMT_SDA")
	)
	(segment
		(start 88.417654 -139.706858)
		(end 88.417654 -140.899896)
		(width 0.127)
		(layer "In2.Cu")
		(net "I2C_EXP_RMT_SDA")
	)
	(segment
		(start 88.5317 -115.027456)
		(end 88.5317 -123.989084)
		(width 0.127)
		(layer "In2.Cu")
		(net "I2C_EXP_RMT_SDA")
	)
	(segment
		(start 88.417654 -140.899896)
		(end 87.695786 -141.621764)
		(width 0.127)
		(layer "In2.Cu")
		(net "I2C_EXP_RMT_SDA")
	)
	(segment
		(start 95.83039 -24.260048)
		(end 95.83039 -25.836372)
		(width 0.127)
		(layer "In2.Cu")
		(net "I2C_EXP_RMT_SDA")
	)
	(segment
		(start 132.299964 -41.800018)
		(end 131.132326 -40.63238)
		(width 0.127)
		(layer "In2.Cu")
		(net "I2C_EXP_RMT_SDA")
	)
	(segment
		(start 128.74498 -29.540454)
		(end 124.930154 -25.725628)
		(width 0.127)
		(layer "In2.Cu")
		(net "I2C_EXP_RMT_SDA")
	)
	(segment
		(start 92.365068 -61.453268)
		(end 92.365068 -61.955934)
		(width 0.127)
		(layer "In2.Cu")
		(net "I2C_EXP_RMT_SDA")
	)
	(segment
		(start 98.718624 -21.371814)
		(end 95.83039 -24.260048)
		(width 0.127)
		(layer "In2.Cu")
		(net "I2C_EXP_RMT_SDA")
	)
	(segment
		(start 88.658446 -127.907034)
		(end 88.658446 -132.768848)
		(width 0.127)
		(layer "In2.Cu")
		(net "I2C_EXP_RMT_SDA")
	)
	(segment
		(start 88.803226 -139.321286)
		(end 88.417654 -139.706858)
		(width 0.127)
		(layer "In2.Cu")
		(net "I2C_EXP_RMT_SDA")
	)
	(segment
		(start 124.930154 -25.725628)
		(end 122.382534 -25.725628)
		(width 0.127)
		(layer "In2.Cu")
		(net "I2C_EXP_RMT_SDA")
	)
	(segment
		(start 88.1126 -124.408184)
		(end 88.1126 -127.361188)
		(width 0.127)
		(layer "In2.Cu")
		(net "I2C_EXP_RMT_SDA")
	)
	(segment
		(start 91.255088 -45.565568)
		(end 91.255088 -50.680112)
		(width 0.127)
		(layer "In2.Cu")
		(net "I2C_EXP_RMT_SDA")
	)
	(segment
		(start 118.38559 -23.35657)
		(end 116.957856 -21.928836)
		(width 0.127)
		(layer "In2.Cu")
		(net "I2C_EXP_RMT_SDA")
	)
	(segment
		(start 116.957856 -21.928836)
		(end 100.852478 -21.928836)
		(width 0.127)
		(layer "In2.Cu")
		(net "I2C_EXP_RMT_SDA")
	)
	(segment
		(start 131.132326 -40.63238)
		(end 131.132326 -30.724348)
		(width 0.127)
		(layer "In2.Cu")
		(net "I2C_EXP_RMT_SDA")
	)
	(segment
		(start 92.99575 -28.671012)
		(end 92.99575 -43.824906)
		(width 0.127)
		(layer "In2.Cu")
		(net "I2C_EXP_RMT_SDA")
	)
	(segment
		(start 120.013476 -23.35657)
		(end 118.38559 -23.35657)
		(width 0.127)
		(layer "In2.Cu")
		(net "I2C_EXP_RMT_SDA")
	)
	(segment
		(start 95.83039 -25.836372)
		(end 92.99575 -28.671012)
		(width 0.127)
		(layer "In2.Cu")
		(net "I2C_EXP_RMT_SDA")
	)
	(segment
		(start 88.658446 -132.768848)
		(end 88.803226 -132.913628)
		(width 0.127)
		(layer "In2.Cu")
		(net "I2C_EXP_RMT_SDA")
	)
	(segment
		(start 100.295456 -21.371814)
		(end 98.718624 -21.371814)
		(width 0.127)
		(layer "In2.Cu")
		(net "I2C_EXP_RMT_SDA")
	)
	(segment
		(start 131.132326 -30.724348)
		(end 129.948432 -29.540454)
		(width 0.127)
		(layer "In2.Cu")
		(net "I2C_EXP_RMT_SDA")
	)
	(segment
		(start 91.255088 -50.680112)
		(end 90.917268 -51.017932)
		(width 0.127)
		(layer "In2.Cu")
		(net "I2C_EXP_RMT_SDA")
	)
	(segment
		(start 129.948432 -29.540454)
		(end 128.74498 -29.540454)
		(width 0.127)
		(layer "In2.Cu")
		(net "I2C_EXP_RMT_SDA")
	)
	(segment
		(start 92.242132 -62.07887)
		(end 92.242132 -111.317024)
		(width 0.127)
		(layer "In2.Cu")
		(net "I2C_EXP_RMT_SDA")
	)
	(segment
		(start 87.60714 -141.533118)
		(end 87.695786 -141.621764)
		(width 0.127)
		(layer "In5.Cu")
		(net "I2C_EXP_RMT_SDA")
	)
	(segment
		(start 81.355184 -142.383002)
		(end 81.542382 -142.5702)
		(width 0.127)
		(layer "In5.Cu")
		(net "I2C_EXP_RMT_SDA")
	)
	(segment
		(start 80.232758 -142.485618)
		(end 80.335374 -142.383002)
		(width 0.127)
		(layer "In5.Cu")
		(net "I2C_EXP_RMT_SDA")
	)
	(segment
		(start 86.790784 -141.533118)
		(end 87.60714 -141.533118)
		(width 0.127)
		(layer "In5.Cu")
		(net "I2C_EXP_RMT_SDA")
	)
	(segment
		(start 75.692 -142.494)
		(end 75.700382 -142.485618)
		(width 0.127)
		(layer "In5.Cu")
		(net "I2C_EXP_RMT_SDA")
	)
	(segment
		(start 81.542382 -142.5702)
		(end 85.753702 -142.5702)
		(width 0.127)
		(layer "In5.Cu")
		(net "I2C_EXP_RMT_SDA")
	)
	(segment
		(start 75.700382 -142.485618)
		(end 80.232758 -142.485618)
		(width 0.127)
		(layer "In5.Cu")
		(net "I2C_EXP_RMT_SDA")
	)
	(segment
		(start 85.753702 -142.5702)
		(end 86.790784 -141.533118)
		(width 0.127)
		(layer "In5.Cu")
		(net "I2C_EXP_RMT_SDA")
	)
	(segment
		(start 80.335374 -142.383002)
		(end 81.355184 -142.383002)
		(width 0.127)
		(layer "In5.Cu")
		(net "I2C_EXP_RMT_SDA")
	)
	(segment
		(start 62.459108 -142.417292)
		(end 62.978284 -141.898116)
		(width 0.127)
		(layer "F.Cu")
		(net "I2C_EXP_RMT_SCL_OUT")
	)
	(segment
		(start 62.978284 -141.898116)
		(end 62.978284 -141.417294)
		(width 0.127)
		(layer "F.Cu")
		(net "I2C_EXP_RMT_SCL_OUT")
	)
	(segment
		(start 64.74587 -141.294866)
		(end 64.74587 -141.163294)
		(width 0.127)
		(layer "F.Cu")
		(net "I2C_EXP_RMT_SCL_OUT")
	)
	(segment
		(start 84.546694 -143.364458)
		(end 84.005166 -142.82293)
		(width 0.127)
		(layer "F.Cu")
		(net "I2C_EXP_RMT_SCL_OUT")
	)
	(segment
		(start 84.005166 -142.82293)
		(end 84.005166 -141.546072)
		(width 0.127)
		(layer "F.Cu")
		(net "I2C_EXP_RMT_SCL_OUT")
	)
	(segment
		(start 64.080136 -141.9606)
		(end 64.74587 -141.294866)
		(width 0.127)
		(layer "F.Cu")
		(net "I2C_EXP_RMT_SCL_OUT")
	)
	(segment
		(start 61.987684 -142.417292)
		(end 62.459108 -142.417292)
		(width 0.127)
		(layer "F.Cu")
		(net "I2C_EXP_RMT_SCL_OUT")
	)
	(segment
		(start 62.978284 -141.417294)
		(end 63.52159 -141.9606)
		(width 0.127)
		(layer "F.Cu")
		(net "I2C_EXP_RMT_SCL_OUT")
	)
	(segment
		(start 63.52159 -141.9606)
		(end 64.080136 -141.9606)
		(width 0.127)
		(layer "F.Cu")
		(net "I2C_EXP_RMT_SCL_OUT")
	)
	(segment
		(start 85.349334 -143.364458)
		(end 84.546694 -143.364458)
		(width 0.127)
		(layer "F.Cu")
		(net "I2C_EXP_RMT_SCL_OUT")
	)
	(via
		(at 84.005166 -141.546072)
		(size 0.508)
		(drill 0.254)
		(layers "F.Cu" "B.Cu")
		(net "I2C_EXP_RMT_SCL_OUT")
	)
	(via
		(at 64.74587 -141.163294)
		(size 0.508)
		(drill 0.254)
		(layers "F.Cu" "B.Cu")
		(net "I2C_EXP_RMT_SCL_OUT")
	)
	(segment
		(start 75.272392 -140.900404)
		(end 74.895964 -140.523976)
		(width 0.127)
		(layer "In5.Cu")
		(net "I2C_EXP_RMT_SCL_OUT")
	)
	(segment
		(start 83.871562 -141.546072)
		(end 82.88909 -140.5636)
		(width 0.127)
		(layer "In5.Cu")
		(net "I2C_EXP_RMT_SCL_OUT")
	)
	(segment
		(start 82.88909 -140.5636)
		(end 82.199226 -140.5636)
		(width 0.127)
		(layer "In5.Cu")
		(net "I2C_EXP_RMT_SCL_OUT")
	)
	(segment
		(start 64.74587 -141.032992)
		(end 64.74587 -141.163294)
		(width 0.127)
		(layer "In5.Cu")
		(net "I2C_EXP_RMT_SCL_OUT")
	)
	(segment
		(start 65.393316 -140.385546)
		(end 64.74587 -141.032992)
		(width 0.127)
		(layer "In5.Cu")
		(net "I2C_EXP_RMT_SCL_OUT")
	)
	(segment
		(start 79.281274 -140.900404)
		(end 75.272392 -140.900404)
		(width 0.127)
		(layer "In5.Cu")
		(net "I2C_EXP_RMT_SCL_OUT")
	)
	(segment
		(start 84.005166 -141.546072)
		(end 83.871562 -141.546072)
		(width 0.127)
		(layer "In5.Cu")
		(net "I2C_EXP_RMT_SCL_OUT")
	)
	(segment
		(start 74.895964 -140.523976)
		(end 68.179696 -140.523976)
		(width 0.127)
		(layer "In5.Cu")
		(net "I2C_EXP_RMT_SCL_OUT")
	)
	(segment
		(start 68.179696 -140.523976)
		(end 68.041266 -140.385546)
		(width 0.127)
		(layer "In5.Cu")
		(net "I2C_EXP_RMT_SCL_OUT")
	)
	(segment
		(start 81.75117 -140.115544)
		(end 80.066134 -140.115544)
		(width 0.127)
		(layer "In5.Cu")
		(net "I2C_EXP_RMT_SCL_OUT")
	)
	(segment
		(start 80.066134 -140.115544)
		(end 79.281274 -140.900404)
		(width 0.127)
		(layer "In5.Cu")
		(net "I2C_EXP_RMT_SCL_OUT")
	)
	(segment
		(start 68.041266 -140.385546)
		(end 65.393316 -140.385546)
		(width 0.127)
		(layer "In5.Cu")
		(net "I2C_EXP_RMT_SCL_OUT")
	)
	(segment
		(start 82.199226 -140.5636)
		(end 81.75117 -140.115544)
		(width 0.127)
		(layer "In5.Cu")
		(net "I2C_EXP_RMT_SCL_OUT")
	)
	(segment
		(start 75.503532 -141.633194)
		(end 74.703178 -142.433548)
		(width 0.127)
		(layer "F.Cu")
		(net "I2C_EXP_RMT_SCL")
	)
	(segment
		(start 76.054204 -141.633194)
		(end 75.503532 -141.633194)
		(width 0.127)
		(layer "F.Cu")
		(net "I2C_EXP_RMT_SCL")
	)
	(via
		(at 87.417402 -140.56233)
		(size 0.508)
		(drill 0.254)
		(layers "F.Cu" "B.Cu")
		(net "I2C_EXP_RMT_SCL")
	)
	(via
		(at 74.703178 -142.433548)
		(size 0.508)
		(drill 0.254)
		(layers "F.Cu" "B.Cu")
		(net "I2C_EXP_RMT_SCL")
	)
	(segment
		(start 90.747088 -45.06849)
		(end 92.48775 -43.327828)
		(width 0.127)
		(layer "In2.Cu")
		(net "I2C_EXP_RMT_SCL")
	)
	(segment
		(start 100.506022 -20.863814)
		(end 101.063044 -21.420836)
		(width 0.127)
		(layer "In2.Cu")
		(net "I2C_EXP_RMT_SCL")
	)
	(segment
		(start 87.417402 -140.56233)
		(end 87.909654 -140.070078)
		(width 0.127)
		(layer "In2.Cu")
		(net "I2C_EXP_RMT_SCL")
	)
	(segment
		(start 125.14072 -25.217628)
		(end 128.955292 -29.0322)
		(width 0.127)
		(layer "In2.Cu")
		(net "I2C_EXP_RMT_SCL")
	)
	(segment
		(start 88.150446 -132.979414)
		(end 88.150446 -128.1176)
		(width 0.127)
		(layer "In2.Cu")
		(net "I2C_EXP_RMT_SCL")
	)
	(segment
		(start 101.063044 -21.420836)
		(end 117.168422 -21.420836)
		(width 0.127)
		(layer "In2.Cu")
		(net "I2C_EXP_RMT_SCL")
	)
	(segment
		(start 87.817198 -127.784352)
		(end 87.242904 -127.784352)
		(width 0.127)
		(layer "In2.Cu")
		(net "I2C_EXP_RMT_SCL")
	)
	(segment
		(start 128.955546 -29.0322)
		(end 128.9558 -29.032454)
		(width 0.127)
		(layer "In2.Cu")
		(net "I2C_EXP_RMT_SCL")
	)
	(segment
		(start 90.409268 -61.046868)
		(end 90.409268 -50.807366)
		(width 0.127)
		(layer "In2.Cu")
		(net "I2C_EXP_RMT_SCL")
	)
	(segment
		(start 90.747088 -50.469546)
		(end 90.747088 -45.06849)
		(width 0.127)
		(layer "In2.Cu")
		(net "I2C_EXP_RMT_SCL")
	)
	(segment
		(start 130.158998 -29.032454)
		(end 131.64312 -30.516576)
		(width 0.127)
		(layer "In2.Cu")
		(net "I2C_EXP_RMT_SCL")
	)
	(segment
		(start 88.0237 -114.81689)
		(end 91.734132 -111.106458)
		(width 0.127)
		(layer "In2.Cu")
		(net "I2C_EXP_RMT_SCL")
	)
	(segment
		(start 87.909654 -139.496292)
		(end 88.295226 -139.11072)
		(width 0.127)
		(layer "In2.Cu")
		(net "I2C_EXP_RMT_SCL")
	)
	(segment
		(start 120.224042 -22.84857)
		(end 122.5931 -25.217628)
		(width 0.127)
		(layer "In2.Cu")
		(net "I2C_EXP_RMT_SCL")
	)
	(segment
		(start 131.64312 -30.516576)
		(end 131.64312 -39.743126)
		(width 0.127)
		(layer "In2.Cu")
		(net "I2C_EXP_RMT_SCL")
	)
	(segment
		(start 90.409268 -50.807366)
		(end 90.747088 -50.469546)
		(width 0.127)
		(layer "In2.Cu")
		(net "I2C_EXP_RMT_SCL")
	)
	(segment
		(start 86.995 -124.807218)
		(end 88.0237 -123.778518)
		(width 0.127)
		(layer "In2.Cu")
		(net "I2C_EXP_RMT_SCL")
	)
	(segment
		(start 131.64312 -39.743126)
		(end 132.299964 -40.39997)
		(width 0.127)
		(layer "In2.Cu")
		(net "I2C_EXP_RMT_SCL")
	)
	(segment
		(start 122.5931 -25.217628)
		(end 125.14072 -25.217628)
		(width 0.127)
		(layer "In2.Cu")
		(net "I2C_EXP_RMT_SCL")
	)
	(segment
		(start 88.295226 -133.124194)
		(end 88.150446 -132.979414)
		(width 0.127)
		(layer "In2.Cu")
		(net "I2C_EXP_RMT_SCL")
	)
	(segment
		(start 91.734132 -62.371732)
		(end 90.409268 -61.046868)
		(width 0.127)
		(layer "In2.Cu")
		(net "I2C_EXP_RMT_SCL")
	)
	(segment
		(start 128.9558 -29.032454)
		(end 130.158998 -29.032454)
		(width 0.127)
		(layer "In2.Cu")
		(net "I2C_EXP_RMT_SCL")
	)
	(segment
		(start 95.32239 -24.049482)
		(end 98.508058 -20.863814)
		(width 0.127)
		(layer "In2.Cu")
		(net "I2C_EXP_RMT_SCL")
	)
	(segment
		(start 87.909654 -140.070078)
		(end 87.909654 -139.496292)
		(width 0.127)
		(layer "In2.Cu")
		(net "I2C_EXP_RMT_SCL")
	)
	(segment
		(start 92.48775 -28.460446)
		(end 95.32239 -25.625806)
		(width 0.127)
		(layer "In2.Cu")
		(net "I2C_EXP_RMT_SCL")
	)
	(segment
		(start 91.734132 -111.106458)
		(end 91.734132 -62.371732)
		(width 0.127)
		(layer "In2.Cu")
		(net "I2C_EXP_RMT_SCL")
	)
	(segment
		(start 88.0237 -123.778518)
		(end 88.0237 -114.81689)
		(width 0.127)
		(layer "In2.Cu")
		(net "I2C_EXP_RMT_SCL")
	)
	(segment
		(start 92.48775 -43.327828)
		(end 92.48775 -28.460446)
		(width 0.127)
		(layer "In2.Cu")
		(net "I2C_EXP_RMT_SCL")
	)
	(segment
		(start 95.32239 -25.625806)
		(end 95.32239 -24.049482)
		(width 0.127)
		(layer "In2.Cu")
		(net "I2C_EXP_RMT_SCL")
	)
	(segment
		(start 98.508058 -20.863814)
		(end 100.506022 -20.863814)
		(width 0.127)
		(layer "In2.Cu")
		(net "I2C_EXP_RMT_SCL")
	)
	(segment
		(start 118.596156 -22.84857)
		(end 120.224042 -22.84857)
		(width 0.127)
		(layer "In2.Cu")
		(net "I2C_EXP_RMT_SCL")
	)
	(segment
		(start 117.168422 -21.420836)
		(end 118.596156 -22.84857)
		(width 0.127)
		(layer "In2.Cu")
		(net "I2C_EXP_RMT_SCL")
	)
	(segment
		(start 88.150446 -128.1176)
		(end 87.817198 -127.784352)
		(width 0.127)
		(layer "In2.Cu")
		(net "I2C_EXP_RMT_SCL")
	)
	(segment
		(start 87.242904 -127.784352)
		(end 86.995 -127.536448)
		(width 0.127)
		(layer "In2.Cu")
		(net "I2C_EXP_RMT_SCL")
	)
	(segment
		(start 128.955292 -29.0322)
		(end 128.955546 -29.0322)
		(width 0.127)
		(layer "In2.Cu")
		(net "I2C_EXP_RMT_SCL")
	)
	(segment
		(start 86.995 -127.536448)
		(end 86.995 -124.807218)
		(width 0.127)
		(layer "In2.Cu")
		(net "I2C_EXP_RMT_SCL")
	)
	(segment
		(start 88.295226 -139.11072)
		(end 88.295226 -133.124194)
		(width 0.127)
		(layer "In2.Cu")
		(net "I2C_EXP_RMT_SCL")
	)
	(segment
		(start 84.82457 -142.0622)
		(end 81.871058 -142.0622)
		(width 0.127)
		(layer "In5.Cu")
		(net "I2C_EXP_RMT_SCL")
	)
	(segment
		(start 81.871058 -142.0622)
		(end 81.60512 -141.796262)
		(width 0.127)
		(layer "In5.Cu")
		(net "I2C_EXP_RMT_SCL")
	)
	(segment
		(start 80.868266 -141.131544)
		(end 80.022192 -141.977618)
		(width 0.127)
		(layer "In5.Cu")
		(net "I2C_EXP_RMT_SCL")
	)
	(segment
		(start 86.32444 -140.56233)
		(end 84.82457 -142.0622)
		(width 0.127)
		(layer "In5.Cu")
		(net "I2C_EXP_RMT_SCL")
	)
	(segment
		(start 81.60512 -141.796262)
		(end 81.60512 -141.406626)
		(width 0.127)
		(layer "In5.Cu")
		(net "I2C_EXP_RMT_SCL")
	)
	(segment
		(start 81.60512 -141.406626)
		(end 81.330038 -141.131544)
		(width 0.127)
		(layer "In5.Cu")
		(net "I2C_EXP_RMT_SCL")
	)
	(segment
		(start 80.022192 -141.977618)
		(end 75.159108 -141.977618)
		(width 0.127)
		(layer "In5.Cu")
		(net "I2C_EXP_RMT_SCL")
	)
	(segment
		(start 75.159108 -141.977618)
		(end 74.703178 -142.433548)
		(width 0.127)
		(layer "In5.Cu")
		(net "I2C_EXP_RMT_SCL")
	)
	(segment
		(start 81.330038 -141.131544)
		(end 80.868266 -141.131544)
		(width 0.127)
		(layer "In5.Cu")
		(net "I2C_EXP_RMT_SCL")
	)
	(segment
		(start 87.417402 -140.56233)
		(end 86.32444 -140.56233)
		(width 0.127)
		(layer "In5.Cu")
		(net "I2C_EXP_RMT_SCL")
	)
	(segment
		(start 86.9188 -142.308326)
		(end 86.9188 -140.960348)
		(width 0.127)
		(layer "F.Cu")
		(net "I2C_EXP_LOC_SDA_OUT")
	)
	(segment
		(start 85.349334 -142.714218)
		(end 86.512908 -142.714218)
		(width 0.127)
		(layer "F.Cu")
		(net "I2C_EXP_LOC_SDA_OUT")
	)
	(segment
		(start 86.512908 -142.714218)
		(end 86.9188 -142.308326)
		(width 0.127)
		(layer "F.Cu")
		(net "I2C_EXP_LOC_SDA_OUT")
	)
	(segment
		(start 86.9188 -140.960348)
		(end 85.647784 -139.689332)
		(width 0.127)
		(layer "F.Cu")
		(net "I2C_EXP_LOC_SDA_OUT")
	)
	(segment
		(start 85.647784 -139.689332)
		(end 85.441028 -139.689332)
		(width 0.127)
		(layer "F.Cu")
		(net "I2C_EXP_LOC_SDA_OUT")
	)
	(segment
		(start 85.441028 -139.689332)
		(end 85.437218 -139.685522)
		(width 0.127)
		(layer "F.Cu")
		(net "I2C_EXP_LOC_SDA_OUT")
	)
	(via
		(at 85.437218 -139.685522)
		(size 0.508)
		(drill 0.254)
		(layers "F.Cu" "B.Cu")
		(net "I2C_EXP_LOC_SDA_OUT")
	)
	(via
		(at 85.6742 -148.082)
		(size 0.508)
		(drill 0.254)
		(layers "F.Cu" "B.Cu")
		(net "I2C_EXP_LOC_SDA_OUT")
	)
	(via
		(at 71.49846 -149.062948)
		(size 0.508)
		(drill 0.254)
		(layers "F.Cu" "B.Cu")
		(net "I2C_EXP_LOC_SDA_OUT")
	)
	(via
		(at 72.533256 -148.07946)
		(size 0.6096)
		(drill 0.3048)
		(layers "F.Cu" "B.Cu")
		(net "I2C_EXP_LOC_SDA_OUT")
	)
	(segment
		(start 68.811648 -141.141704)
		(end 68.817744 -141.1478)
		(width 0.127)
		(layer "B.Cu")
		(net "I2C_EXP_LOC_SDA_OUT")
	)
	(segment
		(start 72.533256 -144.923256)
		(end 72.533256 -148.07946)
		(width 0.127)
		(layer "B.Cu")
		(net "I2C_EXP_LOC_SDA_OUT")
	)
	(segment
		(start 70.03034 -142.42034)
		(end 72.533256 -144.923256)
		(width 0.127)
		(layer "B.Cu")
		(net "I2C_EXP_LOC_SDA_OUT")
	)
	(segment
		(start 65.0621 -142.621)
		(end 65.6336 -142.0495)
		(width 0.127)
		(layer "B.Cu")
		(net "I2C_EXP_LOC_SDA_OUT")
	)
	(segment
		(start 63.35014 -142.8369)
		(end 63.931546 -142.8369)
		(width 0.127)
		(layer "B.Cu")
		(net "I2C_EXP_LOC_SDA_OUT")
	)
	(segment
		(start 68.817744 -141.1478)
		(end 69.342 -141.1478)
		(width 0.127)
		(layer "B.Cu")
		(net "I2C_EXP_LOC_SDA_OUT")
	)
	(segment
		(start 64.077596 -142.69085)
		(end 64.080136 -142.69085)
		(width 0.127)
		(layer "B.Cu")
		(net "I2C_EXP_LOC_SDA_OUT")
	)
	(segment
		(start 72.533256 -148.548344)
		(end 72.533256 -148.07946)
		(width 0.127)
		(layer "B.Cu")
		(net "I2C_EXP_LOC_SDA_OUT")
	)
	(segment
		(start 68.422012 -141.141704)
		(end 68.811648 -141.141704)
		(width 0.127)
		(layer "B.Cu")
		(net "I2C_EXP_LOC_SDA_OUT")
	)
	(segment
		(start 61.4045 -143.9418)
		(end 62.3443 -143.9418)
		(width 0.127)
		(layer "B.Cu")
		(net "I2C_EXP_LOC_SDA_OUT")
	)
	(segment
		(start 65.6336 -142.0495)
		(end 67.514216 -142.0495)
		(width 0.127)
		(layer "B.Cu")
		(net "I2C_EXP_LOC_SDA_OUT")
	)
	(segment
		(start 63.931546 -142.8369)
		(end 64.077596 -142.69085)
		(width 0.127)
		(layer "B.Cu")
		(net "I2C_EXP_LOC_SDA_OUT")
	)
	(segment
		(start 72.018652 -149.062948)
		(end 72.533256 -148.548344)
		(width 0.127)
		(layer "B.Cu")
		(net "I2C_EXP_LOC_SDA_OUT")
	)
	(segment
		(start 67.514216 -142.0495)
		(end 68.422012 -141.141704)
		(width 0.127)
		(layer "B.Cu")
		(net "I2C_EXP_LOC_SDA_OUT")
	)
	(segment
		(start 62.6618 -143.52524)
		(end 63.35014 -142.8369)
		(width 0.127)
		(layer "B.Cu")
		(net "I2C_EXP_LOC_SDA_OUT")
	)
	(segment
		(start 62.5475 -143.7386)
		(end 62.6618 -143.6243)
		(width 0.127)
		(layer "B.Cu")
		(net "I2C_EXP_LOC_SDA_OUT")
	)
	(segment
		(start 64.080136 -142.69085)
		(end 64.149986 -142.621)
		(width 0.127)
		(layer "B.Cu")
		(net "I2C_EXP_LOC_SDA_OUT")
	)
	(segment
		(start 62.3443 -143.9418)
		(end 62.5475 -143.7386)
		(width 0.127)
		(layer "B.Cu")
		(net "I2C_EXP_LOC_SDA_OUT")
	)
	(segment
		(start 71.49846 -149.062948)
		(end 72.018652 -149.062948)
		(width 0.127)
		(layer "B.Cu")
		(net "I2C_EXP_LOC_SDA_OUT")
	)
	(segment
		(start 69.342 -141.1478)
		(end 70.03034 -141.83614)
		(width 0.127)
		(layer "B.Cu")
		(net "I2C_EXP_LOC_SDA_OUT")
	)
	(segment
		(start 62.6618 -143.6243)
		(end 62.6618 -143.52524)
		(width 0.127)
		(layer "B.Cu")
		(net "I2C_EXP_LOC_SDA_OUT")
	)
	(segment
		(start 70.03034 -141.83614)
		(end 70.03034 -142.42034)
		(width 0.127)
		(layer "B.Cu")
		(net "I2C_EXP_LOC_SDA_OUT")
	)
	(segment
		(start 64.149986 -142.621)
		(end 65.0621 -142.621)
		(width 0.127)
		(layer "B.Cu")
		(net "I2C_EXP_LOC_SDA_OUT")
	)
	(segment
		(start 84.84362 -143.421608)
		(end 84.84362 -147.25142)
		(width 0.127)
		(layer "In2.Cu")
		(net "I2C_EXP_LOC_SDA_OUT")
	)
	(segment
		(start 85.437218 -139.685522)
		(end 85.30717 -139.81557)
		(width 0.127)
		(layer "In2.Cu")
		(net "I2C_EXP_LOC_SDA_OUT")
	)
	(segment
		(start 85.30717 -139.81557)
		(end 85.30717 -142.958058)
		(width 0.127)
		(layer "In2.Cu")
		(net "I2C_EXP_LOC_SDA_OUT")
	)
	(segment
		(start 84.84362 -147.25142)
		(end 85.6742 -148.082)
		(width 0.127)
		(layer "In2.Cu")
		(net "I2C_EXP_LOC_SDA_OUT")
	)
	(segment
		(start 85.30717 -142.958058)
		(end 84.84362 -143.421608)
		(width 0.127)
		(layer "In2.Cu")
		(net "I2C_EXP_LOC_SDA_OUT")
	)
	(segment
		(start 77.182218 -149.5679)
		(end 76.792582 -149.5679)
		(width 0.127)
		(layer "In5.Cu")
		(net "I2C_EXP_LOC_SDA_OUT")
	)
	(segment
		(start 83.112864 -148.941536)
		(end 77.808582 -148.941536)
		(width 0.127)
		(layer "In5.Cu")
		(net "I2C_EXP_LOC_SDA_OUT")
	)
	(segment
		(start 74.71791 -149.3774)
		(end 72.442832 -149.3774)
		(width 0.127)
		(layer "In5.Cu")
		(net "I2C_EXP_LOC_SDA_OUT")
	)
	(segment
		(start 85.6742 -148.082)
		(end 85.619336 -148.082)
		(width 0.127)
		(layer "In5.Cu")
		(net "I2C_EXP_LOC_SDA_OUT")
	)
	(segment
		(start 76.364592 -149.13991)
		(end 74.9554 -149.13991)
		(width 0.127)
		(layer "In5.Cu")
		(net "I2C_EXP_LOC_SDA_OUT")
	)
	(segment
		(start 83.82 -148.2344)
		(end 83.112864 -148.941536)
		(width 0.127)
		(layer "In5.Cu")
		(net "I2C_EXP_LOC_SDA_OUT")
	)
	(segment
		(start 76.792582 -149.5679)
		(end 76.364592 -149.13991)
		(width 0.127)
		(layer "In5.Cu")
		(net "I2C_EXP_LOC_SDA_OUT")
	)
	(segment
		(start 77.808582 -148.941536)
		(end 77.182218 -149.5679)
		(width 0.127)
		(layer "In5.Cu")
		(net "I2C_EXP_LOC_SDA_OUT")
	)
	(segment
		(start 72.442832 -149.3774)
		(end 72.12838 -149.062948)
		(width 0.127)
		(layer "In5.Cu")
		(net "I2C_EXP_LOC_SDA_OUT")
	)
	(segment
		(start 74.9554 -149.13991)
		(end 74.71791 -149.3774)
		(width 0.127)
		(layer "In5.Cu")
		(net "I2C_EXP_LOC_SDA_OUT")
	)
	(segment
		(start 85.466936 -148.2344)
		(end 83.82 -148.2344)
		(width 0.127)
		(layer "In5.Cu")
		(net "I2C_EXP_LOC_SDA_OUT")
	)
	(segment
		(start 85.619336 -148.082)
		(end 85.466936 -148.2344)
		(width 0.127)
		(layer "In5.Cu")
		(net "I2C_EXP_LOC_SDA_OUT")
	)
	(segment
		(start 72.12838 -149.062948)
		(end 71.49846 -149.062948)
		(width 0.127)
		(layer "In5.Cu")
		(net "I2C_EXP_LOC_SDA_OUT")
	)
	(via
		(at 81.989676 -144.42821)
		(size 0.6096)
		(drill 0.3048)
		(layers "F.Cu" "B.Cu")
		(net "I2C_EXP_LOC_SDA")
	)
	(via
		(at 82.3468 -143.5862)
		(size 0.508)
		(drill 0.254)
		(layers "F.Cu" "B.Cu")
		(net "I2C_EXP_LOC_SDA")
	)
	(segment
		(start 81.9912 -144.426686)
		(end 81.989676 -144.42821)
		(width 0.127)
		(layer "B.Cu")
		(net "I2C_EXP_LOC_SDA")
	)
	(segment
		(start 82.050128 -144.365472)
		(end 81.9912 -144.4244)
		(width 0.127)
		(layer "B.Cu")
		(net "I2C_EXP_LOC_SDA")
	)
	(segment
		(start 82.3468 -143.5862)
		(end 82.050128 -143.882872)
		(width 0.127)
		(layer "B.Cu")
		(net "I2C_EXP_LOC_SDA")
	)
	(segment
		(start 81.560416 -144.85747)
		(end 80.98663 -144.85747)
		(width 0.127)
		(layer "B.Cu")
		(net "I2C_EXP_LOC_SDA")
	)
	(segment
		(start 80.98663 -144.85747)
		(end 80.3021 -145.542)
		(width 0.127)
		(layer "B.Cu")
		(net "I2C_EXP_LOC_SDA")
	)
	(segment
		(start 82.050128 -143.882872)
		(end 82.050128 -144.365472)
		(width 0.127)
		(layer "B.Cu")
		(net "I2C_EXP_LOC_SDA")
	)
	(segment
		(start 81.989676 -144.42821)
		(end 81.560416 -144.85747)
		(width 0.127)
		(layer "B.Cu")
		(net "I2C_EXP_LOC_SDA")
	)
	(segment
		(start 81.9912 -144.4244)
		(end 81.9912 -144.426686)
		(width 0.127)
		(layer "B.Cu")
		(net "I2C_EXP_LOC_SDA")
	)
	(segment
		(start 92.888054 -9.56564)
		(end 86.166706 -9.56564)
		(width 0.127)
		(layer "In2.Cu")
		(net "I2C_EXP_LOC_SDA")
	)
	(segment
		(start 81.466944 -136.996424)
		(end 81.64957 -137.17905)
		(width 0.127)
		(layer "In2.Cu")
		(net "I2C_EXP_LOC_SDA")
	)
	(segment
		(start 89.50833 -43.15587)
		(end 87.942928 -44.721272)
		(width 0.127)
		(layer "In2.Cu")
		(net "I2C_EXP_LOC_SDA")
	)
	(segment
		(start 101.962458 -20.404836)
		(end 97.72904 -16.171418)
		(width 0.127)
		(layer "In2.Cu")
		(net "I2C_EXP_LOC_SDA")
	)
	(segment
		(start 130.58013 -28.016454)
		(end 129.376932 -28.016454)
		(width 0.127)
		(layer "In2.Cu")
		(net "I2C_EXP_LOC_SDA")
	)
	(segment
		(start 97.72904 -16.171418)
		(end 96.769174 -16.171418)
		(width 0.127)
		(layer "In2.Cu")
		(net "I2C_EXP_LOC_SDA")
	)
	(segment
		(start 82.076798 -132.41782)
		(end 81.466944 -133.027674)
		(width 0.127)
		(layer "In2.Cu")
		(net "I2C_EXP_LOC_SDA")
	)
	(segment
		(start 129.376424 -28.0162)
		(end 126.123192 -24.762968)
		(width 0.127)
		(layer "In2.Cu")
		(net "I2C_EXP_LOC_SDA")
	)
	(segment
		(start 126.123192 -24.762968)
		(end 126.123192 -24.762714)
		(width 0.127)
		(layer "In2.Cu")
		(net "I2C_EXP_LOC_SDA")
	)
	(segment
		(start 85.9028 -122.889772)
		(end 84.505546 -124.287026)
		(width 0.127)
		(layer "In2.Cu")
		(net "I2C_EXP_LOC_SDA")
	)
	(segment
		(start 126.123192 -24.762714)
		(end 125.561852 -24.201374)
		(width 0.127)
		(layer "In2.Cu")
		(net "I2C_EXP_LOC_SDA")
	)
	(segment
		(start 86.166706 -9.56564)
		(end 86.166452 -9.565386)
		(width 0.127)
		(layer "In2.Cu")
		(net "I2C_EXP_LOC_SDA")
	)
	(segment
		(start 119.017288 -21.83257)
		(end 117.589554 -20.404836)
		(width 0.127)
		(layer "In2.Cu")
		(net "I2C_EXP_LOC_SDA")
	)
	(segment
		(start 81.64957 -142.88897)
		(end 82.3468 -143.5862)
		(width 0.127)
		(layer "In2.Cu")
		(net "I2C_EXP_LOC_SDA")
	)
	(segment
		(start 89.613232 -64.155574)
		(end 89.613232 -110.227618)
		(width 0.127)
		(layer "In2.Cu")
		(net "I2C_EXP_LOC_SDA")
	)
	(segment
		(start 133.379464 -44.32046)
		(end 133.379464 -30.815788)
		(width 0.127)
		(layer "In2.Cu")
		(net "I2C_EXP_LOC_SDA")
	)
	(segment
		(start 87.942928 -62.48527)
		(end 89.613232 -64.155574)
		(width 0.127)
		(layer "In2.Cu")
		(net "I2C_EXP_LOC_SDA")
	)
	(segment
		(start 94.679262 -14.081506)
		(end 94.679262 -11.356848)
		(width 0.127)
		(layer "In2.Cu")
		(net "I2C_EXP_LOC_SDA")
	)
	(segment
		(start 81.466944 -133.027674)
		(end 81.466944 -136.996424)
		(width 0.127)
		(layer "In2.Cu")
		(net "I2C_EXP_LOC_SDA")
	)
	(segment
		(start 86.166452 -9.565386)
		(end 84.704428 -9.565386)
		(width 0.127)
		(layer "In2.Cu")
		(net "I2C_EXP_LOC_SDA")
	)
	(segment
		(start 87.942928 -44.721272)
		(end 87.942928 -62.48527)
		(width 0.127)
		(layer "In2.Cu")
		(net "I2C_EXP_LOC_SDA")
	)
	(segment
		(start 125.561852 -24.201374)
		(end 123.013978 -24.201374)
		(width 0.127)
		(layer "In2.Cu")
		(net "I2C_EXP_LOC_SDA")
	)
	(segment
		(start 96.769174 -16.171418)
		(end 94.679262 -14.081506)
		(width 0.127)
		(layer "In2.Cu")
		(net "I2C_EXP_LOC_SDA")
	)
	(segment
		(start 84.505546 -124.287026)
		(end 84.505546 -127.303784)
		(width 0.127)
		(layer "In2.Cu")
		(net "I2C_EXP_LOC_SDA")
	)
	(segment
		(start 89.613232 -110.227618)
		(end 85.9028 -113.93805)
		(width 0.127)
		(layer "In2.Cu")
		(net "I2C_EXP_LOC_SDA")
	)
	(segment
		(start 89.50833 -36.17341)
		(end 89.50833 -43.15587)
		(width 0.127)
		(layer "In2.Cu")
		(net "I2C_EXP_LOC_SDA")
	)
	(segment
		(start 83.05038 -29.71546)
		(end 89.50833 -36.17341)
		(width 0.127)
		(layer "In2.Cu")
		(net "I2C_EXP_LOC_SDA")
	)
	(segment
		(start 123.013978 -24.201374)
		(end 120.645174 -21.83257)
		(width 0.127)
		(layer "In2.Cu")
		(net "I2C_EXP_LOC_SDA")
	)
	(segment
		(start 120.645174 -21.83257)
		(end 119.017288 -21.83257)
		(width 0.127)
		(layer "In2.Cu")
		(net "I2C_EXP_LOC_SDA")
	)
	(segment
		(start 129.376678 -28.0162)
		(end 129.376424 -28.0162)
		(width 0.127)
		(layer "In2.Cu")
		(net "I2C_EXP_LOC_SDA")
	)
	(segment
		(start 94.679262 -11.356848)
		(end 92.888054 -9.56564)
		(width 0.127)
		(layer "In2.Cu")
		(net "I2C_EXP_LOC_SDA")
	)
	(segment
		(start 82.076798 -129.732532)
		(end 82.076798 -132.41782)
		(width 0.127)
		(layer "In2.Cu")
		(net "I2C_EXP_LOC_SDA")
	)
	(segment
		(start 133.379464 -30.815788)
		(end 130.58013 -28.016454)
		(width 0.127)
		(layer "In2.Cu")
		(net "I2C_EXP_LOC_SDA")
	)
	(segment
		(start 129.376932 -28.016454)
		(end 129.376678 -28.0162)
		(width 0.127)
		(layer "In2.Cu")
		(net "I2C_EXP_LOC_SDA")
	)
	(segment
		(start 85.9028 -113.93805)
		(end 85.9028 -122.889772)
		(width 0.127)
		(layer "In2.Cu")
		(net "I2C_EXP_LOC_SDA")
	)
	(segment
		(start 84.505546 -127.303784)
		(end 82.076798 -129.732532)
		(width 0.127)
		(layer "In2.Cu")
		(net "I2C_EXP_LOC_SDA")
	)
	(segment
		(start 117.589554 -20.404836)
		(end 101.962458 -20.404836)
		(width 0.127)
		(layer "In2.Cu")
		(net "I2C_EXP_LOC_SDA")
	)
	(segment
		(start 81.64957 -137.17905)
		(end 81.64957 -142.88897)
		(width 0.127)
		(layer "In2.Cu")
		(net "I2C_EXP_LOC_SDA")
	)
	(segment
		(start 83.05038 -11.219434)
		(end 83.05038 -29.71546)
		(width 0.127)
		(layer "In2.Cu")
		(net "I2C_EXP_LOC_SDA")
	)
	(segment
		(start 132.299964 -45.39996)
		(end 133.379464 -44.32046)
		(width 0.127)
		(layer "In2.Cu")
		(net "I2C_EXP_LOC_SDA")
	)
	(segment
		(start 84.704428 -9.565386)
		(end 83.05038 -11.219434)
		(width 0.127)
		(layer "In2.Cu")
		(net "I2C_EXP_LOC_SDA")
	)
	(segment
		(start 86.4108 -141.1732)
		(end 86.4108 -141.859)
		(width 0.127)
		(layer "F.Cu")
		(net "I2C_EXP_LOC_SCL_OUT")
	)
	(segment
		(start 86.205822 -142.063978)
		(end 85.349334 -142.063978)
		(width 0.127)
		(layer "F.Cu")
		(net "I2C_EXP_LOC_SCL_OUT")
	)
	(segment
		(start 85.925152 -140.687552)
		(end 86.4108 -141.1732)
		(width 0.127)
		(layer "F.Cu")
		(net "I2C_EXP_LOC_SCL_OUT")
	)
	(segment
		(start 86.4108 -141.859)
		(end 86.205822 -142.063978)
		(width 0.127)
		(layer "F.Cu")
		(net "I2C_EXP_LOC_SCL_OUT")
	)
	(segment
		(start 84.712048 -140.687552)
		(end 85.925152 -140.687552)
		(width 0.127)
		(layer "F.Cu")
		(net "I2C_EXP_LOC_SCL_OUT")
	)
	(via
		(at 85.0646 -148.8694)
		(size 0.508)
		(drill 0.254)
		(layers "F.Cu" "B.Cu")
		(net "I2C_EXP_LOC_SCL_OUT")
	)
	(via
		(at 73.3298 -149.0726)
		(size 0.6096)
		(drill 0.3048)
		(layers "F.Cu" "B.Cu")
		(net "I2C_EXP_LOC_SCL_OUT")
	)
	(via
		(at 71.52894 -149.92604)
		(size 0.508)
		(drill 0.254)
		(layers "F.Cu" "B.Cu")
		(net "I2C_EXP_LOC_SCL_OUT")
	)
	(via
		(at 84.712048 -140.687552)
		(size 0.508)
		(drill 0.254)
		(layers "F.Cu" "B.Cu")
		(net "I2C_EXP_LOC_SCL_OUT")
	)
	(segment
		(start 62.207902 -142.9004)
		(end 62.52083 -142.587472)
		(width 0.127)
		(layer "B.Cu")
		(net "I2C_EXP_LOC_SCL_OUT")
	)
	(segment
		(start 65.863724 -141.478)
		(end 65.86093 -141.480794)
		(width 0.127)
		(layer "B.Cu")
		(net "I2C_EXP_LOC_SCL_OUT")
	)
	(segment
		(start 64.6176 -142.0876)
		(end 63.96228 -142.0876)
		(width 0.127)
		(layer "B.Cu")
		(net "I2C_EXP_LOC_SCL_OUT")
	)
	(segment
		(start 65.4685 -141.478)
		(end 65.2272 -141.478)
		(width 0.127)
		(layer "B.Cu")
		(net "I2C_EXP_LOC_SCL_OUT")
	)
	(segment
		(start 62.881002 -142.587472)
		(end 62.52083 -142.587472)
		(width 0.127)
		(layer "B.Cu")
		(net "I2C_EXP_LOC_SCL_OUT")
	)
	(segment
		(start 63.72098 -142.3289)
		(end 63.139574 -142.3289)
		(width 0.127)
		(layer "B.Cu")
		(net "I2C_EXP_LOC_SCL_OUT")
	)
	(segment
		(start 65.86093 -141.480794)
		(end 65.471294 -141.480794)
		(width 0.127)
		(layer "B.Cu")
		(net "I2C_EXP_LOC_SCL_OUT")
	)
	(segment
		(start 63.139574 -142.3289)
		(end 62.881002 -142.587472)
		(width 0.127)
		(layer "B.Cu")
		(net "I2C_EXP_LOC_SCL_OUT")
	)
	(segment
		(start 70.616318 -141.703552)
		(end 69.54647 -140.633704)
		(width 0.127)
		(layer "B.Cu")
		(net "I2C_EXP_LOC_SCL_OUT")
	)
	(segment
		(start 67.10553 -141.478)
		(end 65.863724 -141.478)
		(width 0.127)
		(layer "B.Cu")
		(net "I2C_EXP_LOC_SCL_OUT")
	)
	(segment
		(start 71.59498 -149.86)
		(end 72.5424 -149.86)
		(width 0.127)
		(layer "B.Cu")
		(net "I2C_EXP_LOC_SCL_OUT")
	)
	(segment
		(start 67.949826 -140.633704)
		(end 67.10553 -141.478)
		(width 0.127)
		(layer "B.Cu")
		(net "I2C_EXP_LOC_SCL_OUT")
	)
	(segment
		(start 63.96228 -142.0876)
		(end 63.72098 -142.3289)
		(width 0.127)
		(layer "B.Cu")
		(net "I2C_EXP_LOC_SCL_OUT")
	)
	(segment
		(start 65.471294 -141.480794)
		(end 65.4685 -141.478)
		(width 0.127)
		(layer "B.Cu")
		(net "I2C_EXP_LOC_SCL_OUT")
	)
	(segment
		(start 73.3298 -145.001234)
		(end 70.616318 -142.287752)
		(width 0.127)
		(layer "B.Cu")
		(net "I2C_EXP_LOC_SCL_OUT")
	)
	(segment
		(start 72.5424 -149.86)
		(end 73.3298 -149.0726)
		(width 0.127)
		(layer "B.Cu")
		(net "I2C_EXP_LOC_SCL_OUT")
	)
	(segment
		(start 61.4045 -142.9004)
		(end 62.207902 -142.9004)
		(width 0.127)
		(layer "B.Cu")
		(net "I2C_EXP_LOC_SCL_OUT")
	)
	(segment
		(start 65.2272 -141.478)
		(end 64.6176 -142.0876)
		(width 0.127)
		(layer "B.Cu")
		(net "I2C_EXP_LOC_SCL_OUT")
	)
	(segment
		(start 73.3298 -149.0726)
		(end 73.3298 -145.001234)
		(width 0.127)
		(layer "B.Cu")
		(net "I2C_EXP_LOC_SCL_OUT")
	)
	(segment
		(start 69.54647 -140.633704)
		(end 67.949826 -140.633704)
		(width 0.127)
		(layer "B.Cu")
		(net "I2C_EXP_LOC_SCL_OUT")
	)
	(segment
		(start 70.616318 -142.287752)
		(end 70.616318 -141.703552)
		(width 0.127)
		(layer "B.Cu")
		(net "I2C_EXP_LOC_SCL_OUT")
	)
	(segment
		(start 71.52894 -149.92604)
		(end 71.59498 -149.86)
		(width 0.127)
		(layer "B.Cu")
		(net "I2C_EXP_LOC_SCL_OUT")
	)
	(segment
		(start 85.0646 -148.7678)
		(end 85.0646 -148.8694)
		(width 0.127)
		(layer "In2.Cu")
		(net "I2C_EXP_LOC_SCL_OUT")
	)
	(segment
		(start 84.33562 -143.211042)
		(end 84.33562 -148.03882)
		(width 0.127)
		(layer "In2.Cu")
		(net "I2C_EXP_LOC_SCL_OUT")
	)
	(segment
		(start 84.712048 -140.687552)
		(end 84.475066 -140.924534)
		(width 0.127)
		(layer "In2.Cu")
		(net "I2C_EXP_LOC_SCL_OUT")
	)
	(segment
		(start 84.475066 -140.924534)
		(end 84.475066 -143.071596)
		(width 0.127)
		(layer "In2.Cu")
		(net "I2C_EXP_LOC_SCL_OUT")
	)
	(segment
		(start 84.475066 -143.071596)
		(end 84.33562 -143.211042)
		(width 0.127)
		(layer "In2.Cu")
		(net "I2C_EXP_LOC_SCL_OUT")
	)
	(segment
		(start 84.33562 -148.03882)
		(end 85.0646 -148.7678)
		(width 0.127)
		(layer "In2.Cu")
		(net "I2C_EXP_LOC_SCL_OUT")
	)
	(segment
		(start 84.9376 -148.7424)
		(end 84.030566 -148.7424)
		(width 0.127)
		(layer "In5.Cu")
		(net "I2C_EXP_LOC_SCL_OUT")
	)
	(segment
		(start 76.11491 -149.64791)
		(end 75.165966 -149.64791)
		(width 0.127)
		(layer "In5.Cu")
		(net "I2C_EXP_LOC_SCL_OUT")
	)
	(segment
		(start 77.392784 -150.0759)
		(end 76.5429 -150.0759)
		(width 0.127)
		(layer "In5.Cu")
		(net "I2C_EXP_LOC_SCL_OUT")
	)
	(segment
		(start 84.030566 -148.7424)
		(end 83.32343 -149.449536)
		(width 0.127)
		(layer "In5.Cu")
		(net "I2C_EXP_LOC_SCL_OUT")
	)
	(segment
		(start 76.5429 -150.0759)
		(end 76.11491 -149.64791)
		(width 0.127)
		(layer "In5.Cu")
		(net "I2C_EXP_LOC_SCL_OUT")
	)
	(segment
		(start 78.019148 -149.449536)
		(end 77.392784 -150.0759)
		(width 0.127)
		(layer "In5.Cu")
		(net "I2C_EXP_LOC_SCL_OUT")
	)
	(segment
		(start 85.0646 -148.8694)
		(end 84.9376 -148.7424)
		(width 0.127)
		(layer "In5.Cu")
		(net "I2C_EXP_LOC_SCL_OUT")
	)
	(segment
		(start 74.928476 -149.8854)
		(end 71.56958 -149.8854)
		(width 0.127)
		(layer "In5.Cu")
		(net "I2C_EXP_LOC_SCL_OUT")
	)
	(segment
		(start 83.32343 -149.449536)
		(end 78.019148 -149.449536)
		(width 0.127)
		(layer "In5.Cu")
		(net "I2C_EXP_LOC_SCL_OUT")
	)
	(segment
		(start 75.165966 -149.64791)
		(end 74.928476 -149.8854)
		(width 0.127)
		(layer "In5.Cu")
		(net "I2C_EXP_LOC_SCL_OUT")
	)
	(segment
		(start 71.56958 -149.8854)
		(end 71.52894 -149.92604)
		(width 0.127)
		(layer "In5.Cu")
		(net "I2C_EXP_LOC_SCL_OUT")
	)
	(via
		(at 82.209386 -141.55674)
		(size 0.508)
		(drill 0.254)
		(layers "F.Cu" "B.Cu")
		(net "I2C_EXP_LOC_SCL")
	)
	(via
		(at 82.005932 -142.44828)
		(size 0.6096)
		(drill 0.3048)
		(layers "F.Cu" "B.Cu")
		(net "I2C_EXP_LOC_SCL")
	)
	(segment
		(start 79.2099 -142.3162)
		(end 78.9178 -142.0241)
		(width 0.127)
		(layer "B.Cu")
		(net "I2C_EXP_LOC_SCL")
	)
	(segment
		(start 82.005932 -142.44828)
		(end 81.69148 -142.44828)
		(width 0.127)
		(layer "B.Cu")
		(net "I2C_EXP_LOC_SCL")
	)
	(segment
		(start 81.5594 -142.3162)
		(end 79.2099 -142.3162)
		(width 0.127)
		(layer "B.Cu")
		(net "I2C_EXP_LOC_SCL")
	)
	(segment
		(start 82.209386 -141.55674)
		(end 82.209386 -142.244826)
		(width 0.127)
		(layer "B.Cu")
		(net "I2C_EXP_LOC_SCL")
	)
	(segment
		(start 81.69148 -142.44828)
		(end 81.5594 -142.3162)
		(width 0.127)
		(layer "B.Cu")
		(net "I2C_EXP_LOC_SCL")
	)
	(segment
		(start 82.209386 -142.244826)
		(end 82.005932 -142.44828)
		(width 0.127)
		(layer "B.Cu")
		(net "I2C_EXP_LOC_SCL")
	)
	(segment
		(start 86.4108 -123.100338)
		(end 85.013546 -124.497592)
		(width 0.127)
		(layer "In2.Cu")
		(net "I2C_EXP_LOC_SCL")
	)
	(segment
		(start 120.434608 -22.34057)
		(end 118.806722 -22.34057)
		(width 0.127)
		(layer "In2.Cu")
		(net "I2C_EXP_LOC_SCL")
	)
	(segment
		(start 122.803666 -24.709628)
		(end 120.434608 -22.34057)
		(width 0.127)
		(layer "In2.Cu")
		(net "I2C_EXP_LOC_SCL")
	)
	(segment
		(start 94.171262 -14.292072)
		(end 94.171262 -12.21867)
		(width 0.127)
		(layer "In2.Cu")
		(net "I2C_EXP_LOC_SCL")
	)
	(segment
		(start 90.01633 -43.366436)
		(end 89.134188 -44.248578)
		(width 0.127)
		(layer "In2.Cu")
		(net "I2C_EXP_LOC_SCL")
	)
	(segment
		(start 83.063588 -130.365754)
		(end 83.063588 -132.174234)
		(width 0.127)
		(layer "In2.Cu")
		(net "I2C_EXP_LOC_SCL")
	)
	(segment
		(start 96.97974 -16.679418)
		(end 96.979486 -16.679672)
		(width 0.127)
		(layer "In2.Cu")
		(net "I2C_EXP_LOC_SCL")
	)
	(segment
		(start 88.481662 -50.419)
		(end 88.481662 -62.305438)
		(width 0.127)
		(layer "In2.Cu")
		(net "I2C_EXP_LOC_SCL")
	)
	(segment
		(start 130.369564 -28.524454)
		(end 129.166366 -28.524454)
		(width 0.127)
		(layer "In2.Cu")
		(net "I2C_EXP_LOC_SCL")
	)
	(segment
		(start 85.0138 -126.94793)
		(end 85.013546 -126.948184)
		(width 0.127)
		(layer "In2.Cu")
		(net "I2C_EXP_LOC_SCL")
	)
	(segment
		(start 125.615192 -24.97328)
		(end 125.35154 -24.709628)
		(width 0.127)
		(layer "In2.Cu")
		(net "I2C_EXP_LOC_SCL")
	)
	(segment
		(start 82.49412 -132.743702)
		(end 82.49412 -135.668512)
		(width 0.127)
		(layer "In2.Cu")
		(net "I2C_EXP_LOC_SCL")
	)
	(segment
		(start 83.55838 -11.43)
		(end 83.55838 -29.504894)
		(width 0.127)
		(layer "In2.Cu")
		(net "I2C_EXP_LOC_SCL")
	)
	(segment
		(start 94.171262 -12.21867)
		(end 93.7006 -11.748008)
		(width 0.127)
		(layer "In2.Cu")
		(net "I2C_EXP_LOC_SCL")
	)
	(segment
		(start 132.871464 -31.026354)
		(end 130.369564 -28.524454)
		(width 0.127)
		(layer "In2.Cu")
		(net "I2C_EXP_LOC_SCL")
	)
	(segment
		(start 129.165858 -28.5242)
		(end 125.615192 -24.973534)
		(width 0.127)
		(layer "In2.Cu")
		(net "I2C_EXP_LOC_SCL")
	)
	(segment
		(start 84.91474 -10.07364)
		(end 83.55838 -11.43)
		(width 0.127)
		(layer "In2.Cu")
		(net "I2C_EXP_LOC_SCL")
	)
	(segment
		(start 89.134188 -49.766474)
		(end 88.481662 -50.419)
		(width 0.127)
		(layer "In2.Cu")
		(net "I2C_EXP_LOC_SCL")
	)
	(segment
		(start 132.871464 -43.428666)
		(end 132.871464 -31.026354)
		(width 0.127)
		(layer "In2.Cu")
		(net "I2C_EXP_LOC_SCL")
	)
	(segment
		(start 82.8548 -129.673096)
		(end 82.8548 -130.156966)
		(width 0.127)
		(layer "In2.Cu")
		(net "I2C_EXP_LOC_SCL")
	)
	(segment
		(start 88.481662 -62.305438)
		(end 90.121232 -63.945008)
		(width 0.127)
		(layer "In2.Cu")
		(net "I2C_EXP_LOC_SCL")
	)
	(segment
		(start 97.518474 -16.679418)
		(end 96.97974 -16.679418)
		(width 0.127)
		(layer "In2.Cu")
		(net "I2C_EXP_LOC_SCL")
	)
	(segment
		(start 96.558862 -16.679672)
		(end 94.171262 -14.292072)
		(width 0.127)
		(layer "In2.Cu")
		(net "I2C_EXP_LOC_SCL")
	)
	(segment
		(start 82.8548 -130.156966)
		(end 83.063588 -130.365754)
		(width 0.127)
		(layer "In2.Cu")
		(net "I2C_EXP_LOC_SCL")
	)
	(segment
		(start 85.013546 -124.497592)
		(end 85.013546 -124.701808)
		(width 0.127)
		(layer "In2.Cu")
		(net "I2C_EXP_LOC_SCL")
	)
	(segment
		(start 82.15757 -136.005062)
		(end 82.15757 -141.504924)
		(width 0.127)
		(layer "In2.Cu")
		(net "I2C_EXP_LOC_SCL")
	)
	(segment
		(start 90.01633 -35.962844)
		(end 90.01633 -43.366436)
		(width 0.127)
		(layer "In2.Cu")
		(net "I2C_EXP_LOC_SCL")
	)
	(segment
		(start 85.013546 -127.51435)
		(end 82.8548 -129.673096)
		(width 0.127)
		(layer "In2.Cu")
		(net "I2C_EXP_LOC_SCL")
	)
	(segment
		(start 125.35154 -24.709628)
		(end 122.803666 -24.709628)
		(width 0.127)
		(layer "In2.Cu")
		(net "I2C_EXP_LOC_SCL")
	)
	(segment
		(start 82.49412 -135.668512)
		(end 82.15757 -136.005062)
		(width 0.127)
		(layer "In2.Cu")
		(net "I2C_EXP_LOC_SCL")
	)
	(segment
		(start 129.166112 -28.5242)
		(end 129.165858 -28.5242)
		(width 0.127)
		(layer "In2.Cu")
		(net "I2C_EXP_LOC_SCL")
	)
	(segment
		(start 83.55838 -29.504894)
		(end 90.01633 -35.962844)
		(width 0.127)
		(layer "In2.Cu")
		(net "I2C_EXP_LOC_SCL")
	)
	(segment
		(start 129.166366 -28.524454)
		(end 129.166112 -28.5242)
		(width 0.127)
		(layer "In2.Cu")
		(net "I2C_EXP_LOC_SCL")
	)
	(segment
		(start 82.15757 -141.504924)
		(end 82.209386 -141.55674)
		(width 0.127)
		(layer "In2.Cu")
		(net "I2C_EXP_LOC_SCL")
	)
	(segment
		(start 83.063588 -132.174234)
		(end 82.49412 -132.743702)
		(width 0.127)
		(layer "In2.Cu")
		(net "I2C_EXP_LOC_SCL")
	)
	(segment
		(start 101.751892 -20.912836)
		(end 97.518474 -16.679418)
		(width 0.127)
		(layer "In2.Cu")
		(net "I2C_EXP_LOC_SCL")
	)
	(segment
		(start 96.979486 -16.679672)
		(end 96.558862 -16.679672)
		(width 0.127)
		(layer "In2.Cu")
		(net "I2C_EXP_LOC_SCL")
	)
	(segment
		(start 85.013546 -124.701808)
		(end 85.0138 -124.701808)
		(width 0.127)
		(layer "In2.Cu")
		(net "I2C_EXP_LOC_SCL")
	)
	(segment
		(start 86.4108 -114.148616)
		(end 86.4108 -123.100338)
		(width 0.127)
		(layer "In2.Cu")
		(net "I2C_EXP_LOC_SCL")
	)
	(segment
		(start 117.378988 -20.912836)
		(end 101.751892 -20.912836)
		(width 0.127)
		(layer "In2.Cu")
		(net "I2C_EXP_LOC_SCL")
	)
	(segment
		(start 90.121232 -63.945008)
		(end 90.121232 -110.438184)
		(width 0.127)
		(layer "In2.Cu")
		(net "I2C_EXP_LOC_SCL")
	)
	(segment
		(start 90.121232 -110.438184)
		(end 86.4108 -114.148616)
		(width 0.127)
		(layer "In2.Cu")
		(net "I2C_EXP_LOC_SCL")
	)
	(segment
		(start 92.677488 -10.07364)
		(end 84.91474 -10.07364)
		(width 0.127)
		(layer "In2.Cu")
		(net "I2C_EXP_LOC_SCL")
	)
	(segment
		(start 93.7006 -11.096752)
		(end 92.677488 -10.07364)
		(width 0.127)
		(layer "In2.Cu")
		(net "I2C_EXP_LOC_SCL")
	)
	(segment
		(start 85.0138 -124.701808)
		(end 85.0138 -126.94793)
		(width 0.127)
		(layer "In2.Cu")
		(net "I2C_EXP_LOC_SCL")
	)
	(segment
		(start 93.7006 -11.748008)
		(end 93.7006 -11.096752)
		(width 0.127)
		(layer "In2.Cu")
		(net "I2C_EXP_LOC_SCL")
	)
	(segment
		(start 85.013546 -126.948184)
		(end 85.013546 -127.51435)
		(width 0.127)
		(layer "In2.Cu")
		(net "I2C_EXP_LOC_SCL")
	)
	(segment
		(start 89.134188 -44.248578)
		(end 89.134188 -49.766474)
		(width 0.127)
		(layer "In2.Cu")
		(net "I2C_EXP_LOC_SCL")
	)
	(segment
		(start 125.615192 -24.973534)
		(end 125.615192 -24.97328)
		(width 0.127)
		(layer "In2.Cu")
		(net "I2C_EXP_LOC_SCL")
	)
	(segment
		(start 132.299964 -44.000166)
		(end 132.871464 -43.428666)
		(width 0.127)
		(layer "In2.Cu")
		(net "I2C_EXP_LOC_SCL")
	)
	(segment
		(start 118.806722 -22.34057)
		(end 117.378988 -20.912836)
		(width 0.127)
		(layer "In2.Cu")
		(net "I2C_EXP_LOC_SCL")
	)
	(segment
		(start 46.018704 -159.4104)
		(end 46.018704 -160.916112)
		(width 0.127)
		(layer "F.Cu")
		(net "I2C_DPB_SDA_OUT")
	)
	(segment
		(start 45.99559 -159.272732)
		(end 46.018704 -159.295846)
		(width 0.127)
		(layer "F.Cu")
		(net "I2C_DPB_SDA_OUT")
	)
	(segment
		(start 46.018704 -159.295846)
		(end 46.018704 -159.4104)
		(width 0.127)
		(layer "F.Cu")
		(net "I2C_DPB_SDA_OUT")
	)
	(segment
		(start 83.790536 -146.615658)
		(end 82.67065 -145.495772)
		(width 0.127)
		(layer "F.Cu")
		(net "I2C_DPB_SDA_OUT")
	)
	(segment
		(start 85.349334 -146.615658)
		(end 83.790536 -146.615658)
		(width 0.127)
		(layer "F.Cu")
		(net "I2C_DPB_SDA_OUT")
	)
	(segment
		(start 45.99559 -158.6357)
		(end 45.99559 -159.272732)
		(width 0.127)
		(layer "F.Cu")
		(net "I2C_DPB_SDA_OUT")
	)
	(segment
		(start 46.018704 -160.916112)
		(end 46.011084 -160.923732)
		(width 0.127)
		(layer "F.Cu")
		(net "I2C_DPB_SDA_OUT")
	)
	(via
		(at 82.67065 -145.495772)
		(size 0.508)
		(drill 0.254)
		(layers "F.Cu" "B.Cu")
		(net "I2C_DPB_SDA_OUT")
	)
	(via
		(at 100.690426 -172.645832)
		(size 0.508)
		(drill 0.254)
		(layers "F.Cu" "B.Cu")
		(net "I2C_DPB_SDA_OUT")
	)
	(via
		(at 101.586284 -141.903958)
		(size 0.508)
		(drill 0.254)
		(layers "F.Cu" "B.Cu")
		(net "I2C_DPB_SDA_OUT")
	)
	(via
		(at 46.018704 -159.4104)
		(size 0.508)
		(drill 0.254)
		(layers "F.Cu" "B.Cu")
		(net "I2C_DPB_SDA_OUT")
	)
	(segment
		(start 101.586284 -141.903958)
		(end 101.031548 -142.458694)
		(width 0.127)
		(layer "In2.Cu")
		(net "I2C_DPB_SDA_OUT")
	)
	(segment
		(start 101.031548 -142.458694)
		(end 101.031548 -143.050768)
		(width 0.127)
		(layer "In2.Cu")
		(net "I2C_DPB_SDA_OUT")
	)
	(segment
		(start 101.031548 -143.050768)
		(end 101.096318 -143.115538)
		(width 0.127)
		(layer "In2.Cu")
		(net "I2C_DPB_SDA_OUT")
	)
	(segment
		(start 100.591366 -165.05047)
		(end 100.591366 -166.395654)
		(width 0.127)
		(layer "In2.Cu")
		(net "I2C_DPB_SDA_OUT")
	)
	(segment
		(start 101.091746 -172.244512)
		(end 100.690426 -172.645832)
		(width 0.127)
		(layer "In2.Cu")
		(net "I2C_DPB_SDA_OUT")
	)
	(segment
		(start 100.591366 -166.395654)
		(end 101.091746 -166.896034)
		(width 0.127)
		(layer "In2.Cu")
		(net "I2C_DPB_SDA_OUT")
	)
	(segment
		(start 101.096318 -164.545518)
		(end 100.591366 -165.05047)
		(width 0.127)
		(layer "In2.Cu")
		(net "I2C_DPB_SDA_OUT")
	)
	(segment
		(start 101.096318 -143.115538)
		(end 101.096318 -164.545518)
		(width 0.127)
		(layer "In2.Cu")
		(net "I2C_DPB_SDA_OUT")
	)
	(segment
		(start 101.091746 -166.896034)
		(end 101.091746 -172.244512)
		(width 0.127)
		(layer "In2.Cu")
		(net "I2C_DPB_SDA_OUT")
	)
	(segment
		(start 48.6029 -162.288982)
		(end 47.545244 -161.231326)
		(width 0.127)
		(layer "In5.Cu")
		(net "I2C_DPB_SDA_OUT")
	)
	(segment
		(start 93.173042 -143.712438)
		(end 89.698322 -143.712438)
		(width 0.127)
		(layer "In5.Cu")
		(net "I2C_DPB_SDA_OUT")
	)
	(segment
		(start 99.981766 -171.6024)
		(end 96.487742 -171.6024)
		(width 0.127)
		(layer "In5.Cu")
		(net "I2C_DPB_SDA_OUT")
	)
	(segment
		(start 99.957128 -143.1163)
		(end 98.051366 -143.1163)
		(width 0.127)
		(layer "In5.Cu")
		(net "I2C_DPB_SDA_OUT")
	)
	(segment
		(start 59.9567 -166.9288)
		(end 56.468772 -166.9288)
		(width 0.127)
		(layer "In5.Cu")
		(net "I2C_DPB_SDA_OUT")
	)
	(segment
		(start 100.2792 -171.899834)
		(end 99.981766 -171.6024)
		(width 0.127)
		(layer "In5.Cu")
		(net "I2C_DPB_SDA_OUT")
	)
	(segment
		(start 95.416624 -144.107662)
		(end 94.425262 -143.1163)
		(width 0.127)
		(layer "In5.Cu")
		(net "I2C_DPB_SDA_OUT")
	)
	(segment
		(start 51.31562 -164.5031)
		(end 49.97704 -163.16452)
		(width 0.127)
		(layer "In5.Cu")
		(net "I2C_DPB_SDA_OUT")
	)
	(segment
		(start 54.280308 -164.985446)
		(end 52.986686 -164.985446)
		(width 0.127)
		(layer "In5.Cu")
		(net "I2C_DPB_SDA_OUT")
	)
	(segment
		(start 83.300062 -144.86636)
		(end 82.67065 -145.495772)
		(width 0.127)
		(layer "In5.Cu")
		(net "I2C_DPB_SDA_OUT")
	)
	(segment
		(start 85.61324 -144.86636)
		(end 83.300062 -144.86636)
		(width 0.127)
		(layer "In5.Cu")
		(net "I2C_DPB_SDA_OUT")
	)
	(segment
		(start 48.6029 -162.660838)
		(end 48.6029 -162.288982)
		(width 0.127)
		(layer "In5.Cu")
		(net "I2C_DPB_SDA_OUT")
	)
	(segment
		(start 49.97704 -163.16452)
		(end 49.106582 -163.16452)
		(width 0.127)
		(layer "In5.Cu")
		(net "I2C_DPB_SDA_OUT")
	)
	(segment
		(start 87.333582 -143.146018)
		(end 85.61324 -144.86636)
		(width 0.127)
		(layer "In5.Cu")
		(net "I2C_DPB_SDA_OUT")
	)
	(segment
		(start 60.593478 -167.565578)
		(end 59.9567 -166.9288)
		(width 0.127)
		(layer "In5.Cu")
		(net "I2C_DPB_SDA_OUT")
	)
	(segment
		(start 96.487742 -171.6024)
		(end 96.411288 -171.525946)
		(width 0.127)
		(layer "In5.Cu")
		(net "I2C_DPB_SDA_OUT")
	)
	(segment
		(start 87.061802 -167.841676)
		(end 83.081876 -167.841676)
		(width 0.127)
		(layer "In5.Cu")
		(net "I2C_DPB_SDA_OUT")
	)
	(segment
		(start 94.425262 -143.1163)
		(end 93.76918 -143.1163)
		(width 0.127)
		(layer "In5.Cu")
		(net "I2C_DPB_SDA_OUT")
	)
	(segment
		(start 46.018704 -160.032954)
		(end 46.018704 -159.4104)
		(width 0.127)
		(layer "In5.Cu")
		(net "I2C_DPB_SDA_OUT")
	)
	(segment
		(start 90.746072 -171.525946)
		(end 87.061802 -167.841676)
		(width 0.127)
		(layer "In5.Cu")
		(net "I2C_DPB_SDA_OUT")
	)
	(segment
		(start 89.698322 -143.712438)
		(end 89.127584 -143.1417)
		(width 0.127)
		(layer "In5.Cu")
		(net "I2C_DPB_SDA_OUT")
	)
	(segment
		(start 97.060004 -144.107662)
		(end 95.416624 -144.107662)
		(width 0.127)
		(layer "In5.Cu")
		(net "I2C_DPB_SDA_OUT")
	)
	(segment
		(start 89.127584 -143.1417)
		(end 88.273382 -143.1417)
		(width 0.127)
		(layer "In5.Cu")
		(net "I2C_DPB_SDA_OUT")
	)
	(segment
		(start 96.411288 -171.525946)
		(end 90.746072 -171.525946)
		(width 0.127)
		(layer "In5.Cu")
		(net "I2C_DPB_SDA_OUT")
	)
	(segment
		(start 101.16947 -141.903958)
		(end 99.957128 -143.1163)
		(width 0.127)
		(layer "In5.Cu")
		(net "I2C_DPB_SDA_OUT")
	)
	(segment
		(start 47.545244 -161.231326)
		(end 47.217076 -161.231326)
		(width 0.127)
		(layer "In5.Cu")
		(net "I2C_DPB_SDA_OUT")
	)
	(segment
		(start 47.217076 -161.231326)
		(end 46.018704 -160.032954)
		(width 0.127)
		(layer "In5.Cu")
		(net "I2C_DPB_SDA_OUT")
	)
	(segment
		(start 98.051366 -143.1163)
		(end 97.060004 -144.107662)
		(width 0.127)
		(layer "In5.Cu")
		(net "I2C_DPB_SDA_OUT")
	)
	(segment
		(start 101.586284 -141.903958)
		(end 101.16947 -141.903958)
		(width 0.127)
		(layer "In5.Cu")
		(net "I2C_DPB_SDA_OUT")
	)
	(segment
		(start 100.690426 -172.645832)
		(end 100.2792 -172.234606)
		(width 0.127)
		(layer "In5.Cu")
		(net "I2C_DPB_SDA_OUT")
	)
	(segment
		(start 52.50434 -164.5031)
		(end 51.31562 -164.5031)
		(width 0.127)
		(layer "In5.Cu")
		(net "I2C_DPB_SDA_OUT")
	)
	(segment
		(start 49.106582 -163.16452)
		(end 48.6029 -162.660838)
		(width 0.127)
		(layer "In5.Cu")
		(net "I2C_DPB_SDA_OUT")
	)
	(segment
		(start 56.468772 -166.9288)
		(end 55.668672 -166.1287)
		(width 0.127)
		(layer "In5.Cu")
		(net "I2C_DPB_SDA_OUT")
	)
	(segment
		(start 83.081876 -167.841676)
		(end 82.805778 -167.565578)
		(width 0.127)
		(layer "In5.Cu")
		(net "I2C_DPB_SDA_OUT")
	)
	(segment
		(start 52.986686 -164.985446)
		(end 52.50434 -164.5031)
		(width 0.127)
		(layer "In5.Cu")
		(net "I2C_DPB_SDA_OUT")
	)
	(segment
		(start 88.273382 -143.1417)
		(end 88.269064 -143.146018)
		(width 0.127)
		(layer "In5.Cu")
		(net "I2C_DPB_SDA_OUT")
	)
	(segment
		(start 100.2792 -172.234606)
		(end 100.2792 -171.899834)
		(width 0.127)
		(layer "In5.Cu")
		(net "I2C_DPB_SDA_OUT")
	)
	(segment
		(start 55.423562 -166.1287)
		(end 54.280308 -164.985446)
		(width 0.127)
		(layer "In5.Cu")
		(net "I2C_DPB_SDA_OUT")
	)
	(segment
		(start 82.805778 -167.565578)
		(end 60.593478 -167.565578)
		(width 0.127)
		(layer "In5.Cu")
		(net "I2C_DPB_SDA_OUT")
	)
	(segment
		(start 55.668672 -166.1287)
		(end 55.423562 -166.1287)
		(width 0.127)
		(layer "In5.Cu")
		(net "I2C_DPB_SDA_OUT")
	)
	(segment
		(start 88.269064 -143.146018)
		(end 87.333582 -143.146018)
		(width 0.127)
		(layer "In5.Cu")
		(net "I2C_DPB_SDA_OUT")
	)
	(segment
		(start 93.76918 -143.1163)
		(end 93.173042 -143.712438)
		(width 0.127)
		(layer "In5.Cu")
		(net "I2C_DPB_SDA_OUT")
	)
	(segment
		(start 109.47146 -44.171362)
		(end 110.700058 -45.39996)
		(width 0.127)
		(layer "F.Cu")
		(net "I2C_DPB_SDA")
	)
	(segment
		(start 104.555544 -44.985432)
		(end 104.555544 -28.23845)
		(width 0.127)
		(layer "F.Cu")
		(net "I2C_DPB_SDA")
	)
	(segment
		(start 109.47146 -29.045916)
		(end 109.47146 -44.171362)
		(width 0.127)
		(layer "F.Cu")
		(net "I2C_DPB_SDA")
	)
	(segment
		(start 102.855522 -132.93852)
		(end 102.855522 -126.67996)
		(width 0.127)
		(layer "F.Cu")
		(net "I2C_DPB_SDA")
	)
	(segment
		(start 102.279958 -123.201938)
		(end 102.279958 -47.261018)
		(width 0.127)
		(layer "F.Cu")
		(net "I2C_DPB_SDA")
	)
	(segment
		(start 104.555544 -28.23845)
		(end 105.463594 -27.3304)
		(width 0.127)
		(layer "F.Cu")
		(net "I2C_DPB_SDA")
	)
	(segment
		(start 75.941428 -146.839432)
		(end 75.139296 -146.839432)
		(width 0.127)
		(layer "F.Cu")
		(net "I2C_DPB_SDA")
	)
	(segment
		(start 101.119686 -124.944124)
		(end 101.119686 -124.36221)
		(width 0.127)
		(layer "F.Cu")
		(net "I2C_DPB_SDA")
	)
	(segment
		(start 102.279958 -47.261018)
		(end 104.555544 -44.985432)
		(width 0.127)
		(layer "F.Cu")
		(net "I2C_DPB_SDA")
	)
	(segment
		(start 107.755944 -27.3304)
		(end 109.47146 -29.045916)
		(width 0.127)
		(layer "F.Cu")
		(net "I2C_DPB_SDA")
	)
	(segment
		(start 101.119686 -124.36221)
		(end 102.279958 -123.201938)
		(width 0.127)
		(layer "F.Cu")
		(net "I2C_DPB_SDA")
	)
	(segment
		(start 102.855522 -126.67996)
		(end 101.119686 -124.944124)
		(width 0.127)
		(layer "F.Cu")
		(net "I2C_DPB_SDA")
	)
	(segment
		(start 101.62032 -134.173722)
		(end 102.855522 -132.93852)
		(width 0.127)
		(layer "F.Cu")
		(net "I2C_DPB_SDA")
	)
	(segment
		(start 105.463594 -27.3304)
		(end 107.755944 -27.3304)
		(width 0.127)
		(layer "F.Cu")
		(net "I2C_DPB_SDA")
	)
	(via
		(at 76.619862 -145.402808)
		(size 0.6096)
		(drill 0.3048)
		(layers "F.Cu" "B.Cu")
		(net "I2C_DPB_SDA")
	)
	(via
		(at 101.62032 -134.173722)
		(size 0.508)
		(drill 0.254)
		(layers "F.Cu" "B.Cu")
		(net "I2C_DPB_SDA")
	)
	(via
		(at 85.7377 -135.793226)
		(size 0.508)
		(drill 0.254)
		(layers "F.Cu" "B.Cu")
		(net "I2C_DPB_SDA")
	)
	(via
		(at 75.139296 -146.839432)
		(size 0.508)
		(drill 0.254)
		(layers "F.Cu" "B.Cu")
		(net "I2C_DPB_SDA")
	)
	(segment
		(start 75.183238 -146.839432)
		(end 76.619862 -145.402808)
		(width 0.127)
		(layer "B.Cu")
		(net "I2C_DPB_SDA")
	)
	(segment
		(start 85.7377 -136.114282)
		(end 85.7377 -135.793226)
		(width 0.127)
		(layer "B.Cu")
		(net "I2C_DPB_SDA")
	)
	(segment
		(start 83.830668 -138.021314)
		(end 85.7377 -136.114282)
		(width 0.127)
		(layer "B.Cu")
		(net "I2C_DPB_SDA")
	)
	(segment
		(start 78.2574 -141.150848)
		(end 81.386934 -138.021314)
		(width 0.127)
		(layer "B.Cu")
		(net "I2C_DPB_SDA")
	)
	(segment
		(start 81.386934 -138.021314)
		(end 83.830668 -138.021314)
		(width 0.127)
		(layer "B.Cu")
		(net "I2C_DPB_SDA")
	)
	(segment
		(start 75.139296 -146.839432)
		(end 75.183238 -146.839432)
		(width 0.127)
		(layer "B.Cu")
		(net "I2C_DPB_SDA")
	)
	(segment
		(start 76.619862 -145.402808)
		(end 78.2574 -143.76527)
		(width 0.127)
		(layer "B.Cu")
		(net "I2C_DPB_SDA")
	)
	(segment
		(start 78.2574 -143.76527)
		(end 78.2574 -141.150848)
		(width 0.127)
		(layer "B.Cu")
		(net "I2C_DPB_SDA")
	)
	(segment
		(start 85.907626 -135.6233)
		(end 100.170742 -135.6233)
		(width 0.127)
		(layer "In5.Cu")
		(net "I2C_DPB_SDA")
	)
	(segment
		(start 85.7377 -135.793226)
		(end 85.907626 -135.6233)
		(width 0.127)
		(layer "In5.Cu")
		(net "I2C_DPB_SDA")
	)
	(segment
		(start 100.170742 -135.6233)
		(end 101.62032 -134.173722)
		(width 0.127)
		(layer "In5.Cu")
		(net "I2C_DPB_SDA")
	)
	(segment
		(start 84.139278 -145.965418)
		(end 85.349334 -145.965418)
		(width 0.127)
		(layer "F.Cu")
		(net "I2C_DPB_SCL_OUT")
	)
	(segment
		(start 46.693836 -159.838136)
		(end 46.7487 -159.893)
		(width 0.127)
		(layer "F.Cu")
		(net "I2C_DPB_SCL_OUT")
	)
	(segment
		(start 83.77936 -145.46834)
		(end 83.77936 -145.6055)
		(width 0.127)
		(layer "F.Cu")
		(net "I2C_DPB_SCL_OUT")
	)
	(segment
		(start 46.693836 -158.953454)
		(end 46.693836 -159.838136)
		(width 0.127)
		(layer "F.Cu")
		(net "I2C_DPB_SCL_OUT")
	)
	(segment
		(start 46.7487 -159.893)
		(end 47.060104 -160.204404)
		(width 0.127)
		(layer "F.Cu")
		(net "I2C_DPB_SCL_OUT")
	)
	(segment
		(start 47.060104 -160.204404)
		(end 47.060104 -160.735772)
		(width 0.127)
		(layer "F.Cu")
		(net "I2C_DPB_SCL_OUT")
	)
	(segment
		(start 83.77936 -145.6055)
		(end 84.139278 -145.965418)
		(width 0.127)
		(layer "F.Cu")
		(net "I2C_DPB_SCL_OUT")
	)
	(segment
		(start 47.01159 -158.6357)
		(end 46.693836 -158.953454)
		(width 0.127)
		(layer "F.Cu")
		(net "I2C_DPB_SCL_OUT")
	)
	(via
		(at 101.599746 -171.049188)
		(size 0.508)
		(drill 0.254)
		(layers "F.Cu" "B.Cu")
		(net "I2C_DPB_SCL_OUT")
	)
	(via
		(at 101.530404 -142.831058)
		(size 0.508)
		(drill 0.254)
		(layers "F.Cu" "B.Cu")
		(net "I2C_DPB_SCL_OUT")
	)
	(via
		(at 83.77936 -145.46834)
		(size 0.508)
		(drill 0.254)
		(layers "F.Cu" "B.Cu")
		(net "I2C_DPB_SCL_OUT")
	)
	(via
		(at 46.7487 -159.893)
		(size 0.508)
		(drill 0.254)
		(layers "F.Cu" "B.Cu")
		(net "I2C_DPB_SCL_OUT")
	)
	(segment
		(start 101.599746 -166.685468)
		(end 101.599746 -171.049188)
		(width 0.127)
		(layer "In2.Cu")
		(net "I2C_DPB_SCL_OUT")
	)
	(segment
		(start 101.530404 -142.831058)
		(end 101.604318 -142.904972)
		(width 0.127)
		(layer "In2.Cu")
		(net "I2C_DPB_SCL_OUT")
	)
	(segment
		(start 101.099366 -165.261036)
		(end 101.099366 -166.185088)
		(width 0.127)
		(layer "In2.Cu")
		(net "I2C_DPB_SCL_OUT")
	)
	(segment
		(start 101.604318 -164.756084)
		(end 101.099366 -165.261036)
		(width 0.127)
		(layer "In2.Cu")
		(net "I2C_DPB_SCL_OUT")
	)
	(segment
		(start 101.099366 -166.185088)
		(end 101.599746 -166.685468)
		(width 0.127)
		(layer "In2.Cu")
		(net "I2C_DPB_SCL_OUT")
	)
	(segment
		(start 101.604318 -142.904972)
		(end 101.604318 -164.756084)
		(width 0.127)
		(layer "In2.Cu")
		(net "I2C_DPB_SCL_OUT")
	)
	(segment
		(start 87.147908 -144.75968)
		(end 86.784942 -144.75968)
		(width 0.127)
		(layer "In5.Cu")
		(net "I2C_DPB_SCL_OUT")
	)
	(segment
		(start 50.967386 -163.2712)
		(end 49.268126 -161.57194)
		(width 0.127)
		(layer "In5.Cu")
		(net "I2C_DPB_SCL_OUT")
	)
	(segment
		(start 84.983574 -167.2082)
		(end 83.166966 -167.2082)
		(width 0.127)
		(layer "In5.Cu")
		(net "I2C_DPB_SCL_OUT")
	)
	(segment
		(start 101.599746 -171.049188)
		(end 100.781358 -170.2308)
		(width 0.127)
		(layer "In5.Cu")
		(net "I2C_DPB_SCL_OUT")
	)
	(segment
		(start 53.790596 -163.2712)
		(end 50.967386 -163.2712)
		(width 0.127)
		(layer "In5.Cu")
		(net "I2C_DPB_SCL_OUT")
	)
	(segment
		(start 46.7487 -160.044384)
		(end 46.7487 -159.893)
		(width 0.127)
		(layer "In5.Cu")
		(net "I2C_DPB_SCL_OUT")
	)
	(segment
		(start 55.050182 -164.9857)
		(end 54.294024 -164.229542)
		(width 0.127)
		(layer "In5.Cu")
		(net "I2C_DPB_SCL_OUT")
	)
	(segment
		(start 86.834472 -166.710106)
		(end 85.481668 -166.710106)
		(width 0.127)
		(layer "In5.Cu")
		(net "I2C_DPB_SCL_OUT")
	)
	(segment
		(start 55.617618 -164.9857)
		(end 55.050182 -164.9857)
		(width 0.127)
		(layer "In5.Cu")
		(net "I2C_DPB_SCL_OUT")
	)
	(segment
		(start 83.87334 -145.37436)
		(end 83.77936 -145.46834)
		(width 0.127)
		(layer "In5.Cu")
		(net "I2C_DPB_SCL_OUT")
	)
	(segment
		(start 49.268126 -161.57194)
		(end 48.663098 -161.57194)
		(width 0.127)
		(layer "In5.Cu")
		(net "I2C_DPB_SCL_OUT")
	)
	(segment
		(start 91.898978 -144.29486)
		(end 87.612728 -144.29486)
		(width 0.127)
		(layer "In5.Cu")
		(net "I2C_DPB_SCL_OUT")
	)
	(segment
		(start 85.481668 -166.710106)
		(end 84.983574 -167.2082)
		(width 0.127)
		(layer "In5.Cu")
		(net "I2C_DPB_SCL_OUT")
	)
	(segment
		(start 48.663098 -161.57194)
		(end 47.708058 -160.6169)
		(width 0.127)
		(layer "In5.Cu")
		(net "I2C_DPB_SCL_OUT")
	)
	(segment
		(start 98.234246 -143.651986)
		(end 97.27057 -144.615662)
		(width 0.127)
		(layer "In5.Cu")
		(net "I2C_DPB_SCL_OUT")
	)
	(segment
		(start 63.116968 -166.24935)
		(end 56.881268 -166.24935)
		(width 0.127)
		(layer "In5.Cu")
		(net "I2C_DPB_SCL_OUT")
	)
	(segment
		(start 47.708058 -160.6169)
		(end 47.321216 -160.6169)
		(width 0.127)
		(layer "In5.Cu")
		(net "I2C_DPB_SCL_OUT")
	)
	(segment
		(start 100.709476 -143.651986)
		(end 98.234246 -143.651986)
		(width 0.127)
		(layer "In5.Cu")
		(net "I2C_DPB_SCL_OUT")
	)
	(segment
		(start 97.27057 -144.615662)
		(end 92.21978 -144.615662)
		(width 0.127)
		(layer "In5.Cu")
		(net "I2C_DPB_SCL_OUT")
	)
	(segment
		(start 86.170262 -145.37436)
		(end 83.87334 -145.37436)
		(width 0.127)
		(layer "In5.Cu")
		(net "I2C_DPB_SCL_OUT")
	)
	(segment
		(start 54.294024 -164.229542)
		(end 54.294024 -163.774628)
		(width 0.127)
		(layer "In5.Cu")
		(net "I2C_DPB_SCL_OUT")
	)
	(segment
		(start 101.530404 -142.831058)
		(end 100.709476 -143.651986)
		(width 0.127)
		(layer "In5.Cu")
		(net "I2C_DPB_SCL_OUT")
	)
	(segment
		(start 63.925196 -167.057578)
		(end 63.116968 -166.24935)
		(width 0.127)
		(layer "In5.Cu")
		(net "I2C_DPB_SCL_OUT")
	)
	(segment
		(start 83.166966 -167.2082)
		(end 83.016344 -167.057578)
		(width 0.127)
		(layer "In5.Cu")
		(net "I2C_DPB_SCL_OUT")
	)
	(segment
		(start 100.781358 -170.2308)
		(end 94.3864 -170.2308)
		(width 0.127)
		(layer "In5.Cu")
		(net "I2C_DPB_SCL_OUT")
	)
	(segment
		(start 56.881268 -166.24935)
		(end 55.617618 -164.9857)
		(width 0.127)
		(layer "In5.Cu")
		(net "I2C_DPB_SCL_OUT")
	)
	(segment
		(start 87.612728 -144.29486)
		(end 87.147908 -144.75968)
		(width 0.127)
		(layer "In5.Cu")
		(net "I2C_DPB_SCL_OUT")
	)
	(segment
		(start 54.294024 -163.774628)
		(end 53.790596 -163.2712)
		(width 0.127)
		(layer "In5.Cu")
		(net "I2C_DPB_SCL_OUT")
	)
	(segment
		(start 94.3864 -170.2308)
		(end 92.583 -168.4274)
		(width 0.127)
		(layer "In5.Cu")
		(net "I2C_DPB_SCL_OUT")
	)
	(segment
		(start 88.551766 -168.4274)
		(end 86.834472 -166.710106)
		(width 0.127)
		(layer "In5.Cu")
		(net "I2C_DPB_SCL_OUT")
	)
	(segment
		(start 83.016344 -167.057578)
		(end 63.925196 -167.057578)
		(width 0.127)
		(layer "In5.Cu")
		(net "I2C_DPB_SCL_OUT")
	)
	(segment
		(start 92.21978 -144.615662)
		(end 91.898978 -144.29486)
		(width 0.127)
		(layer "In5.Cu")
		(net "I2C_DPB_SCL_OUT")
	)
	(segment
		(start 47.321216 -160.6169)
		(end 46.7487 -160.044384)
		(width 0.127)
		(layer "In5.Cu")
		(net "I2C_DPB_SCL_OUT")
	)
	(segment
		(start 86.784942 -144.75968)
		(end 86.170262 -145.37436)
		(width 0.127)
		(layer "In5.Cu")
		(net "I2C_DPB_SCL_OUT")
	)
	(segment
		(start 92.583 -168.4274)
		(end 88.551766 -168.4274)
		(width 0.127)
		(layer "In5.Cu")
		(net "I2C_DPB_SCL_OUT")
	)
	(segment
		(start 100.611686 -125.15469)
		(end 100.611686 -124.151644)
		(width 0.127)
		(layer "F.Cu")
		(net "I2C_DPB_SCL")
	)
	(segment
		(start 105.253028 -26.8224)
		(end 107.96651 -26.8224)
		(width 0.127)
		(layer "F.Cu")
		(net "I2C_DPB_SCL")
	)
	(segment
		(start 74.1172 -146.1135)
		(end 74.5109 -145.7198)
		(width 0.127)
		(layer "F.Cu")
		(net "I2C_DPB_SCL")
	)
	(segment
		(start 102.347522 -126.890526)
		(end 100.611686 -125.15469)
		(width 0.127)
		(layer "F.Cu")
		(net "I2C_DPB_SCL")
	)
	(segment
		(start 100.611686 -124.151644)
		(end 101.771958 -122.991372)
		(width 0.127)
		(layer "F.Cu")
		(net "I2C_DPB_SCL")
	)
	(segment
		(start 102.347522 -132.34416)
		(end 102.347522 -126.890526)
		(width 0.127)
		(layer "F.Cu")
		(net "I2C_DPB_SCL")
	)
	(segment
		(start 101.62032 -133.071362)
		(end 102.347522 -132.34416)
		(width 0.127)
		(layer "F.Cu")
		(net "I2C_DPB_SCL")
	)
	(segment
		(start 104.047544 -28.027884)
		(end 105.253028 -26.8224)
		(width 0.127)
		(layer "F.Cu")
		(net "I2C_DPB_SCL")
	)
	(segment
		(start 109.97946 -43.279568)
		(end 110.700058 -44.000166)
		(width 0.127)
		(layer "F.Cu")
		(net "I2C_DPB_SCL")
	)
	(segment
		(start 101.771958 -122.991372)
		(end 101.771958 -47.050452)
		(width 0.127)
		(layer "F.Cu")
		(net "I2C_DPB_SCL")
	)
	(segment
		(start 74.1172 -146.483832)
		(end 74.1172 -146.1135)
		(width 0.127)
		(layer "F.Cu")
		(net "I2C_DPB_SCL")
	)
	(segment
		(start 107.96651 -26.8224)
		(end 109.97946 -28.83535)
		(width 0.127)
		(layer "F.Cu")
		(net "I2C_DPB_SCL")
	)
	(segment
		(start 101.771958 -47.050452)
		(end 104.047544 -44.774866)
		(width 0.127)
		(layer "F.Cu")
		(net "I2C_DPB_SCL")
	)
	(segment
		(start 109.97946 -28.83535)
		(end 109.97946 -43.279568)
		(width 0.127)
		(layer "F.Cu")
		(net "I2C_DPB_SCL")
	)
	(segment
		(start 104.047544 -44.774866)
		(end 104.047544 -28.027884)
		(width 0.127)
		(layer "F.Cu")
		(net "I2C_DPB_SCL")
	)
	(via
		(at 101.62032 -133.071362)
		(size 0.508)
		(drill 0.254)
		(layers "F.Cu" "B.Cu")
		(net "I2C_DPB_SCL")
	)
	(via
		(at 74.1172 -146.483832)
		(size 0.508)
		(drill 0.254)
		(layers "F.Cu" "B.Cu")
		(net "I2C_DPB_SCL")
	)
	(via
		(at 84.7852 -135.84682)
		(size 0.508)
		(drill 0.254)
		(layers "F.Cu" "B.Cu")
		(net "I2C_DPB_SCL")
	)
	(segment
		(start 84.7852 -136.348216)
		(end 84.7852 -135.84682)
		(width 0.127)
		(layer "B.Cu")
		(net "I2C_DPB_SCL")
	)
	(segment
		(start 81.19872 -137.490962)
		(end 83.642454 -137.490962)
		(width 0.127)
		(layer "B.Cu")
		(net "I2C_DPB_SCL")
	)
	(segment
		(start 77.7494 -140.940282)
		(end 81.19872 -137.490962)
		(width 0.127)
		(layer "B.Cu")
		(net "I2C_DPB_SCL")
	)
	(segment
		(start 77.7494 -142.851632)
		(end 77.7494 -140.940282)
		(width 0.127)
		(layer "B.Cu")
		(net "I2C_DPB_SCL")
	)
	(segment
		(start 83.642454 -137.490962)
		(end 84.7852 -136.348216)
		(width 0.127)
		(layer "B.Cu")
		(net "I2C_DPB_SCL")
	)
	(segment
		(start 74.1172 -146.483832)
		(end 77.7494 -142.851632)
		(width 0.127)
		(layer "B.Cu")
		(net "I2C_DPB_SCL")
	)
	(segment
		(start 99.576382 -135.1153)
		(end 85.51672 -135.1153)
		(width 0.127)
		(layer "In5.Cu")
		(net "I2C_DPB_SCL")
	)
	(segment
		(start 101.62032 -133.071362)
		(end 99.576382 -135.1153)
		(width 0.127)
		(layer "In5.Cu")
		(net "I2C_DPB_SCL")
	)
	(segment
		(start 85.51672 -135.1153)
		(end 84.7852 -135.84682)
		(width 0.127)
		(layer "In5.Cu")
		(net "I2C_DPB_SCL")
	)
	(segment
		(start 136.938766 -23.332948)
		(end 121.241566 -23.332948)
		(width 0.127)
		(layer "F.Cu")
		(net "I2C_DPB_MISC_SDA")
	)
	(segment
		(start 97.855786 -121.552462)
		(end 97.855786 -125.99162)
		(width 0.127)
		(layer "F.Cu")
		(net "I2C_DPB_MISC_SDA")
	)
	(segment
		(start 98.6536 -120.3706)
		(end 98.6536 -120.754648)
		(width 0.127)
		(layer "F.Cu")
		(net "I2C_DPB_MISC_SDA")
	)
	(segment
		(start 100.1141 -171.621958)
		(end 99.535742 -171.621958)
		(width 0.127)
		(layer "F.Cu")
		(net "I2C_DPB_MISC_SDA")
	)
	(segment
		(start 96.258634 -117.975634)
		(end 98.6536 -120.3706)
		(width 0.127)
		(layer "F.Cu")
		(net "I2C_DPB_MISC_SDA")
	)
	(segment
		(start 100.486718 -143.534384)
		(end 101.349048 -144.396714)
		(width 0.127)
		(layer "F.Cu")
		(net "I2C_DPB_MISC_SDA")
	)
	(segment
		(start 100.2411 -171.494958)
		(end 100.1141 -171.621958)
		(width 0.127)
		(layer "F.Cu")
		(net "I2C_DPB_MISC_SDA")
	)
	(segment
		(start 97.949512 -93.00972)
		(end 98.723958 -93.784166)
		(width 0.127)
		(layer "F.Cu")
		(net "I2C_DPB_MISC_SDA")
	)
	(segment
		(start 139.499848 -45.39996)
		(end 140.579348 -44.32046)
		(width 0.127)
		(layer "F.Cu")
		(net "I2C_DPB_MISC_SDA")
	)
	(segment
		(start 98.933762 -26.308812)
		(end 98.933762 -41.982644)
		(width 0.127)
		(layer "F.Cu")
		(net "I2C_DPB_MISC_SDA")
	)
	(segment
		(start 121.241566 -23.332948)
		(end 120.72874 -22.820122)
		(width 0.127)
		(layer "F.Cu")
		(net "I2C_DPB_MISC_SDA")
	)
	(segment
		(start 98.6536 -120.754648)
		(end 97.855786 -121.552462)
		(width 0.127)
		(layer "F.Cu")
		(net "I2C_DPB_MISC_SDA")
	)
	(segment
		(start 99.588828 -135.031988)
		(end 100.486718 -135.929878)
		(width 0.127)
		(layer "F.Cu")
		(net "I2C_DPB_MISC_SDA")
	)
	(segment
		(start 99.535742 -171.621958)
		(end 98.9711 -172.1866)
		(width 0.127)
		(layer "F.Cu")
		(net "I2C_DPB_MISC_SDA")
	)
	(segment
		(start 97.949512 -42.966894)
		(end 97.949512 -93.00972)
		(width 0.127)
		(layer "F.Cu")
		(net "I2C_DPB_MISC_SDA")
	)
	(segment
		(start 100.486718 -135.929878)
		(end 100.486718 -143.534384)
		(width 0.127)
		(layer "F.Cu")
		(net "I2C_DPB_MISC_SDA")
	)
	(segment
		(start 120.72874 -22.820122)
		(end 116.85651 -18.947892)
		(width 0.127)
		(layer "F.Cu")
		(net "I2C_DPB_MISC_SDA")
	)
	(segment
		(start 140.579348 -26.97353)
		(end 136.938766 -23.332948)
		(width 0.127)
		(layer "F.Cu")
		(net "I2C_DPB_MISC_SDA")
	)
	(segment
		(start 100.2411 -165.222936)
		(end 100.2411 -171.494958)
		(width 0.127)
		(layer "F.Cu")
		(net "I2C_DPB_MISC_SDA")
	)
	(segment
		(start 99.150678 -127.286512)
		(end 99.150678 -127.791718)
		(width 0.127)
		(layer "F.Cu")
		(net "I2C_DPB_MISC_SDA")
	)
	(segment
		(start 99.588828 -128.229868)
		(end 99.588828 -135.031988)
		(width 0.127)
		(layer "F.Cu")
		(net "I2C_DPB_MISC_SDA")
	)
	(segment
		(start 106.650536 -19.815302)
		(end 105.427272 -19.815302)
		(width 0.127)
		(layer "F.Cu")
		(net "I2C_DPB_MISC_SDA")
	)
	(segment
		(start 98.723958 -113.714276)
		(end 96.258634 -116.1796)
		(width 0.127)
		(layer "F.Cu")
		(net "I2C_DPB_MISC_SDA")
	)
	(segment
		(start 101.349048 -164.114988)
		(end 100.2411 -165.222936)
		(width 0.127)
		(layer "F.Cu")
		(net "I2C_DPB_MISC_SDA")
	)
	(segment
		(start 107.517946 -18.947892)
		(end 106.650536 -19.815302)
		(width 0.127)
		(layer "F.Cu")
		(net "I2C_DPB_MISC_SDA")
	)
	(segment
		(start 116.85651 -18.947892)
		(end 107.517946 -18.947892)
		(width 0.127)
		(layer "F.Cu")
		(net "I2C_DPB_MISC_SDA")
	)
	(segment
		(start 96.258634 -116.1796)
		(end 96.258634 -117.975634)
		(width 0.127)
		(layer "F.Cu")
		(net "I2C_DPB_MISC_SDA")
	)
	(segment
		(start 98.933762 -41.982644)
		(end 97.949512 -42.966894)
		(width 0.127)
		(layer "F.Cu")
		(net "I2C_DPB_MISC_SDA")
	)
	(segment
		(start 101.349048 -144.396714)
		(end 101.349048 -164.114988)
		(width 0.127)
		(layer "F.Cu")
		(net "I2C_DPB_MISC_SDA")
	)
	(segment
		(start 105.427272 -19.815302)
		(end 98.933762 -26.308812)
		(width 0.127)
		(layer "F.Cu")
		(net "I2C_DPB_MISC_SDA")
	)
	(segment
		(start 99.150678 -127.791718)
		(end 99.588828 -128.229868)
		(width 0.127)
		(layer "F.Cu")
		(net "I2C_DPB_MISC_SDA")
	)
	(segment
		(start 97.855786 -125.99162)
		(end 99.150678 -127.286512)
		(width 0.127)
		(layer "F.Cu")
		(net "I2C_DPB_MISC_SDA")
	)
	(segment
		(start 98.723958 -93.784166)
		(end 98.723958 -113.714276)
		(width 0.127)
		(layer "F.Cu")
		(net "I2C_DPB_MISC_SDA")
	)
	(segment
		(start 140.579348 -44.32046)
		(end 140.579348 -26.97353)
		(width 0.127)
		(layer "F.Cu")
		(net "I2C_DPB_MISC_SDA")
	)
	(via
		(at 120.72874 -22.820122)
		(size 0.6604)
		(drill 0.3302)
		(layers "F.Cu" "B.Cu")
		(net "I2C_DPB_MISC_SDA")
	)
	(segment
		(start 107.728512 -19.455892)
		(end 106.861102 -20.323302)
		(width 0.127)
		(layer "F.Cu")
		(net "I2C_DPB_MISC_SCL")
	)
	(segment
		(start 98.363786 -121.763028)
		(end 98.363786 -125.781054)
		(width 0.127)
		(layer "F.Cu")
		(net "I2C_DPB_MISC_SCL")
	)
	(segment
		(start 99.1616 -120.965214)
		(end 98.363786 -121.763028)
		(width 0.127)
		(layer "F.Cu")
		(net "I2C_DPB_MISC_SCL")
	)
	(segment
		(start 99.59467 -172.961046)
		(end 99.59467 -173.899576)
		(width 0.127)
		(layer "F.Cu")
		(net "I2C_DPB_MISC_SCL")
	)
	(segment
		(start 100.994718 -135.719312)
		(end 100.994718 -143.311118)
		(width 0.127)
		(layer "F.Cu")
		(net "I2C_DPB_MISC_SCL")
	)
	(segment
		(start 116.217954 -19.455892)
		(end 107.728512 -19.455892)
		(width 0.127)
		(layer "F.Cu")
		(net "I2C_DPB_MISC_SCL")
	)
	(segment
		(start 100.994718 -143.311118)
		(end 101.857048 -144.173448)
		(width 0.127)
		(layer "F.Cu")
		(net "I2C_DPB_MISC_SCL")
	)
	(segment
		(start 140.071348 -43.428666)
		(end 140.071348 -27.184096)
		(width 0.127)
		(layer "F.Cu")
		(net "I2C_DPB_MISC_SCL")
	)
	(segment
		(start 99.1616 -120.160034)
		(end 99.1616 -120.965214)
		(width 0.127)
		(layer "F.Cu")
		(net "I2C_DPB_MISC_SCL")
	)
	(segment
		(start 139.499848 -44.000166)
		(end 140.071348 -43.428666)
		(width 0.127)
		(layer "F.Cu")
		(net "I2C_DPB_MISC_SCL")
	)
	(segment
		(start 101.857048 -164.325554)
		(end 100.7491 -165.433502)
		(width 0.127)
		(layer "F.Cu")
		(net "I2C_DPB_MISC_SCL")
	)
	(segment
		(start 101.857048 -144.60728)
		(end 101.857048 -164.325554)
		(width 0.127)
		(layer "F.Cu")
		(net "I2C_DPB_MISC_SCL")
	)
	(segment
		(start 98.457512 -92.799154)
		(end 99.231958 -93.5736)
		(width 0.127)
		(layer "F.Cu")
		(net "I2C_DPB_MISC_SCL")
	)
	(segment
		(start 98.363786 -125.781054)
		(end 99.658932 -127.0762)
		(width 0.127)
		(layer "F.Cu")
		(net "I2C_DPB_MISC_SCL")
	)
	(segment
		(start 105.637838 -20.323302)
		(end 99.441762 -26.519378)
		(width 0.127)
		(layer "F.Cu")
		(net "I2C_DPB_MISC_SCL")
	)
	(segment
		(start 140.071348 -27.184096)
		(end 136.7282 -23.840948)
		(width 0.127)
		(layer "F.Cu")
		(net "I2C_DPB_MISC_SCL")
	)
	(segment
		(start 99.231958 -93.5736)
		(end 99.231958 -113.924842)
		(width 0.127)
		(layer "F.Cu")
		(net "I2C_DPB_MISC_SCL")
	)
	(segment
		(start 99.231958 -113.924842)
		(end 96.766634 -116.390166)
		(width 0.127)
		(layer "F.Cu")
		(net "I2C_DPB_MISC_SCL")
	)
	(segment
		(start 101.857302 -144.607026)
		(end 101.857048 -144.60728)
		(width 0.127)
		(layer "F.Cu")
		(net "I2C_DPB_MISC_SCL")
	)
	(segment
		(start 99.441762 -26.519378)
		(end 99.441762 -42.294302)
		(width 0.127)
		(layer "F.Cu")
		(net "I2C_DPB_MISC_SCL")
	)
	(segment
		(start 119.291862 -22.5298)
		(end 116.217954 -19.455892)
		(width 0.127)
		(layer "F.Cu")
		(net "I2C_DPB_MISC_SCL")
	)
	(segment
		(start 120.60301 -23.840948)
		(end 119.291862 -22.5298)
		(width 0.127)
		(layer "F.Cu")
		(net "I2C_DPB_MISC_SCL")
	)
	(segment
		(start 98.457512 -43.278552)
		(end 98.457512 -92.799154)
		(width 0.127)
		(layer "F.Cu")
		(net "I2C_DPB_MISC_SCL")
	)
	(segment
		(start 106.861102 -20.323302)
		(end 105.637838 -20.323302)
		(width 0.127)
		(layer "F.Cu")
		(net "I2C_DPB_MISC_SCL")
	)
	(segment
		(start 96.766634 -117.765068)
		(end 99.1616 -120.160034)
		(width 0.127)
		(layer "F.Cu")
		(net "I2C_DPB_MISC_SCL")
	)
	(segment
		(start 99.441762 -42.294302)
		(end 98.457512 -43.278552)
		(width 0.127)
		(layer "F.Cu")
		(net "I2C_DPB_MISC_SCL")
	)
	(segment
		(start 100.096828 -128.019302)
		(end 100.096828 -134.821422)
		(width 0.127)
		(layer "F.Cu")
		(net "I2C_DPB_MISC_SCL")
	)
	(segment
		(start 100.7491 -165.433502)
		(end 100.7491 -171.806616)
		(width 0.127)
		(layer "F.Cu")
		(net "I2C_DPB_MISC_SCL")
	)
	(segment
		(start 99.658932 -127.581406)
		(end 100.096828 -128.019302)
		(width 0.127)
		(layer "F.Cu")
		(net "I2C_DPB_MISC_SCL")
	)
	(segment
		(start 99.658932 -127.0762)
		(end 99.658932 -127.581406)
		(width 0.127)
		(layer "F.Cu")
		(net "I2C_DPB_MISC_SCL")
	)
	(segment
		(start 100.096828 -134.821422)
		(end 100.994718 -135.719312)
		(width 0.127)
		(layer "F.Cu")
		(net "I2C_DPB_MISC_SCL")
	)
	(segment
		(start 101.857302 -144.186402)
		(end 101.857302 -144.607026)
		(width 0.127)
		(layer "F.Cu")
		(net "I2C_DPB_MISC_SCL")
	)
	(segment
		(start 96.766634 -116.390166)
		(end 96.766634 -117.765068)
		(width 0.127)
		(layer "F.Cu")
		(net "I2C_DPB_MISC_SCL")
	)
	(segment
		(start 101.857048 -144.173448)
		(end 101.857048 -144.186148)
		(width 0.127)
		(layer "F.Cu")
		(net "I2C_DPB_MISC_SCL")
	)
	(segment
		(start 136.7282 -23.840948)
		(end 120.60301 -23.840948)
		(width 0.127)
		(layer "F.Cu")
		(net "I2C_DPB_MISC_SCL")
	)
	(segment
		(start 100.7491 -171.806616)
		(end 99.59467 -172.961046)
		(width 0.127)
		(layer "F.Cu")
		(net "I2C_DPB_MISC_SCL")
	)
	(segment
		(start 101.857048 -144.186148)
		(end 101.857302 -144.186402)
		(width 0.127)
		(layer "F.Cu")
		(net "I2C_DPB_MISC_SCL")
	)
	(via
		(at 119.291862 -22.5298)
		(size 0.6604)
		(drill 0.3302)
		(layers "F.Cu" "B.Cu")
		(net "I2C_DPB_MISC_SCL")
	)
	(segment
		(start 55.299864 -137.40003)
		(end 55.731664 -136.96823)
		(width 0.127)
		(layer "F.Cu")
		(net "EXP_SPARE_1_R")
	)
	(segment
		(start 57.288176 -135.497824)
		(end 58.205116 -134.580884)
		(width 0.127)
		(layer "F.Cu")
		(net "EXP_SPARE_1_R")
	)
	(segment
		(start 56.3245 -136.96823)
		(end 57.288176 -136.004554)
		(width 0.127)
		(layer "F.Cu")
		(net "EXP_SPARE_1_R")
	)
	(segment
		(start 58.42 -133.1722)
		(end 58.8772 -132.715)
		(width 0.127)
		(layer "F.Cu")
		(net "EXP_SPARE_1_R")
	)
	(segment
		(start 58.42 -133.735318)
		(end 58.42 -133.1722)
		(width 0.127)
		(layer "F.Cu")
		(net "EXP_SPARE_1_R")
	)
	(segment
		(start 59.524392 -131.740656)
		(end 59.524392 -132.067808)
		(width 0.127)
		(layer "F.Cu")
		(net "EXP_SPARE_1_R")
	)
	(segment
		(start 55.731664 -136.96823)
		(end 56.3245 -136.96823)
		(width 0.127)
		(layer "F.Cu")
		(net "EXP_SPARE_1_R")
	)
	(segment
		(start 57.288176 -136.004554)
		(end 57.288176 -135.497824)
		(width 0.127)
		(layer "F.Cu")
		(net "EXP_SPARE_1_R")
	)
	(segment
		(start 58.205116 -134.580884)
		(end 58.205116 -133.950202)
		(width 0.127)
		(layer "F.Cu")
		(net "EXP_SPARE_1_R")
	)
	(segment
		(start 58.205116 -133.950202)
		(end 58.42 -133.735318)
		(width 0.127)
		(layer "F.Cu")
		(net "EXP_SPARE_1_R")
	)
	(segment
		(start 59.524392 -132.067808)
		(end 58.8772 -132.715)
		(width 0.127)
		(layer "F.Cu")
		(net "EXP_SPARE_1_R")
	)
	(via
		(at 58.8772 -132.715)
		(size 0.6604)
		(drill 0.3302)
		(layers "F.Cu" "B.Cu")
		(net "EXP_SPARE_1_R")
	)
	(segment
		(start 59.524392 -125.26391)
		(end 59.524392 -130.851656)
		(width 0.127)
		(layer "F.Cu")
		(net "EXP_SPARE_1")
	)
	(segment
		(start 58.5978 -124.337318)
		(end 59.524392 -125.26391)
		(width 0.127)
		(layer "F.Cu")
		(net "EXP_SPARE_1")
	)
	(segment
		(start 58.5978 -123.611132)
		(end 58.5978 -124.337318)
		(width 0.127)
		(layer "F.Cu")
		(net "EXP_SPARE_1")
	)
	(via
		(at 58.5978 -123.611132)
		(size 0.508)
		(drill 0.254)
		(layers "F.Cu" "B.Cu")
		(net "EXP_SPARE_1")
	)
	(via
		(at 100.726494 -89.260172)
		(size 0.508)
		(drill 0.254)
		(layers "F.Cu" "B.Cu")
		(net "EXP_SPARE_1")
	)
	(segment
		(start 106.0958 -41.481756)
		(end 100.882958 -46.694598)
		(width 0.127)
		(layer "In2.Cu")
		(net "EXP_SPARE_1")
	)
	(segment
		(start 108.89996 -44.200064)
		(end 107.851448 -43.151552)
		(width 0.127)
		(layer "In2.Cu")
		(net "EXP_SPARE_1")
	)
	(segment
		(start 100.882958 -46.694598)
		(end 100.882958 -89.103708)
		(width 0.127)
		(layer "In2.Cu")
		(net "EXP_SPARE_1")
	)
	(segment
		(start 107.33659 -31.528512)
		(end 106.863134 -31.528512)
		(width 0.127)
		(layer "In2.Cu")
		(net "EXP_SPARE_1")
	)
	(segment
		(start 100.882958 -89.103708)
		(end 100.726494 -89.260172)
		(width 0.127)
		(layer "In2.Cu")
		(net "EXP_SPARE_1")
	)
	(segment
		(start 106.863134 -31.528512)
		(end 106.0958 -32.295846)
		(width 0.127)
		(layer "In2.Cu")
		(net "EXP_SPARE_1")
	)
	(segment
		(start 106.0958 -32.295846)
		(end 106.0958 -41.481756)
		(width 0.127)
		(layer "In2.Cu")
		(net "EXP_SPARE_1")
	)
	(segment
		(start 107.851448 -32.04337)
		(end 107.33659 -31.528512)
		(width 0.127)
		(layer "In2.Cu")
		(net "EXP_SPARE_1")
	)
	(segment
		(start 107.851448 -43.151552)
		(end 107.851448 -32.04337)
		(width 0.127)
		(layer "In2.Cu")
		(net "EXP_SPARE_1")
	)
	(segment
		(start 85.979 -124.3584)
		(end 98.191574 -124.3584)
		(width 0.127)
		(layer "In5.Cu")
		(net "EXP_SPARE_1")
	)
	(segment
		(start 98.191574 -124.3584)
		(end 101.712776 -120.837198)
		(width 0.127)
		(layer "In5.Cu")
		(net "EXP_SPARE_1")
	)
	(segment
		(start 83.845146 -126.492254)
		(end 85.979 -124.3584)
		(width 0.127)
		(layer "In5.Cu")
		(net "EXP_SPARE_1")
	)
	(segment
		(start 101.712776 -120.837198)
		(end 101.712776 -90.246454)
		(width 0.127)
		(layer "In5.Cu")
		(net "EXP_SPARE_1")
	)
	(segment
		(start 101.712776 -90.246454)
		(end 100.726494 -89.260172)
		(width 0.127)
		(layer "In5.Cu")
		(net "EXP_SPARE_1")
	)
	(segment
		(start 58.5978 -123.611132)
		(end 58.891932 -123.317)
		(width 0.127)
		(layer "In5.Cu")
		(net "EXP_SPARE_1")
	)
	(segment
		(start 58.891932 -123.317)
		(end 71.023734 -123.317)
		(width 0.127)
		(layer "In5.Cu")
		(net "EXP_SPARE_1")
	)
	(segment
		(start 74.198988 -126.492254)
		(end 83.845146 -126.492254)
		(width 0.127)
		(layer "In5.Cu")
		(net "EXP_SPARE_1")
	)
	(segment
		(start 71.023734 -123.317)
		(end 74.198988 -126.492254)
		(width 0.127)
		(layer "In5.Cu")
		(net "EXP_SPARE_1")
	)
	(segment
		(start 56.912256 -133.290056)
		(end 56.912256 -132.660136)
		(width 0.127)
		(layer "F.Cu")
		(net "EXP_SPARE_0_R")
	)
	(segment
		(start 56.8706 -134.0866)
		(end 56.1086 -134.8486)
		(width 0.127)
		(layer "F.Cu")
		(net "EXP_SPARE_0_R")
	)
	(segment
		(start 55.299864 -136.425686)
		(end 55.299864 -136.59993)
		(width 0.127)
		(layer "F.Cu")
		(net "EXP_SPARE_0_R")
	)
	(segment
		(start 56.1086 -134.8486)
		(end 56.1086 -135.61695)
		(width 0.127)
		(layer "F.Cu")
		(net "EXP_SPARE_0_R")
	)
	(segment
		(start 58.36158 -131.75742)
		(end 58.486548 -131.75742)
		(width 0.127)
		(layer "F.Cu")
		(net "EXP_SPARE_0_R")
	)
	(segment
		(start 57.2262 -134.0866)
		(end 56.8706 -134.0866)
		(width 0.127)
		(layer "F.Cu")
		(net "EXP_SPARE_0_R")
	)
	(segment
		(start 57.200292 -132.3721)
		(end 57.7469 -132.3721)
		(width 0.127)
		(layer "F.Cu")
		(net "EXP_SPARE_0_R")
	)
	(segment
		(start 56.912256 -132.660136)
		(end 57.200292 -132.3721)
		(width 0.127)
		(layer "F.Cu")
		(net "EXP_SPARE_0_R")
	)
	(segment
		(start 57.2262 -134.0866)
		(end 57.2262 -133.604)
		(width 0.127)
		(layer "F.Cu")
		(net "EXP_SPARE_0_R")
	)
	(segment
		(start 57.7469 -132.3721)
		(end 58.36158 -131.75742)
		(width 0.127)
		(layer "F.Cu")
		(net "EXP_SPARE_0_R")
	)
	(segment
		(start 56.1086 -135.61695)
		(end 55.299864 -136.425686)
		(width 0.127)
		(layer "F.Cu")
		(net "EXP_SPARE_0_R")
	)
	(segment
		(start 57.2262 -133.604)
		(end 56.912256 -133.290056)
		(width 0.127)
		(layer "F.Cu")
		(net "EXP_SPARE_0_R")
	)
	(via
		(at 57.2262 -134.0866)
		(size 0.6604)
		(drill 0.3302)
		(layers "F.Cu" "B.Cu")
		(net "EXP_SPARE_0_R")
	)
	(segment
		(start 102.787958 -123.57354)
		(end 102.787958 -47.471584)
		(width 0.127)
		(layer "F.Cu")
		(net "EXP_SPARE_0")
	)
	(segment
		(start 107.94746 -41.847516)
		(end 108.89996 -42.800016)
		(width 0.127)
		(layer "F.Cu")
		(net "EXP_SPARE_0")
	)
	(segment
		(start 101.62032 -124.741178)
		(end 102.787958 -123.57354)
		(width 0.127)
		(layer "F.Cu")
		(net "EXP_SPARE_0")
	)
	(segment
		(start 107.545378 -27.8384)
		(end 107.94746 -28.240482)
		(width 0.127)
		(layer "F.Cu")
		(net "EXP_SPARE_0")
	)
	(segment
		(start 107.94746 -28.240482)
		(end 107.94746 -41.847516)
		(width 0.127)
		(layer "F.Cu")
		(net "EXP_SPARE_0")
	)
	(segment
		(start 105.67416 -27.8384)
		(end 107.545378 -27.8384)
		(width 0.127)
		(layer "F.Cu")
		(net "EXP_SPARE_0")
	)
	(segment
		(start 102.787958 -47.471584)
		(end 105.063544 -45.195998)
		(width 0.127)
		(layer "F.Cu")
		(net "EXP_SPARE_0")
	)
	(segment
		(start 58.4073 -130.789172)
		(end 58.486548 -130.86842)
		(width 0.127)
		(layer "F.Cu")
		(net "EXP_SPARE_0")
	)
	(segment
		(start 58.0898 -129.738882)
		(end 58.4073 -130.056382)
		(width 0.127)
		(layer "F.Cu")
		(net "EXP_SPARE_0")
	)
	(segment
		(start 105.063544 -28.449016)
		(end 105.67416 -27.8384)
		(width 0.127)
		(layer "F.Cu")
		(net "EXP_SPARE_0")
	)
	(segment
		(start 58.4073 -130.056382)
		(end 58.4073 -130.789172)
		(width 0.127)
		(layer "F.Cu")
		(net "EXP_SPARE_0")
	)
	(segment
		(start 58.0898 -124.642118)
		(end 58.0898 -129.738882)
		(width 0.127)
		(layer "F.Cu")
		(net "EXP_SPARE_0")
	)
	(segment
		(start 105.063544 -45.195998)
		(end 105.063544 -28.449016)
		(width 0.127)
		(layer "F.Cu")
		(net "EXP_SPARE_0")
	)
	(via
		(at 58.0898 -124.642118)
		(size 0.508)
		(drill 0.254)
		(layers "F.Cu" "B.Cu")
		(net "EXP_SPARE_0")
	)
	(via
		(at 101.62032 -124.741178)
		(size 0.508)
		(drill 0.254)
		(layers "F.Cu" "B.Cu")
		(net "EXP_SPARE_0")
	)
	(segment
		(start 84.11337 -126.873254)
		(end 85.586824 -125.3998)
		(width 0.127)
		(layer "In5.Cu")
		(net "EXP_SPARE_0")
	)
	(segment
		(start 58.0898 -124.642118)
		(end 58.772044 -124.642118)
		(width 0.127)
		(layer "In5.Cu")
		(net "EXP_SPARE_0")
	)
	(segment
		(start 71.068946 -123.9012)
		(end 74.041 -126.873254)
		(width 0.127)
		(layer "In5.Cu")
		(net "EXP_SPARE_0")
	)
	(segment
		(start 58.772044 -124.642118)
		(end 59.512962 -123.9012)
		(width 0.127)
		(layer "In5.Cu")
		(net "EXP_SPARE_0")
	)
	(segment
		(start 100.961698 -125.3998)
		(end 101.62032 -124.741178)
		(width 0.127)
		(layer "In5.Cu")
		(net "EXP_SPARE_0")
	)
	(segment
		(start 85.586824 -125.3998)
		(end 100.961698 -125.3998)
		(width 0.127)
		(layer "In5.Cu")
		(net "EXP_SPARE_0")
	)
	(segment
		(start 59.512962 -123.9012)
		(end 71.068946 -123.9012)
		(width 0.127)
		(layer "In5.Cu")
		(net "EXP_SPARE_0")
	)
	(segment
		(start 74.041 -126.873254)
		(end 84.11337 -126.873254)
		(width 0.127)
		(layer "In5.Cu")
		(net "EXP_SPARE_0")
	)
	(segment
		(start 88.728042 -172.62856)
		(end 88.855042 -172.75556)
		(width 0.127)
		(layer "F.Cu")
		(net "DPB_MISC_ALERT")
	)
	(segment
		(start 87.826342 -171.907454)
		(end 88.00719 -171.907454)
		(width 0.127)
		(layer "F.Cu")
		(net "DPB_MISC_ALERT")
	)
	(segment
		(start 87.207852 -172.525944)
		(end 87.826342 -171.907454)
		(width 0.127)
		(layer "F.Cu")
		(net "DPB_MISC_ALERT")
	)
	(segment
		(start 88.00719 -171.907454)
		(end 88.728042 -172.628306)
		(width 0.127)
		(layer "F.Cu")
		(net "DPB_MISC_ALERT")
	)
	(segment
		(start 88.728042 -172.628306)
		(end 88.728042 -172.62856)
		(width 0.127)
		(layer "F.Cu")
		(net "DPB_MISC_ALERT")
	)
	(segment
		(start 88.855042 -172.75556)
		(end 89.51214 -172.75556)
		(width 0.127)
		(layer "F.Cu")
		(net "DPB_MISC_ALERT")
	)
	(via
		(at 99.684332 -43.605704)
		(size 0.508)
		(drill 0.254)
		(layers "F.Cu" "B.Cu")
		(net "DPB_MISC_ALERT")
	)
	(via
		(at 87.207852 -172.525944)
		(size 0.508)
		(drill 0.254)
		(layers "F.Cu" "B.Cu")
		(net "DPB_MISC_ALERT")
	)
	(via
		(at 88.00719 -171.907454)
		(size 0.6604)
		(drill 0.3302)
		(layers "F.Cu" "B.Cu")
		(net "DPB_MISC_ALERT")
	)
	(via
		(at 95.1738 -116.9162)
		(size 0.508)
		(drill 0.254)
		(layers "F.Cu" "B.Cu")
		(net "DPB_MISC_ALERT")
	)
	(segment
		(start 90.21445 -164.732716)
		(end 90.21445 -163.615624)
		(width 0.127)
		(layer "In2.Cu")
		(net "DPB_MISC_ALERT")
	)
	(segment
		(start 93.783404 -160.345882)
		(end 93.783404 -159.121094)
		(width 0.127)
		(layer "In2.Cu")
		(net "DPB_MISC_ALERT")
	)
	(segment
		(start 95.3389 -157.565598)
		(end 95.3389 -153.609802)
		(width 0.127)
		(layer "In2.Cu")
		(net "DPB_MISC_ALERT")
	)
	(segment
		(start 95.026988 -141.233652)
		(end 95.026988 -137.862818)
		(width 0.127)
		(layer "In2.Cu")
		(net "DPB_MISC_ALERT")
	)
	(segment
		(start 93.6625 -145.00987)
		(end 93.67266 -144.99971)
		(width 0.127)
		(layer "In2.Cu")
		(net "DPB_MISC_ALERT")
	)
	(segment
		(start 93.661992 -125.132846)
		(end 93.661992 -122.97156)
		(width 0.127)
		(layer "In2.Cu")
		(net "DPB_MISC_ALERT")
	)
	(segment
		(start 93.6625 -148.445728)
		(end 93.6625 -145.00987)
		(width 0.127)
		(layer "In2.Cu")
		(net "DPB_MISC_ALERT")
	)
	(segment
		(start 105.721404 -27.280616)
		(end 113.288572 -27.280616)
		(width 0.127)
		(layer "In2.Cu")
		(net "DPB_MISC_ALERT")
	)
	(segment
		(start 94.4118 -125.882654)
		(end 93.661992 -125.132846)
		(width 0.127)
		(layer "In2.Cu")
		(net "DPB_MISC_ALERT")
	)
	(segment
		(start 94.9071 -153.178002)
		(end 94.9071 -150.537672)
		(width 0.127)
		(layer "In2.Cu")
		(net "DPB_MISC_ALERT")
	)
	(segment
		(start 95.428308 -137.461498)
		(end 95.428308 -135.925052)
		(width 0.127)
		(layer "In2.Cu")
		(net "DPB_MISC_ALERT")
	)
	(segment
		(start 93.971872 -120.835928)
		(end 94.742 -120.0658)
		(width 0.127)
		(layer "In2.Cu")
		(net "DPB_MISC_ALERT")
	)
	(segment
		(start 93.971872 -122.66168)
		(end 93.971872 -120.835928)
		(width 0.127)
		(layer "In2.Cu")
		(net "DPB_MISC_ALERT")
	)
	(segment
		(start 94.742 -117.348)
		(end 95.1738 -116.9162)
		(width 0.127)
		(layer "In2.Cu")
		(net "DPB_MISC_ALERT")
	)
	(segment
		(start 90.21445 -163.615624)
		(end 91.054174 -162.7759)
		(width 0.127)
		(layer "In2.Cu")
		(net "DPB_MISC_ALERT")
	)
	(segment
		(start 93.67266 -143.847566)
		(end 94.024704 -143.495522)
		(width 0.127)
		(layer "In2.Cu")
		(net "DPB_MISC_ALERT")
	)
	(segment
		(start 116.671344 -42.228516)
		(end 116.099844 -42.800016)
		(width 0.127)
		(layer "In2.Cu")
		(net "DPB_MISC_ALERT")
	)
	(segment
		(start 87.207852 -172.525944)
		(end 89.3826 -170.351196)
		(width 0.127)
		(layer "In2.Cu")
		(net "DPB_MISC_ALERT")
	)
	(segment
		(start 102.27056 -37.77742)
		(end 102.27056 -30.73146)
		(width 0.127)
		(layer "In2.Cu")
		(net "DPB_MISC_ALERT")
	)
	(segment
		(start 93.783404 -159.121094)
		(end 95.3389 -157.565598)
		(width 0.127)
		(layer "In2.Cu")
		(net "DPB_MISC_ALERT")
	)
	(segment
		(start 116.671344 -30.663388)
		(end 116.671344 -42.228516)
		(width 0.127)
		(layer "In2.Cu")
		(net "DPB_MISC_ALERT")
	)
	(segment
		(start 89.3826 -170.351196)
		(end 89.3826 -167.310054)
		(width 0.127)
		(layer "In2.Cu")
		(net "DPB_MISC_ALERT")
	)
	(segment
		(start 99.684332 -43.605704)
		(end 99.684332 -43.401996)
		(width 0.127)
		(layer "In2.Cu")
		(net "DPB_MISC_ALERT")
	)
	(segment
		(start 100.46716 -42.619168)
		(end 100.46716 -38.925754)
		(width 0.127)
		(layer "In2.Cu")
		(net "DPB_MISC_ALERT")
	)
	(segment
		(start 94.898464 -133.1214)
		(end 94.4118 -132.634736)
		(width 0.127)
		(layer "In2.Cu")
		(net "DPB_MISC_ALERT")
	)
	(segment
		(start 94.742 -120.0658)
		(end 94.742 -117.348)
		(width 0.127)
		(layer "In2.Cu")
		(net "DPB_MISC_ALERT")
	)
	(segment
		(start 89.6366 -167.056054)
		(end 89.6366 -165.310566)
		(width 0.127)
		(layer "In2.Cu")
		(net "DPB_MISC_ALERT")
	)
	(segment
		(start 94.4118 -132.634736)
		(end 94.4118 -125.882654)
		(width 0.127)
		(layer "In2.Cu")
		(net "DPB_MISC_ALERT")
	)
	(segment
		(start 101.86162 -38.18636)
		(end 102.27056 -37.77742)
		(width 0.127)
		(layer "In2.Cu")
		(net "DPB_MISC_ALERT")
	)
	(segment
		(start 93.661992 -122.97156)
		(end 93.971872 -122.66168)
		(width 0.127)
		(layer "In2.Cu")
		(net "DPB_MISC_ALERT")
	)
	(segment
		(start 89.3826 -167.310054)
		(end 89.6366 -167.056054)
		(width 0.127)
		(layer "In2.Cu")
		(net "DPB_MISC_ALERT")
	)
	(segment
		(start 102.27056 -30.73146)
		(end 105.721404 -27.280616)
		(width 0.127)
		(layer "In2.Cu")
		(net "DPB_MISC_ALERT")
	)
	(segment
		(start 99.684332 -43.401996)
		(end 100.46716 -42.619168)
		(width 0.127)
		(layer "In2.Cu")
		(net "DPB_MISC_ALERT")
	)
	(segment
		(start 113.288572 -27.280616)
		(end 116.671344 -30.663388)
		(width 0.127)
		(layer "In2.Cu")
		(net "DPB_MISC_ALERT")
	)
	(segment
		(start 89.6366 -165.310566)
		(end 90.21445 -164.732716)
		(width 0.127)
		(layer "In2.Cu")
		(net "DPB_MISC_ALERT")
	)
	(segment
		(start 95.428308 -135.925052)
		(end 94.898464 -135.395208)
		(width 0.127)
		(layer "In2.Cu")
		(net "DPB_MISC_ALERT")
	)
	(segment
		(start 94.898464 -135.395208)
		(end 94.898464 -133.1214)
		(width 0.127)
		(layer "In2.Cu")
		(net "DPB_MISC_ALERT")
	)
	(segment
		(start 93.756988 -149.38756)
		(end 93.756988 -148.540216)
		(width 0.127)
		(layer "In2.Cu")
		(net "DPB_MISC_ALERT")
	)
	(segment
		(start 95.3389 -153.609802)
		(end 94.9071 -153.178002)
		(width 0.127)
		(layer "In2.Cu")
		(net "DPB_MISC_ALERT")
	)
	(segment
		(start 100.46716 -38.925754)
		(end 101.206554 -38.18636)
		(width 0.127)
		(layer "In2.Cu")
		(net "DPB_MISC_ALERT")
	)
	(segment
		(start 91.353386 -162.7759)
		(end 93.783404 -160.345882)
		(width 0.127)
		(layer "In2.Cu")
		(net "DPB_MISC_ALERT")
	)
	(segment
		(start 93.67266 -144.99971)
		(end 93.67266 -143.847566)
		(width 0.127)
		(layer "In2.Cu")
		(net "DPB_MISC_ALERT")
	)
	(segment
		(start 94.024704 -142.235936)
		(end 95.026988 -141.233652)
		(width 0.127)
		(layer "In2.Cu")
		(net "DPB_MISC_ALERT")
	)
	(segment
		(start 94.024704 -143.495522)
		(end 94.024704 -142.235936)
		(width 0.127)
		(layer "In2.Cu")
		(net "DPB_MISC_ALERT")
	)
	(segment
		(start 95.026988 -137.862818)
		(end 95.428308 -137.461498)
		(width 0.127)
		(layer "In2.Cu")
		(net "DPB_MISC_ALERT")
	)
	(segment
		(start 93.756988 -148.540216)
		(end 93.6625 -148.445728)
		(width 0.127)
		(layer "In2.Cu")
		(net "DPB_MISC_ALERT")
	)
	(segment
		(start 91.054174 -162.7759)
		(end 91.353386 -162.7759)
		(width 0.127)
		(layer "In2.Cu")
		(net "DPB_MISC_ALERT")
	)
	(segment
		(start 94.9071 -150.537672)
		(end 93.756988 -149.38756)
		(width 0.127)
		(layer "In2.Cu")
		(net "DPB_MISC_ALERT")
	)
	(segment
		(start 101.206554 -38.18636)
		(end 101.86162 -38.18636)
		(width 0.127)
		(layer "In2.Cu")
		(net "DPB_MISC_ALERT")
	)
	(segment
		(start 98.410776 -96.790764)
		(end 98.410776 -114.368834)
		(width 0.127)
		(layer "In5.Cu")
		(net "DPB_MISC_ALERT")
	)
	(segment
		(start 100.083366 -45.767498)
		(end 99.654106 -46.196758)
		(width 0.127)
		(layer "In5.Cu")
		(net "DPB_MISC_ALERT")
	)
	(segment
		(start 94.986856 -93.366844)
		(end 98.410776 -96.790764)
		(width 0.127)
		(layer "In5.Cu")
		(net "DPB_MISC_ALERT")
	)
	(segment
		(start 99.684332 -43.605704)
		(end 100.083366 -44.004738)
		(width 0.127)
		(layer "In5.Cu")
		(net "DPB_MISC_ALERT")
	)
	(segment
		(start 100.083366 -44.004738)
		(end 100.083366 -45.767498)
		(width 0.127)
		(layer "In5.Cu")
		(net "DPB_MISC_ALERT")
	)
	(segment
		(start 99.654106 -46.196758)
		(end 99.654106 -82.543142)
		(width 0.127)
		(layer "In5.Cu")
		(net "DPB_MISC_ALERT")
	)
	(segment
		(start 98.410776 -114.368834)
		(end 96.564704 -116.214906)
		(width 0.127)
		(layer "In5.Cu")
		(net "DPB_MISC_ALERT")
	)
	(segment
		(start 96.564704 -116.214906)
		(end 95.875094 -116.214906)
		(width 0.127)
		(layer "In5.Cu")
		(net "DPB_MISC_ALERT")
	)
	(segment
		(start 95.875094 -116.214906)
		(end 95.1738 -116.9162)
		(width 0.127)
		(layer "In5.Cu")
		(net "DPB_MISC_ALERT")
	)
	(segment
		(start 99.654106 -82.543142)
		(end 94.986856 -87.210392)
		(width 0.127)
		(layer "In5.Cu")
		(net "DPB_MISC_ALERT")
	)
	(segment
		(start 94.986856 -87.210392)
		(end 94.986856 -93.366844)
		(width 0.127)
		(layer "In5.Cu")
		(net "DPB_MISC_ALERT")
	)
	(segment
		(start 65.95618 -134.380224)
		(end 65.95618 -135.34898)
		(width 0.127)
		(layer "F.Cu")
		(net "COMP_SPARE_1")
	)
	(segment
		(start 65.9892 -134.347204)
		(end 65.95618 -134.380224)
		(width 0.127)
		(layer "F.Cu")
		(net "COMP_SPARE_1")
	)
	(segment
		(start 67.140582 -134.347204)
		(end 65.9892 -134.347204)
		(width 0.127)
		(layer "F.Cu")
		(net "COMP_SPARE_1")
	)
	(via
		(at 101.623622 -136.233154)
		(size 0.508)
		(drill 0.254)
		(layers "F.Cu" "B.Cu")
		(net "COMP_SPARE_1")
	)
	(via
		(at 65.9892 -134.347204)
		(size 0.6604)
		(drill 0.3302)
		(layers "F.Cu" "B.Cu")
		(net "COMP_SPARE_1")
	)
	(via
		(at 67.140582 -134.347204)
		(size 0.508)
		(drill 0.254)
		(layers "F.Cu" "B.Cu")
		(net "COMP_SPARE_1")
	)
	(segment
		(start 107.07116 -45.428662)
		(end 107.099862 -45.39996)
		(width 0.127)
		(layer "In2.Cu")
		(net "COMP_SPARE_1")
	)
	(segment
		(start 102.090474 -47.104046)
		(end 103.765858 -45.428662)
		(width 0.127)
		(layer "In2.Cu")
		(net "COMP_SPARE_1")
	)
	(segment
		(start 102.090474 -135.766302)
		(end 102.090474 -47.104046)
		(width 0.127)
		(layer "In2.Cu")
		(net "COMP_SPARE_1")
	)
	(segment
		(start 101.623622 -136.233154)
		(end 102.090474 -135.766302)
		(width 0.127)
		(layer "In2.Cu")
		(net "COMP_SPARE_1")
	)
	(segment
		(start 103.765858 -45.428662)
		(end 107.07116 -45.428662)
		(width 0.127)
		(layer "In2.Cu")
		(net "COMP_SPARE_1")
	)
	(segment
		(start 80.308196 -134.51713)
		(end 80.901032 -133.924294)
		(width 0.127)
		(layer "In5.Cu")
		(net "COMP_SPARE_1")
	)
	(segment
		(start 80.901032 -133.924294)
		(end 83.521042 -133.924294)
		(width 0.127)
		(layer "In5.Cu")
		(net "COMP_SPARE_1")
	)
	(segment
		(start 84.852256 -136.578594)
		(end 93.258386 -136.578594)
		(width 0.127)
		(layer "In5.Cu")
		(net "COMP_SPARE_1")
	)
	(segment
		(start 67.315334 -134.172452)
		(end 72.801226 -134.172452)
		(width 0.127)
		(layer "In5.Cu")
		(net "COMP_SPARE_1")
	)
	(segment
		(start 100.076 -137.780776)
		(end 101.623622 -136.233154)
		(width 0.127)
		(layer "In5.Cu")
		(net "COMP_SPARE_1")
	)
	(segment
		(start 83.521042 -133.924294)
		(end 84.311744 -134.714996)
		(width 0.127)
		(layer "In5.Cu")
		(net "COMP_SPARE_1")
	)
	(segment
		(start 78.563724 -134.51713)
		(end 80.308196 -134.51713)
		(width 0.127)
		(layer "In5.Cu")
		(net "COMP_SPARE_1")
	)
	(segment
		(start 72.801226 -134.172452)
		(end 73.869296 -135.240522)
		(width 0.127)
		(layer "In5.Cu")
		(net "COMP_SPARE_1")
	)
	(segment
		(start 84.311744 -134.714996)
		(end 84.311744 -136.038082)
		(width 0.127)
		(layer "In5.Cu")
		(net "COMP_SPARE_1")
	)
	(segment
		(start 84.311744 -136.038082)
		(end 84.852256 -136.578594)
		(width 0.127)
		(layer "In5.Cu")
		(net "COMP_SPARE_1")
	)
	(segment
		(start 77.840332 -135.240522)
		(end 78.563724 -134.51713)
		(width 0.127)
		(layer "In5.Cu")
		(net "COMP_SPARE_1")
	)
	(segment
		(start 67.140582 -134.347204)
		(end 67.315334 -134.172452)
		(width 0.127)
		(layer "In5.Cu")
		(net "COMP_SPARE_1")
	)
	(segment
		(start 73.869296 -135.240522)
		(end 77.840332 -135.240522)
		(width 0.127)
		(layer "In5.Cu")
		(net "COMP_SPARE_1")
	)
	(segment
		(start 94.460568 -137.780776)
		(end 100.076 -137.780776)
		(width 0.127)
		(layer "In5.Cu")
		(net "COMP_SPARE_1")
	)
	(segment
		(start 93.258386 -136.578594)
		(end 94.460568 -137.780776)
		(width 0.127)
		(layer "In5.Cu")
		(net "COMP_SPARE_1")
	)
	(via
		(at 64.4398 -134.93496)
		(size 0.6096)
		(drill 0.3048)
		(layers "F.Cu" "B.Cu")
		(net "COMP_SPARE_0")
	)
	(via
		(at 101.62032 -131.953)
		(size 0.508)
		(drill 0.254)
		(layers "F.Cu" "B.Cu")
		(net "COMP_SPARE_0")
	)
	(via
		(at 67.347592 -133.24713)
		(size 0.508)
		(drill 0.254)
		(layers "F.Cu" "B.Cu")
		(net "COMP_SPARE_0")
	)
	(segment
		(start 64.4398 -134.93496)
		(end 65.659762 -134.93496)
		(width 0.127)
		(layer "B.Cu")
		(net "COMP_SPARE_0")
	)
	(segment
		(start 65.659762 -134.93496)
		(end 67.347592 -133.24713)
		(width 0.127)
		(layer "B.Cu")
		(net "COMP_SPARE_0")
	)
	(segment
		(start 64.4398 -134.93496)
		(end 62.6999 -134.93496)
		(width 0.127)
		(layer "B.Cu")
		(net "COMP_SPARE_0")
	)
	(segment
		(start 101.150166 -127.451104)
		(end 101.150166 -124.514102)
		(width 0.127)
		(layer "In2.Cu")
		(net "COMP_SPARE_0")
	)
	(segment
		(start 104.655366 -44.000166)
		(end 107.099862 -44.000166)
		(width 0.127)
		(layer "In2.Cu")
		(net "COMP_SPARE_0")
	)
	(segment
		(start 101.709474 -46.946058)
		(end 104.655366 -44.000166)
		(width 0.127)
		(layer "In2.Cu")
		(net "COMP_SPARE_0")
	)
	(segment
		(start 101.62032 -127.921258)
		(end 101.150166 -127.451104)
		(width 0.127)
		(layer "In2.Cu")
		(net "COMP_SPARE_0")
	)
	(segment
		(start 101.709474 -123.954794)
		(end 101.709474 -46.946058)
		(width 0.127)
		(layer "In2.Cu")
		(net "COMP_SPARE_0")
	)
	(segment
		(start 101.150166 -124.514102)
		(end 101.709474 -123.954794)
		(width 0.127)
		(layer "In2.Cu")
		(net "COMP_SPARE_0")
	)
	(segment
		(start 101.62032 -131.953)
		(end 101.62032 -127.921258)
		(width 0.127)
		(layer "In2.Cu")
		(net "COMP_SPARE_0")
	)
	(segment
		(start 73.84288 -134.13232)
		(end 80.002634 -134.13232)
		(width 0.127)
		(layer "In5.Cu")
		(net "COMP_SPARE_0")
	)
	(segment
		(start 83.714844 -133.543294)
		(end 84.581492 -134.409942)
		(width 0.127)
		(layer "In5.Cu")
		(net "COMP_SPARE_0")
	)
	(segment
		(start 80.59166 -133.543294)
		(end 83.714844 -133.543294)
		(width 0.127)
		(layer "In5.Cu")
		(net "COMP_SPARE_0")
	)
	(segment
		(start 87.479886 -134.409942)
		(end 87.56142 -134.491476)
		(width 0.127)
		(layer "In5.Cu")
		(net "COMP_SPARE_0")
	)
	(segment
		(start 72.95769 -133.24713)
		(end 73.84288 -134.13232)
		(width 0.127)
		(layer "In5.Cu")
		(net "COMP_SPARE_0")
	)
	(segment
		(start 94.864682 -134.491476)
		(end 97.403158 -131.953)
		(width 0.127)
		(layer "In5.Cu")
		(net "COMP_SPARE_0")
	)
	(segment
		(start 97.403158 -131.953)
		(end 101.62032 -131.953)
		(width 0.127)
		(layer "In5.Cu")
		(net "COMP_SPARE_0")
	)
	(segment
		(start 87.56142 -134.491476)
		(end 94.864682 -134.491476)
		(width 0.127)
		(layer "In5.Cu")
		(net "COMP_SPARE_0")
	)
	(segment
		(start 67.347592 -133.24713)
		(end 72.95769 -133.24713)
		(width 0.127)
		(layer "In5.Cu")
		(net "COMP_SPARE_0")
	)
	(segment
		(start 80.002634 -134.13232)
		(end 80.59166 -133.543294)
		(width 0.127)
		(layer "In5.Cu")
		(net "COMP_SPARE_0")
	)
	(segment
		(start 84.581492 -134.409942)
		(end 87.479886 -134.409942)
		(width 0.127)
		(layer "In5.Cu")
		(net "COMP_SPARE_0")
	)
	(segment
		(start 137.700004 -42.800016)
		(end 136.993884 -42.093896)
		(width 0.127)
		(layer "F.Cu")
		(net "BMC_RMT_HEARTBEAT")
	)
	(segment
		(start 136.993884 -42.093896)
		(end 136.993884 -29.040582)
		(width 0.127)
		(layer "F.Cu")
		(net "BMC_RMT_HEARTBEAT")
	)
	(via
		(at 40.74668 -154.98318)
		(size 0.508)
		(drill 0.254)
		(layers "F.Cu" "B.Cu")
		(net "BMC_RMT_HEARTBEAT")
	)
	(via
		(at 39.04488 -155.95854)
		(size 0.6096)
		(drill 0.3048)
		(layers "F.Cu" "B.Cu")
		(net "BMC_RMT_HEARTBEAT")
	)
	(via
		(at 85.0138 -163.703)
		(size 0.508)
		(drill 0.254)
		(layers "F.Cu" "B.Cu")
		(net "BMC_RMT_HEARTBEAT")
	)
	(via
		(at 136.993884 -29.040582)
		(size 0.508)
		(drill 0.254)
		(layers "F.Cu" "B.Cu")
		(net "BMC_RMT_HEARTBEAT")
	)
	(segment
		(start 38.154356 -156.04236)
		(end 38.96106 -156.04236)
		(width 0.127)
		(layer "B.Cu")
		(net "BMC_RMT_HEARTBEAT")
	)
	(segment
		(start 38.117018 -156.005022)
		(end 38.154356 -156.04236)
		(width 0.127)
		(layer "B.Cu")
		(net "BMC_RMT_HEARTBEAT")
	)
	(segment
		(start 38.96106 -156.04236)
		(end 39.04488 -155.95854)
		(width 0.127)
		(layer "B.Cu")
		(net "BMC_RMT_HEARTBEAT")
	)
	(segment
		(start 40.48506 -155.2448)
		(end 40.74668 -154.98318)
		(width 0.127)
		(layer "B.Cu")
		(net "BMC_RMT_HEARTBEAT")
	)
	(segment
		(start 39.04488 -155.95854)
		(end 39.75862 -155.2448)
		(width 0.127)
		(layer "B.Cu")
		(net "BMC_RMT_HEARTBEAT")
	)
	(segment
		(start 39.75862 -155.2448)
		(end 40.48506 -155.2448)
		(width 0.127)
		(layer "B.Cu")
		(net "BMC_RMT_HEARTBEAT")
	)
	(segment
		(start 79.258922 -129.492502)
		(end 79.727044 -129.960624)
		(width 0.127)
		(layer "In2.Cu")
		(net "BMC_RMT_HEARTBEAT")
	)
	(segment
		(start 81.329022 -149.237192)
		(end 82.251042 -150.159212)
		(width 0.127)
		(layer "In2.Cu")
		(net "BMC_RMT_HEARTBEAT")
	)
	(segment
		(start 84.571078 -43.982132)
		(end 84.571078 -46.09465)
		(width 0.127)
		(layer "In2.Cu")
		(net "BMC_RMT_HEARTBEAT")
	)
	(segment
		(start 84.4931 -160.69056)
		(end 84.4931 -163.1823)
		(width 0.127)
		(layer "In2.Cu")
		(net "BMC_RMT_HEARTBEAT")
	)
	(segment
		(start 74.362056 -122.730514)
		(end 79.258922 -127.62738)
		(width 0.127)
		(layer "In2.Cu")
		(net "BMC_RMT_HEARTBEAT")
	)
	(segment
		(start 79.727044 -129.960624)
		(end 79.727044 -140.654786)
		(width 0.127)
		(layer "In2.Cu")
		(net "BMC_RMT_HEARTBEAT")
	)
	(segment
		(start 84.4296 -109.825028)
		(end 84.4296 -111.520224)
		(width 0.127)
		(layer "In2.Cu")
		(net "BMC_RMT_HEARTBEAT")
	)
	(segment
		(start 75.654662 -116.433346)
		(end 75.536806 -116.609368)
		(width 0.127)
		(layer "In2.Cu")
		(net "BMC_RMT_HEARTBEAT")
	)
	(segment
		(start 79.090774 -113.0554)
		(end 76.609448 -115.536726)
		(width 0.127)
		(layer "In2.Cu")
		(net "BMC_RMT_HEARTBEAT")
	)
	(segment
		(start 76.609448 -115.536726)
		(end 76.433426 -115.654582)
		(width 0.127)
		(layer "In2.Cu")
		(net "BMC_RMT_HEARTBEAT")
	)
	(segment
		(start 79.8449 -140.772642)
		(end 79.8449 -146.377406)
		(width 0.127)
		(layer "In2.Cu")
		(net "BMC_RMT_HEARTBEAT")
	)
	(segment
		(start 130.44551 -25.033478)
		(end 126.505462 -21.09343)
		(width 0.127)
		(layer "In2.Cu")
		(net "BMC_RMT_HEARTBEAT")
	)
	(segment
		(start 84.4804 -96.7994)
		(end 84.3534 -96.9264)
		(width 0.127)
		(layer "In2.Cu")
		(net "BMC_RMT_HEARTBEAT")
	)
	(segment
		(start 120.175782 -19.03857)
		(end 118.6307 -17.493488)
		(width 0.127)
		(layer "In2.Cu")
		(net "BMC_RMT_HEARTBEAT")
	)
	(segment
		(start 81.329022 -147.861528)
		(end 81.329022 -149.237192)
		(width 0.127)
		(layer "In2.Cu")
		(net "BMC_RMT_HEARTBEAT")
	)
	(segment
		(start 82.373724 -6.742938)
		(end 80.25638 -8.860282)
		(width 0.127)
		(layer "In2.Cu")
		(net "BMC_RMT_HEARTBEAT")
	)
	(segment
		(start 85.868002 -36.651946)
		(end 85.868002 -42.685208)
		(width 0.127)
		(layer "In2.Cu")
		(net "BMC_RMT_HEARTBEAT")
	)
	(segment
		(start 102.223824 -16.662654)
		(end 98.091498 -12.530328)
		(width 0.127)
		(layer "In2.Cu")
		(net "BMC_RMT_HEARTBEAT")
	)
	(segment
		(start 118.6307 -17.493488)
		(end 109.023912 -17.493488)
		(width 0.127)
		(layer "In2.Cu")
		(net "BMC_RMT_HEARTBEAT")
	)
	(segment
		(start 80.25638 -8.860282)
		(end 80.25638 -31.040324)
		(width 0.127)
		(layer "In2.Cu")
		(net "BMC_RMT_HEARTBEAT")
	)
	(segment
		(start 84.3534 -99.911154)
		(end 86.423246 -101.981)
		(width 0.127)
		(layer "In2.Cu")
		(net "BMC_RMT_HEARTBEAT")
	)
	(segment
		(start 84.3534 -96.9264)
		(end 84.3534 -99.911154)
		(width 0.127)
		(layer "In2.Cu")
		(net "BMC_RMT_HEARTBEAT")
	)
	(segment
		(start 84.4296 -111.520224)
		(end 82.894424 -113.0554)
		(width 0.127)
		(layer "In2.Cu")
		(net "BMC_RMT_HEARTBEAT")
	)
	(segment
		(start 79.8449 -146.377406)
		(end 81.329022 -147.861528)
		(width 0.127)
		(layer "In2.Cu")
		(net "BMC_RMT_HEARTBEAT")
	)
	(segment
		(start 123.871736 -21.09343)
		(end 121.816876 -19.03857)
		(width 0.127)
		(layer "In2.Cu")
		(net "BMC_RMT_HEARTBEAT")
	)
	(segment
		(start 82.251042 -150.159212)
		(end 82.251042 -158.448502)
		(width 0.127)
		(layer "In2.Cu")
		(net "BMC_RMT_HEARTBEAT")
	)
	(segment
		(start 82.251042 -158.448502)
		(end 84.4931 -160.69056)
		(width 0.127)
		(layer "In2.Cu")
		(net "BMC_RMT_HEARTBEAT")
	)
	(segment
		(start 86.168738 -72.768206)
		(end 86.273132 -72.8726)
		(width 0.127)
		(layer "In2.Cu")
		(net "BMC_RMT_HEARTBEAT")
	)
	(segment
		(start 136.993884 -29.040582)
		(end 132.98678 -25.033478)
		(width 0.127)
		(layer "In2.Cu")
		(net "BMC_RMT_HEARTBEAT")
	)
	(segment
		(start 75.536806 -116.609368)
		(end 74.362056 -117.784372)
		(width 0.127)
		(layer "In2.Cu")
		(net "BMC_RMT_HEARTBEAT")
	)
	(segment
		(start 86.423246 -107.831382)
		(end 84.4296 -109.825028)
		(width 0.127)
		(layer "In2.Cu")
		(net "BMC_RMT_HEARTBEAT")
	)
	(segment
		(start 126.505462 -21.09343)
		(end 123.871736 -21.09343)
		(width 0.127)
		(layer "In2.Cu")
		(net "BMC_RMT_HEARTBEAT")
	)
	(segment
		(start 109.023912 -17.493488)
		(end 108.193078 -16.662654)
		(width 0.127)
		(layer "In2.Cu")
		(net "BMC_RMT_HEARTBEAT")
	)
	(segment
		(start 83.726528 -46.9392)
		(end 83.726528 -66.606928)
		(width 0.127)
		(layer "In2.Cu")
		(net "BMC_RMT_HEARTBEAT")
	)
	(segment
		(start 83.726528 -66.606928)
		(end 86.168738 -69.049138)
		(width 0.127)
		(layer "In2.Cu")
		(net "BMC_RMT_HEARTBEAT")
	)
	(segment
		(start 80.25638 -31.040324)
		(end 85.868002 -36.651946)
		(width 0.127)
		(layer "In2.Cu")
		(net "BMC_RMT_HEARTBEAT")
	)
	(segment
		(start 74.362056 -117.784372)
		(end 74.362056 -122.730514)
		(width 0.127)
		(layer "In2.Cu")
		(net "BMC_RMT_HEARTBEAT")
	)
	(segment
		(start 86.273132 -72.8726)
		(end 86.273132 -86.810342)
		(width 0.127)
		(layer "In2.Cu")
		(net "BMC_RMT_HEARTBEAT")
	)
	(segment
		(start 82.894424 -113.0554)
		(end 79.090774 -113.0554)
		(width 0.127)
		(layer "In2.Cu")
		(net "BMC_RMT_HEARTBEAT")
	)
	(segment
		(start 84.571078 -46.09465)
		(end 83.726528 -46.9392)
		(width 0.127)
		(layer "In2.Cu")
		(net "BMC_RMT_HEARTBEAT")
	)
	(segment
		(start 86.423246 -101.981)
		(end 86.423246 -107.831382)
		(width 0.127)
		(layer "In2.Cu")
		(net "BMC_RMT_HEARTBEAT")
	)
	(segment
		(start 121.816876 -19.03857)
		(end 120.175782 -19.03857)
		(width 0.127)
		(layer "In2.Cu")
		(net "BMC_RMT_HEARTBEAT")
	)
	(segment
		(start 84.4931 -163.1823)
		(end 85.0138 -163.703)
		(width 0.127)
		(layer "In2.Cu")
		(net "BMC_RMT_HEARTBEAT")
	)
	(segment
		(start 94.18955 -6.742938)
		(end 82.373724 -6.742938)
		(width 0.127)
		(layer "In2.Cu")
		(net "BMC_RMT_HEARTBEAT")
	)
	(segment
		(start 98.091498 -12.530328)
		(end 98.091498 -10.644886)
		(width 0.127)
		(layer "In2.Cu")
		(net "BMC_RMT_HEARTBEAT")
	)
	(segment
		(start 98.091498 -10.644886)
		(end 94.18955 -6.742938)
		(width 0.127)
		(layer "In2.Cu")
		(net "BMC_RMT_HEARTBEAT")
	)
	(segment
		(start 108.193078 -16.662654)
		(end 102.223824 -16.662654)
		(width 0.127)
		(layer "In2.Cu")
		(net "BMC_RMT_HEARTBEAT")
	)
	(segment
		(start 76.433426 -115.654582)
		(end 75.654662 -116.433346)
		(width 0.127)
		(layer "In2.Cu")
		(net "BMC_RMT_HEARTBEAT")
	)
	(segment
		(start 85.868002 -42.685208)
		(end 84.571078 -43.982132)
		(width 0.127)
		(layer "In2.Cu")
		(net "BMC_RMT_HEARTBEAT")
	)
	(segment
		(start 79.258922 -127.62738)
		(end 79.258922 -129.492502)
		(width 0.127)
		(layer "In2.Cu")
		(net "BMC_RMT_HEARTBEAT")
	)
	(segment
		(start 132.98678 -25.033478)
		(end 130.44551 -25.033478)
		(width 0.127)
		(layer "In2.Cu")
		(net "BMC_RMT_HEARTBEAT")
	)
	(segment
		(start 86.273132 -86.810342)
		(end 84.4804 -88.603074)
		(width 0.127)
		(layer "In2.Cu")
		(net "BMC_RMT_HEARTBEAT")
	)
	(segment
		(start 84.4804 -88.603074)
		(end 84.4804 -96.7994)
		(width 0.127)
		(layer "In2.Cu")
		(net "BMC_RMT_HEARTBEAT")
	)
	(segment
		(start 79.727044 -140.654786)
		(end 79.8449 -140.772642)
		(width 0.127)
		(layer "In2.Cu")
		(net "BMC_RMT_HEARTBEAT")
	)
	(segment
		(start 86.168738 -69.049138)
		(end 86.168738 -72.768206)
		(width 0.127)
		(layer "In2.Cu")
		(net "BMC_RMT_HEARTBEAT")
	)
	(segment
		(start 74.20483 -158.177738)
		(end 73.703688 -158.67888)
		(width 0.127)
		(layer "In5.Cu")
		(net "BMC_RMT_HEARTBEAT")
	)
	(segment
		(start 85.725 -162.8394)
		(end 85.725 -162.361372)
		(width 0.127)
		(layer "In5.Cu")
		(net "BMC_RMT_HEARTBEAT")
	)
	(segment
		(start 46.317662 -154.00655)
		(end 41.72331 -154.00655)
		(width 0.127)
		(layer "In5.Cu")
		(net "BMC_RMT_HEARTBEAT")
	)
	(segment
		(start 62.9158 -156.6672)
		(end 58.3946 -156.6672)
		(width 0.127)
		(layer "In5.Cu")
		(net "BMC_RMT_HEARTBEAT")
	)
	(segment
		(start 76.138278 -158.177738)
		(end 74.20483 -158.177738)
		(width 0.127)
		(layer "In5.Cu")
		(net "BMC_RMT_HEARTBEAT")
	)
	(segment
		(start 73.703688 -158.67888)
		(end 68.28028 -158.67888)
		(width 0.127)
		(layer "In5.Cu")
		(net "BMC_RMT_HEARTBEAT")
	)
	(segment
		(start 58.3946 -156.6672)
		(end 56.8452 -155.1178)
		(width 0.127)
		(layer "In5.Cu")
		(net "BMC_RMT_HEARTBEAT")
	)
	(segment
		(start 67.193668 -157.592268)
		(end 63.840868 -157.592268)
		(width 0.127)
		(layer "In5.Cu")
		(net "BMC_RMT_HEARTBEAT")
	)
	(segment
		(start 56.8452 -155.1178)
		(end 50.24374 -155.1178)
		(width 0.127)
		(layer "In5.Cu")
		(net "BMC_RMT_HEARTBEAT")
	)
	(segment
		(start 41.72331 -154.00655)
		(end 40.74668 -154.98318)
		(width 0.127)
		(layer "In5.Cu")
		(net "BMC_RMT_HEARTBEAT")
	)
	(segment
		(start 85.0138 -163.5506)
		(end 85.725 -162.8394)
		(width 0.127)
		(layer "In5.Cu")
		(net "BMC_RMT_HEARTBEAT")
	)
	(segment
		(start 85.725 -162.361372)
		(end 82.629502 -159.265874)
		(width 0.127)
		(layer "In5.Cu")
		(net "BMC_RMT_HEARTBEAT")
	)
	(segment
		(start 48.292512 -155.9814)
		(end 46.317662 -154.00655)
		(width 0.127)
		(layer "In5.Cu")
		(net "BMC_RMT_HEARTBEAT")
	)
	(segment
		(start 82.629502 -159.265874)
		(end 77.226414 -159.265874)
		(width 0.127)
		(layer "In5.Cu")
		(net "BMC_RMT_HEARTBEAT")
	)
	(segment
		(start 77.226414 -159.265874)
		(end 76.138278 -158.177738)
		(width 0.127)
		(layer "In5.Cu")
		(net "BMC_RMT_HEARTBEAT")
	)
	(segment
		(start 68.28028 -158.67888)
		(end 67.193668 -157.592268)
		(width 0.127)
		(layer "In5.Cu")
		(net "BMC_RMT_HEARTBEAT")
	)
	(segment
		(start 63.840868 -157.592268)
		(end 62.9158 -156.6672)
		(width 0.127)
		(layer "In5.Cu")
		(net "BMC_RMT_HEARTBEAT")
	)
	(segment
		(start 85.0138 -163.703)
		(end 85.0138 -163.5506)
		(width 0.127)
		(layer "In5.Cu")
		(net "BMC_RMT_HEARTBEAT")
	)
	(segment
		(start 49.38014 -155.9814)
		(end 48.292512 -155.9814)
		(width 0.127)
		(layer "In5.Cu")
		(net "BMC_RMT_HEARTBEAT")
	)
	(segment
		(start 50.24374 -155.1178)
		(end 49.38014 -155.9814)
		(width 0.127)
		(layer "In5.Cu")
		(net "BMC_RMT_HEARTBEAT")
	)
	(segment
		(start 42.900092 -150.599648)
		(end 43.299888 -150.199852)
		(width 0.127)
		(layer "F.Cu")
		(net "BMC_RMT_HB")
	)
	(segment
		(start 42.900092 -150.599902)
		(end 42.900092 -150.599648)
		(width 0.127)
		(layer "F.Cu")
		(net "BMC_RMT_HB")
	)
	(via
		(at 39.793926 -153.46299)
		(size 0.6096)
		(drill 0.3048)
		(layers "F.Cu" "B.Cu")
		(net "BMC_RMT_HB")
	)
	(via
		(at 42.900092 -150.599902)
		(size 0.4572)
		(drill 0.2032)
		(layers "F.Cu" "B.Cu")
		(net "BMC_RMT_HB")
	)
	(segment
		(start 41.706292 -151.550624)
		(end 41.706292 -151.23668)
		(width 0.127)
		(layer "B.Cu")
		(net "BMC_RMT_HB")
	)
	(segment
		(start 40.893492 -152.04948)
		(end 41.14927 -151.793702)
		(width 0.127)
		(layer "B.Cu")
		(net "BMC_RMT_HB")
	)
	(segment
		(start 42.734992 -150.765002)
		(end 42.900092 -150.599902)
		(width 0.127)
		(layer "B.Cu")
		(net "BMC_RMT_HB")
	)
	(segment
		(start 40.893492 -152.363424)
		(end 40.893492 -152.04948)
		(width 0.127)
		(layer "B.Cu")
		(net "BMC_RMT_HB")
	)
	(segment
		(start 41.93667 -151.006302)
		(end 42.413428 -151.006302)
		(width 0.127)
		(layer "B.Cu")
		(net "BMC_RMT_HB")
	)
	(segment
		(start 42.654728 -150.765002)
		(end 42.734992 -150.765002)
		(width 0.127)
		(layer "B.Cu")
		(net "BMC_RMT_HB")
	)
	(segment
		(start 41.14927 -151.793702)
		(end 41.463214 -151.793702)
		(width 0.127)
		(layer "B.Cu")
		(net "BMC_RMT_HB")
	)
	(segment
		(start 38.117018 -155.116022)
		(end 38.141148 -155.116022)
		(width 0.127)
		(layer "B.Cu")
		(net "BMC_RMT_HB")
	)
	(segment
		(start 39.228522 -154.028648)
		(end 39.228522 -154.028394)
		(width 0.127)
		(layer "B.Cu")
		(net "BMC_RMT_HB")
	)
	(segment
		(start 41.706292 -151.23668)
		(end 41.93667 -151.006302)
		(width 0.127)
		(layer "B.Cu")
		(net "BMC_RMT_HB")
	)
	(segment
		(start 39.228522 -154.028394)
		(end 39.793926 -153.46299)
		(width 0.127)
		(layer "B.Cu")
		(net "BMC_RMT_HB")
	)
	(segment
		(start 42.413428 -151.006302)
		(end 42.654728 -150.765002)
		(width 0.127)
		(layer "B.Cu")
		(net "BMC_RMT_HB")
	)
	(segment
		(start 41.463214 -151.793702)
		(end 41.706292 -151.550624)
		(width 0.127)
		(layer "B.Cu")
		(net "BMC_RMT_HB")
	)
	(segment
		(start 39.793926 -153.46299)
		(end 40.893492 -152.363424)
		(width 0.127)
		(layer "B.Cu")
		(net "BMC_RMT_HB")
	)
	(segment
		(start 38.141148 -155.116022)
		(end 39.228522 -154.028648)
		(width 0.127)
		(layer "B.Cu")
		(net "BMC_RMT_HB")
	)
	(segment
		(start 137.700004 -44.200064)
		(end 136.523984 -43.024044)
		(width 0.127)
		(layer "F.Cu")
		(net "BMC_LOC_HEARTBEAT")
	)
	(segment
		(start 136.523984 -28.845764)
		(end 136.799066 -28.570682)
		(width 0.127)
		(layer "F.Cu")
		(net "BMC_LOC_HEARTBEAT")
	)
	(segment
		(start 136.837928 -28.570682)
		(end 137.205466 -28.203144)
		(width 0.127)
		(layer "F.Cu")
		(net "BMC_LOC_HEARTBEAT")
	)
	(segment
		(start 136.523984 -43.024044)
		(end 136.523984 -28.845764)
		(width 0.127)
		(layer "F.Cu")
		(net "BMC_LOC_HEARTBEAT")
	)
	(segment
		(start 136.799066 -28.570682)
		(end 136.837928 -28.570682)
		(width 0.127)
		(layer "F.Cu")
		(net "BMC_LOC_HEARTBEAT")
	)
	(via
		(at 137.205466 -28.203144)
		(size 0.508)
		(drill 0.254)
		(layers "F.Cu" "B.Cu")
		(net "BMC_LOC_HEARTBEAT")
	)
	(via
		(at 41.4528 -154.95778)
		(size 0.508)
		(drill 0.254)
		(layers "F.Cu" "B.Cu")
		(net "BMC_LOC_HEARTBEAT")
	)
	(via
		(at 83.9216 -163.6522)
		(size 0.508)
		(drill 0.254)
		(layers "F.Cu" "B.Cu")
		(net "BMC_LOC_HEARTBEAT")
	)
	(segment
		(start 41.4528 -154.95778)
		(end 41.6433 -154.76728)
		(width 0.127)
		(layer "B.Cu")
		(net "BMC_LOC_HEARTBEAT")
	)
	(segment
		(start 41.6433 -154.76728)
		(end 41.6433 -154.11704)
		(width 0.127)
		(layer "B.Cu")
		(net "BMC_LOC_HEARTBEAT")
	)
	(segment
		(start 81.870042 -150.3172)
		(end 81.870042 -158.60649)
		(width 0.127)
		(layer "In2.Cu")
		(net "BMC_LOC_HEARTBEAT")
	)
	(segment
		(start 82.463386 -5.5753)
		(end 79.49438 -8.544306)
		(width 0.127)
		(layer "In2.Cu")
		(net "BMC_LOC_HEARTBEAT")
	)
	(segment
		(start 79.49438 -31.3563)
		(end 84.9757 -36.83762)
		(width 0.127)
		(layer "In2.Cu")
		(net "BMC_LOC_HEARTBEAT")
	)
	(segment
		(start 82.964528 -46.473872)
		(end 82.964528 -68.181728)
		(width 0.127)
		(layer "In2.Cu")
		(net "BMC_LOC_HEARTBEAT")
	)
	(segment
		(start 126.985776 -20.701)
		(end 124.018294 -20.701)
		(width 0.127)
		(layer "In2.Cu")
		(net "BMC_LOC_HEARTBEAT")
	)
	(segment
		(start 83.947 -100.165154)
		(end 86.042246 -102.2604)
		(width 0.127)
		(layer "In2.Cu")
		(net "BMC_LOC_HEARTBEAT")
	)
	(segment
		(start 84.0486 -109.66704)
		(end 84.0486 -111.3282)
		(width 0.127)
		(layer "In2.Cu")
		(net "BMC_LOC_HEARTBEAT")
	)
	(segment
		(start 83.3501 -163.0807)
		(end 83.9216 -163.6522)
		(width 0.127)
		(layer "In2.Cu")
		(net "BMC_LOC_HEARTBEAT")
	)
	(segment
		(start 79.718408 -148.165566)
		(end 81.870042 -150.3172)
		(width 0.127)
		(layer "In2.Cu")
		(net "BMC_LOC_HEARTBEAT")
	)
	(segment
		(start 83.947 -96.647)
		(end 83.947 -100.165154)
		(width 0.127)
		(layer "In2.Cu")
		(net "BMC_LOC_HEARTBEAT")
	)
	(segment
		(start 121.974864 -18.65757)
		(end 120.4087 -18.65757)
		(width 0.127)
		(layer "In2.Cu")
		(net "BMC_LOC_HEARTBEAT")
	)
	(segment
		(start 124.018294 -20.701)
		(end 121.974864 -18.65757)
		(width 0.127)
		(layer "In2.Cu")
		(net "BMC_LOC_HEARTBEAT")
	)
	(segment
		(start 86.042246 -107.673394)
		(end 84.0486 -109.66704)
		(width 0.127)
		(layer "In2.Cu")
		(net "BMC_LOC_HEARTBEAT")
	)
	(segment
		(start 118.85803 -17.1069)
		(end 109.728 -17.1069)
		(width 0.127)
		(layer "In2.Cu")
		(net "BMC_LOC_HEARTBEAT")
	)
	(segment
		(start 78.877668 -127.785114)
		(end 78.877668 -129.650236)
		(width 0.127)
		(layer "In2.Cu")
		(net "BMC_LOC_HEARTBEAT")
	)
	(segment
		(start 78.87462 -112.6744)
		(end 73.981056 -117.567964)
		(width 0.127)
		(layer "In2.Cu")
		(net "BMC_LOC_HEARTBEAT")
	)
	(segment
		(start 79.4639 -140.93063)
		(end 79.4639 -146.535394)
		(width 0.127)
		(layer "In2.Cu")
		(net "BMC_LOC_HEARTBEAT")
	)
	(segment
		(start 82.964528 -68.181728)
		(end 84.013802 -69.231002)
		(width 0.127)
		(layer "In2.Cu")
		(net "BMC_LOC_HEARTBEAT")
	)
	(segment
		(start 79.718408 -146.789902)
		(end 79.718408 -148.165566)
		(width 0.127)
		(layer "In2.Cu")
		(net "BMC_LOC_HEARTBEAT")
	)
	(segment
		(start 86.042246 -102.2604)
		(end 86.042246 -107.673394)
		(width 0.127)
		(layer "In2.Cu")
		(net "BMC_LOC_HEARTBEAT")
	)
	(segment
		(start 78.877668 -129.650236)
		(end 79.312262 -130.08483)
		(width 0.127)
		(layer "In2.Cu")
		(net "BMC_LOC_HEARTBEAT")
	)
	(segment
		(start 73.981056 -117.567964)
		(end 73.981056 -122.888502)
		(width 0.127)
		(layer "In2.Cu")
		(net "BMC_LOC_HEARTBEAT")
	)
	(segment
		(start 83.3501 -160.086548)
		(end 83.3501 -163.0807)
		(width 0.127)
		(layer "In2.Cu")
		(net "BMC_LOC_HEARTBEAT")
	)
	(segment
		(start 83.693 -43.782234)
		(end 83.693 -45.7454)
		(width 0.127)
		(layer "In2.Cu")
		(net "BMC_LOC_HEARTBEAT")
	)
	(segment
		(start 137.205466 -28.203144)
		(end 133.6548 -24.652478)
		(width 0.127)
		(layer "In2.Cu")
		(net "BMC_LOC_HEARTBEAT")
	)
	(segment
		(start 120.4087 -18.65757)
		(end 118.85803 -17.1069)
		(width 0.127)
		(layer "In2.Cu")
		(net "BMC_LOC_HEARTBEAT")
	)
	(segment
		(start 84.9757 -42.499534)
		(end 83.693 -43.782234)
		(width 0.127)
		(layer "In2.Cu")
		(net "BMC_LOC_HEARTBEAT")
	)
	(segment
		(start 130.937254 -24.652478)
		(end 126.985776 -20.701)
		(width 0.127)
		(layer "In2.Cu")
		(net "BMC_LOC_HEARTBEAT")
	)
	(segment
		(start 84.013802 -69.231002)
		(end 84.013802 -96.580198)
		(width 0.127)
		(layer "In2.Cu")
		(net "BMC_LOC_HEARTBEAT")
	)
	(segment
		(start 105.49382 -4.3815)
		(end 84.652612 -4.3815)
		(width 0.127)
		(layer "In2.Cu")
		(net "BMC_LOC_HEARTBEAT")
	)
	(segment
		(start 84.0486 -111.3282)
		(end 82.7024 -112.6744)
		(width 0.127)
		(layer "In2.Cu")
		(net "BMC_LOC_HEARTBEAT")
	)
	(segment
		(start 79.312262 -140.778992)
		(end 79.4639 -140.93063)
		(width 0.127)
		(layer "In2.Cu")
		(net "BMC_LOC_HEARTBEAT")
	)
	(segment
		(start 79.4639 -146.535394)
		(end 79.718408 -146.789902)
		(width 0.127)
		(layer "In2.Cu")
		(net "BMC_LOC_HEARTBEAT")
	)
	(segment
		(start 83.693 -45.7454)
		(end 82.964528 -46.473872)
		(width 0.127)
		(layer "In2.Cu")
		(net "BMC_LOC_HEARTBEAT")
	)
	(segment
		(start 79.49438 -8.544306)
		(end 79.49438 -31.3563)
		(width 0.127)
		(layer "In2.Cu")
		(net "BMC_LOC_HEARTBEAT")
	)
	(segment
		(start 109.728 -17.1069)
		(end 108.7501 -16.129)
		(width 0.127)
		(layer "In2.Cu")
		(net "BMC_LOC_HEARTBEAT")
	)
	(segment
		(start 83.458812 -5.5753)
		(end 82.463386 -5.5753)
		(width 0.127)
		(layer "In2.Cu")
		(net "BMC_LOC_HEARTBEAT")
	)
	(segment
		(start 82.7024 -112.6744)
		(end 78.87462 -112.6744)
		(width 0.127)
		(layer "In2.Cu")
		(net "BMC_LOC_HEARTBEAT")
	)
	(segment
		(start 84.013802 -96.580198)
		(end 83.947 -96.647)
		(width 0.127)
		(layer "In2.Cu")
		(net "BMC_LOC_HEARTBEAT")
	)
	(segment
		(start 81.870042 -158.60649)
		(end 83.3501 -160.086548)
		(width 0.127)
		(layer "In2.Cu")
		(net "BMC_LOC_HEARTBEAT")
	)
	(segment
		(start 84.9757 -36.83762)
		(end 84.9757 -42.499534)
		(width 0.127)
		(layer "In2.Cu")
		(net "BMC_LOC_HEARTBEAT")
	)
	(segment
		(start 84.652612 -4.3815)
		(end 83.458812 -5.5753)
		(width 0.127)
		(layer "In2.Cu")
		(net "BMC_LOC_HEARTBEAT")
	)
	(segment
		(start 108.7501 -16.129)
		(end 108.7501 -7.63778)
		(width 0.127)
		(layer "In2.Cu")
		(net "BMC_LOC_HEARTBEAT")
	)
	(segment
		(start 133.6548 -24.652478)
		(end 130.937254 -24.652478)
		(width 0.127)
		(layer "In2.Cu")
		(net "BMC_LOC_HEARTBEAT")
	)
	(segment
		(start 79.312262 -130.08483)
		(end 79.312262 -140.778992)
		(width 0.127)
		(layer "In2.Cu")
		(net "BMC_LOC_HEARTBEAT")
	)
	(segment
		(start 73.981056 -122.888502)
		(end 78.877668 -127.785114)
		(width 0.127)
		(layer "In2.Cu")
		(net "BMC_LOC_HEARTBEAT")
	)
	(segment
		(start 108.7501 -7.63778)
		(end 105.49382 -4.3815)
		(width 0.127)
		(layer "In2.Cu")
		(net "BMC_LOC_HEARTBEAT")
	)
	(segment
		(start 66.239644 -159.538162)
		(end 65.262252 -158.56077)
		(width 0.127)
		(layer "In5.Cu")
		(net "BMC_LOC_HEARTBEAT")
	)
	(segment
		(start 74.284078 -158.637478)
		(end 73.861676 -159.05988)
		(width 0.127)
		(layer "In5.Cu")
		(net "BMC_LOC_HEARTBEAT")
	)
	(segment
		(start 84.5693 -163.0045)
		(end 84.5693 -162.424872)
		(width 0.127)
		(layer "In5.Cu")
		(net "BMC_LOC_HEARTBEAT")
	)
	(segment
		(start 76.05903 -158.637478)
		(end 74.284078 -158.637478)
		(width 0.127)
		(layer "In5.Cu")
		(net "BMC_LOC_HEARTBEAT")
	)
	(segment
		(start 47.965614 -156.387546)
		(end 45.987462 -154.409394)
		(width 0.127)
		(layer "In5.Cu")
		(net "BMC_LOC_HEARTBEAT")
	)
	(segment
		(start 84.5693 -162.424872)
		(end 81.791556 -159.647128)
		(width 0.127)
		(layer "In5.Cu")
		(net "BMC_LOC_HEARTBEAT")
	)
	(segment
		(start 73.861676 -159.05988)
		(end 68.453508 -159.05988)
		(width 0.127)
		(layer "In5.Cu")
		(net "BMC_LOC_HEARTBEAT")
	)
	(segment
		(start 63.86957 -158.56077)
		(end 62.5094 -157.2006)
		(width 0.127)
		(layer "In5.Cu")
		(net "BMC_LOC_HEARTBEAT")
	)
	(segment
		(start 58.1914 -157.2006)
		(end 56.388 -155.3972)
		(width 0.127)
		(layer "In5.Cu")
		(net "BMC_LOC_HEARTBEAT")
	)
	(segment
		(start 42.001186 -154.409394)
		(end 41.4528 -154.95778)
		(width 0.127)
		(layer "In5.Cu")
		(net "BMC_LOC_HEARTBEAT")
	)
	(segment
		(start 68.081906 -159.431736)
		(end 67.97548 -159.538162)
		(width 0.127)
		(layer "In5.Cu")
		(net "BMC_LOC_HEARTBEAT")
	)
	(segment
		(start 45.987462 -154.409394)
		(end 42.001186 -154.409394)
		(width 0.127)
		(layer "In5.Cu")
		(net "BMC_LOC_HEARTBEAT")
	)
	(segment
		(start 50.5714 -155.3972)
		(end 49.581054 -156.387546)
		(width 0.127)
		(layer "In5.Cu")
		(net "BMC_LOC_HEARTBEAT")
	)
	(segment
		(start 67.97548 -159.538162)
		(end 66.239644 -159.538162)
		(width 0.127)
		(layer "In5.Cu")
		(net "BMC_LOC_HEARTBEAT")
	)
	(segment
		(start 62.5094 -157.2006)
		(end 58.1914 -157.2006)
		(width 0.127)
		(layer "In5.Cu")
		(net "BMC_LOC_HEARTBEAT")
	)
	(segment
		(start 56.388 -155.3972)
		(end 50.5714 -155.3972)
		(width 0.127)
		(layer "In5.Cu")
		(net "BMC_LOC_HEARTBEAT")
	)
	(segment
		(start 81.791556 -159.647128)
		(end 77.06868 -159.647128)
		(width 0.127)
		(layer "In5.Cu")
		(net "BMC_LOC_HEARTBEAT")
	)
	(segment
		(start 65.262252 -158.56077)
		(end 63.86957 -158.56077)
		(width 0.127)
		(layer "In5.Cu")
		(net "BMC_LOC_HEARTBEAT")
	)
	(segment
		(start 83.9216 -163.6522)
		(end 84.5693 -163.0045)
		(width 0.127)
		(layer "In5.Cu")
		(net "BMC_LOC_HEARTBEAT")
	)
	(segment
		(start 68.081906 -159.431482)
		(end 68.081906 -159.431736)
		(width 0.127)
		(layer "In5.Cu")
		(net "BMC_LOC_HEARTBEAT")
	)
	(segment
		(start 77.06868 -159.647128)
		(end 76.05903 -158.637478)
		(width 0.127)
		(layer "In5.Cu")
		(net "BMC_LOC_HEARTBEAT")
	)
	(segment
		(start 49.581054 -156.387546)
		(end 47.965614 -156.387546)
		(width 0.127)
		(layer "In5.Cu")
		(net "BMC_LOC_HEARTBEAT")
	)
	(segment
		(start 68.453508 -159.05988)
		(end 68.081906 -159.431482)
		(width 0.127)
		(layer "In5.Cu")
		(net "BMC_LOC_HEARTBEAT")
	)
	(segment
		(start 42.900092 -151.399748)
		(end 43.299888 -150.999952)
		(width 0.127)
		(layer "F.Cu")
		(net "BMC_LOC_HB")
	)
	(segment
		(start 42.900092 -151.400002)
		(end 42.900092 -151.399748)
		(width 0.127)
		(layer "F.Cu")
		(net "BMC_LOC_HB")
	)
	(via
		(at 42.900092 -151.400002)
		(size 0.4572)
		(drill 0.2032)
		(layers "F.Cu" "B.Cu")
		(net "BMC_LOC_HB")
	)
	(via
		(at 41.4782 -153.0604)
		(size 0.6096)
		(drill 0.3048)
		(layers "F.Cu" "B.Cu")
		(net "BMC_LOC_HB")
	)
	(segment
		(start 42.493692 -152.363424)
		(end 41.796716 -153.0604)
		(width 0.127)
		(layer "B.Cu")
		(net "BMC_LOC_HB")
	)
	(segment
		(start 41.796716 -153.0604)
		(end 41.4782 -153.0604)
		(width 0.127)
		(layer "B.Cu")
		(net "BMC_LOC_HB")
	)
	(segment
		(start 41.4782 -153.0604)
		(end 40.7543 -153.7843)
		(width 0.127)
		(layer "B.Cu")
		(net "BMC_LOC_HB")
	)
	(segment
		(start 42.493692 -152.04948)
		(end 42.493692 -152.363424)
		(width 0.127)
		(layer "B.Cu")
		(net "BMC_LOC_HB")
	)
	(segment
		(start 42.900092 -151.400002)
		(end 42.900092 -151.64308)
		(width 0.127)
		(layer "B.Cu")
		(net "BMC_LOC_HB")
	)
	(segment
		(start 40.7543 -153.7843)
		(end 40.7543 -154.11704)
		(width 0.127)
		(layer "B.Cu")
		(net "BMC_LOC_HB")
	)
	(segment
		(start 42.900092 -151.64308)
		(end 42.493692 -152.04948)
		(width 0.127)
		(layer "B.Cu")
		(net "BMC_LOC_HB")
	)
	(segment
		(start 26.90368 -124.375672)
		(end 26.90368 -123.303792)
		(width 0.127)
		(layer "F.Cu")
		(net "WP_DISABLE")
	)
	(segment
		(start 65.2526 -178.538886)
		(end 65.641474 -178.92776)
		(width 0.4064)
		(layer "F.Cu")
		(net "VREF_2V2")
	)
	(segment
		(start 66.709036 -178.92776)
		(end 66.71183 -178.930554)
		(width 0.508)
		(layer "F.Cu")
		(net "VREF_2V2")
	)
	(segment
		(start 65.2526 -177.72761)
		(end 65.2526 -178.538886)
		(width 0.4064)
		(layer "F.Cu")
		(net "VREF_2V2")
	)
	(segment
		(start 65.2526 -177.2412)
		(end 65.2526 -177.72761)
		(width 0.4064)
		(layer "F.Cu")
		(net "VREF_2V2")
	)
	(segment
		(start 65.626234 -175.913796)
		(end 65.626234 -176.867566)
		(width 0.4064)
		(layer "F.Cu")
		(net "VREF_2V2")
	)
	(segment
		(start 65.641474 -178.92776)
		(end 66.709036 -178.92776)
		(width 0.508)
		(layer "F.Cu")
		(net "VREF_2V2")
	)
	(segment
		(start 65.626234 -176.867566)
		(end 65.2526 -177.2412)
		(width 0.4064)
		(layer "F.Cu")
		(net "VREF_2V2")
	)
	(via
		(at 65.2526 -177.72761)
		(size 0.6604)
		(drill 0.3302)
		(layers "F.Cu" "B.Cu")
		(net "VREF_2V2")
	)
	(segment
		(start 114.3 -44.405042)
		(end 114.43208 -44.537122)
		(width 0.14605)
		(layer "F.Cu")
		(net "USB_COMP_DP")
	)
	(segment
		(start 96.31045 -160.89376)
		(end 94.102428 -160.89376)
		(width 0.14605)
		(layer "F.Cu")
		(net "USB_COMP_DP")
	)
	(segment
		(start 107.815888 -25.285192)
		(end 104.692958 -25.285192)
		(width 0.14605)
		(layer "F.Cu")
		(net "USB_COMP_DP")
	)
	(segment
		(start 113.976404 -22.265894)
		(end 110.835186 -22.265894)
		(width 0.14605)
		(layer "F.Cu")
		(net "USB_COMP_DP")
	)
	(segment
		(start 96.95688 -161.754312)
		(end 96.95688 -161.54019)
		(width 0.14605)
		(layer "F.Cu")
		(net "USB_COMP_DP")
	)
	(segment
		(start 114.81435 -44.537122)
		(end 114.986562 -44.36491)
		(width 0.14605)
		(layer "F.Cu")
		(net "USB_COMP_DP")
	)
	(segment
		(start 93.289628 -159.34309)
		(end 93.251782 -159.305244)
		(width 0.14605)
		(layer "F.Cu")
		(net "USB_COMP_DP")
	)
	(segment
		(start 96.632522 -162.07867)
		(end 96.95688 -161.754312)
		(width 0.14605)
		(layer "F.Cu")
		(net "USB_COMP_DP")
	)
	(segment
		(start 114.3 -44.000166)
		(end 114.3 -44.405042)
		(width 0.14605)
		(layer "F.Cu")
		(net "USB_COMP_DP")
	)
	(segment
		(start 93.251782 -159.305244)
		(end 93.251782 -158.47568)
		(width 0.14605)
		(layer "F.Cu")
		(net "USB_COMP_DP")
	)
	(segment
		(start 93.289628 -160.08096)
		(end 93.289628 -159.34309)
		(width 0.14605)
		(layer "F.Cu")
		(net "USB_COMP_DP")
	)
	(segment
		(start 102.556056 -40.493442)
		(end 102.264718 -40.78478)
		(width 0.14605)
		(layer "F.Cu")
		(net "USB_COMP_DP")
	)
	(segment
		(start 114.986562 -44.36491)
		(end 114.986562 -23.276052)
		(width 0.14605)
		(layer "F.Cu")
		(net "USB_COMP_DP")
	)
	(segment
		(start 101.991414 -40.78478)
		(end 101.65207 -41.124124)
		(width 0.14605)
		(layer "F.Cu")
		(net "USB_COMP_DP")
	)
	(segment
		(start 114.986562 -23.276052)
		(end 113.976404 -22.265894)
		(width 0.14605)
		(layer "F.Cu")
		(net "USB_COMP_DP")
	)
	(segment
		(start 104.692958 -25.285192)
		(end 102.556056 -27.422094)
		(width 0.14605)
		(layer "F.Cu")
		(net "USB_COMP_DP")
	)
	(segment
		(start 114.43208 -44.537122)
		(end 114.81435 -44.537122)
		(width 0.14605)
		(layer "F.Cu")
		(net "USB_COMP_DP")
	)
	(segment
		(start 94.102428 -160.89376)
		(end 93.289628 -160.08096)
		(width 0.14605)
		(layer "F.Cu")
		(net "USB_COMP_DP")
	)
	(segment
		(start 102.264718 -40.78478)
		(end 101.991414 -40.78478)
		(width 0.14605)
		(layer "F.Cu")
		(net "USB_COMP_DP")
	)
	(segment
		(start 102.556056 -27.422094)
		(end 102.556056 -40.493442)
		(width 0.14605)
		(layer "F.Cu")
		(net "USB_COMP_DP")
	)
	(segment
		(start 96.95688 -161.54019)
		(end 96.31045 -160.89376)
		(width 0.14605)
		(layer "F.Cu")
		(net "USB_COMP_DP")
	)
	(segment
		(start 110.835186 -22.265894)
		(end 107.815888 -25.285192)
		(width 0.14605)
		(layer "F.Cu")
		(net "USB_COMP_DP")
	)
	(via
		(at 98.844354 -110.800642)
		(size 0.6096)
		(drill 0.3048)
		(layers "F.Cu" "B.Cu")
		(net "USB_COMP_DP")
	)
	(via
		(at 101.65207 -41.124124)
		(size 0.508)
		(drill 0.254)
		(layers "F.Cu" "B.Cu")
		(net "USB_COMP_DP")
	)
	(via
		(at 96.632522 -162.07867)
		(size 0.508)
		(drill 0.254)
		(layers "F.Cu" "B.Cu")
		(net "USB_COMP_DP")
	)
	(segment
		(start 100.792534 -41.024302)
		(end 100.989638 -40.827198)
		(width 0.14605)
		(layer "B.Cu")
		(net "USB_COMP_DP")
	)
	(segment
		(start 99.30765 -157.54604)
		(end 98.607118 -156.845508)
		(width 0.14605)
		(layer "B.Cu")
		(net "USB_COMP_DP")
	)
	(segment
		(start 97.39376 -163.694618)
		(end 98.586798 -163.694618)
		(width 0.14605)
		(layer "B.Cu")
		(net "USB_COMP_DP")
	)
	(segment
		(start 101.355144 -40.827198)
		(end 101.65207 -41.124124)
		(width 0.14605)
		(layer "B.Cu")
		(net "USB_COMP_DP")
	)
	(segment
		(start 95.230188 -83.454494)
		(end 95.230188 -83.239102)
		(width 0.14605)
		(layer "B.Cu")
		(net "USB_COMP_DP")
	)
	(segment
		(start 100.1014 -139.615164)
		(end 100.1014 -128.872996)
		(width 0.14605)
		(layer "B.Cu")
		(net "USB_COMP_DP")
	)
	(segment
		(start 96.97085 -162.416998)
		(end 96.97085 -163.271708)
		(width 0.14605)
		(layer "B.Cu")
		(net "USB_COMP_DP")
	)
	(segment
		(start 94.704916 -83.764374)
		(end 94.920562 -83.764374)
		(width 0.14605)
		(layer "B.Cu")
		(net "USB_COMP_DP")
	)
	(segment
		(start 100.792534 -42.23258)
		(end 100.792534 -41.024302)
		(width 0.14605)
		(layer "B.Cu")
		(net "USB_COMP_DP")
	)
	(segment
		(start 95.230188 -83.239102)
		(end 95.540068 -82.929222)
		(width 0.14605)
		(layer "B.Cu")
		(net "USB_COMP_DP")
	)
	(segment
		(start 96.900492 -81.78419)
		(end 96.900492 -81.568798)
		(width 0.14605)
		(layer "B.Cu")
		(net "USB_COMP_DP")
	)
	(segment
		(start 96.632522 -162.07867)
		(end 96.97085 -162.416998)
		(width 0.14605)
		(layer "B.Cu")
		(net "USB_COMP_DP")
	)
	(segment
		(start 94.920562 -83.764374)
		(end 95.230188 -83.454494)
		(width 0.14605)
		(layer "B.Cu")
		(net "USB_COMP_DP")
	)
	(segment
		(start 97.181162 -122.761502)
		(end 97.181162 -115.7224)
		(width 0.14605)
		(layer "B.Cu")
		(net "USB_COMP_DP")
	)
	(segment
		(start 97.210372 -81.258918)
		(end 97.426018 -81.258918)
		(width 0.14605)
		(layer "B.Cu")
		(net "USB_COMP_DP")
	)
	(segment
		(start 96.97085 -163.271708)
		(end 97.39376 -163.694618)
		(width 0.14605)
		(layer "B.Cu")
		(net "USB_COMP_DP")
	)
	(segment
		(start 95.755714 -82.929222)
		(end 96.06534 -82.619342)
		(width 0.14605)
		(layer "B.Cu")
		(net "USB_COMP_DP")
	)
	(segment
		(start 91.157552 -88.370664)
		(end 91.157552 -87.311738)
		(width 0.14605)
		(layer "B.Cu")
		(net "USB_COMP_DP")
	)
	(segment
		(start 97.735898 -80.949038)
		(end 97.735898 -80.733392)
		(width 0.14605)
		(layer "B.Cu")
		(net "USB_COMP_DP")
	)
	(segment
		(start 97.426018 -81.258918)
		(end 97.735898 -80.949038)
		(width 0.14605)
		(layer "B.Cu")
		(net "USB_COMP_DP")
	)
	(segment
		(start 98.541332 -93.12021)
		(end 96.15805 -90.736928)
		(width 0.14605)
		(layer "B.Cu")
		(net "USB_COMP_DP")
	)
	(segment
		(start 98.541332 -114.36223)
		(end 98.541332 -110.800642)
		(width 0.14605)
		(layer "B.Cu")
		(net "USB_COMP_DP")
	)
	(segment
		(start 101.3206 -77.14869)
		(end 101.3206 -42.760646)
		(width 0.14605)
		(layer "B.Cu")
		(net "USB_COMP_DP")
	)
	(segment
		(start 100.1014 -128.872996)
		(end 99.47783 -128.249426)
		(width 0.14605)
		(layer "B.Cu")
		(net "USB_COMP_DP")
	)
	(segment
		(start 96.900492 -81.568798)
		(end 97.210372 -81.258918)
		(width 0.14605)
		(layer "B.Cu")
		(net "USB_COMP_DP")
	)
	(segment
		(start 101.3206 -42.760646)
		(end 100.792534 -42.23258)
		(width 0.14605)
		(layer "B.Cu")
		(net "USB_COMP_DP")
	)
	(segment
		(start 97.181162 -115.7224)
		(end 98.541332 -114.36223)
		(width 0.14605)
		(layer "B.Cu")
		(net "USB_COMP_DP")
	)
	(segment
		(start 97.735898 -80.733392)
		(end 101.3206 -77.14869)
		(width 0.14605)
		(layer "B.Cu")
		(net "USB_COMP_DP")
	)
	(segment
		(start 95.540068 -82.929222)
		(end 95.755714 -82.929222)
		(width 0.14605)
		(layer "B.Cu")
		(net "USB_COMP_DP")
	)
	(segment
		(start 96.37522 -82.09407)
		(end 96.590866 -82.09407)
		(width 0.14605)
		(layer "B.Cu")
		(net "USB_COMP_DP")
	)
	(segment
		(start 98.586798 -163.694618)
		(end 99.30765 -162.973766)
		(width 0.14605)
		(layer "B.Cu")
		(net "USB_COMP_DP")
	)
	(segment
		(start 98.607118 -155.11272)
		(end 98.976434 -154.743404)
		(width 0.14605)
		(layer "B.Cu")
		(net "USB_COMP_DP")
	)
	(segment
		(start 98.541332 -110.800642)
		(end 98.844354 -110.800642)
		(width 0.14605)
		(layer "B.Cu")
		(net "USB_COMP_DP")
	)
	(segment
		(start 100.989638 -40.827198)
		(end 101.355144 -40.827198)
		(width 0.14605)
		(layer "B.Cu")
		(net "USB_COMP_DP")
	)
	(segment
		(start 99.30765 -162.973766)
		(end 99.30765 -157.54604)
		(width 0.14605)
		(layer "B.Cu")
		(net "USB_COMP_DP")
	)
	(segment
		(start 99.47783 -125.05817)
		(end 97.181162 -122.761502)
		(width 0.14605)
		(layer "B.Cu")
		(net "USB_COMP_DP")
	)
	(segment
		(start 93.523816 -90.736928)
		(end 91.157552 -88.370664)
		(width 0.14605)
		(layer "B.Cu")
		(net "USB_COMP_DP")
	)
	(segment
		(start 91.157552 -87.311738)
		(end 94.704916 -83.764374)
		(width 0.14605)
		(layer "B.Cu")
		(net "USB_COMP_DP")
	)
	(segment
		(start 99.469448 -146.832574)
		(end 99.469448 -140.247116)
		(width 0.14605)
		(layer "B.Cu")
		(net "USB_COMP_DP")
	)
	(segment
		(start 98.976434 -147.325588)
		(end 99.469448 -146.832574)
		(width 0.14605)
		(layer "B.Cu")
		(net "USB_COMP_DP")
	)
	(segment
		(start 99.47783 -128.249426)
		(end 99.47783 -125.05817)
		(width 0.14605)
		(layer "B.Cu")
		(net "USB_COMP_DP")
	)
	(segment
		(start 99.469448 -140.247116)
		(end 100.1014 -139.615164)
		(width 0.14605)
		(layer "B.Cu")
		(net "USB_COMP_DP")
	)
	(segment
		(start 98.976434 -154.743404)
		(end 98.976434 -147.325588)
		(width 0.14605)
		(layer "B.Cu")
		(net "USB_COMP_DP")
	)
	(segment
		(start 96.06534 -82.40395)
		(end 96.37522 -82.09407)
		(width 0.14605)
		(layer "B.Cu")
		(net "USB_COMP_DP")
	)
	(segment
		(start 98.541332 -110.800642)
		(end 98.541332 -93.12021)
		(width 0.14605)
		(layer "B.Cu")
		(net "USB_COMP_DP")
	)
	(segment
		(start 96.590866 -82.09407)
		(end 96.900492 -81.78419)
		(width 0.14605)
		(layer "B.Cu")
		(net "USB_COMP_DP")
	)
	(segment
		(start 96.06534 -82.619342)
		(end 96.06534 -82.40395)
		(width 0.14605)
		(layer "B.Cu")
		(net "USB_COMP_DP")
	)
	(segment
		(start 98.607118 -156.845508)
		(end 98.607118 -155.11272)
		(width 0.14605)
		(layer "B.Cu")
		(net "USB_COMP_DP")
	)
	(segment
		(start 96.15805 -90.736928)
		(end 93.523816 -90.736928)
		(width 0.14605)
		(layer "B.Cu")
		(net "USB_COMP_DP")
	)
	(segment
		(start 115.297712 -23.14702)
		(end 114.105436 -21.954744)
		(width 0.14605)
		(layer "F.Cu")
		(net "USB_COMP_DN")
	)
	(segment
		(start 107.686856 -24.974042)
		(end 104.563926 -24.974042)
		(width 0.14605)
		(layer "F.Cu")
		(net "USB_COMP_DN")
	)
	(segment
		(start 102.244906 -40.36441)
		(end 102.135686 -40.47363)
		(width 0.14605)
		(layer "F.Cu")
		(net "USB_COMP_DN")
	)
	(segment
		(start 97.576132 -162.07867)
		(end 97.26803 -161.770568)
		(width 0.14605)
		(layer "F.Cu")
		(net "USB_COMP_DN")
	)
	(segment
		(start 93.600778 -159.45612)
		(end 93.751654 -159.305244)
		(width 0.14605)
		(layer "F.Cu")
		(net "USB_COMP_DN")
	)
	(segment
		(start 102.244906 -27.293062)
		(end 102.244906 -40.36441)
		(width 0.14605)
		(layer "F.Cu")
		(net "USB_COMP_DN")
	)
	(segment
		(start 115.297712 -44.493942)
		(end 115.297712 -23.14702)
		(width 0.14605)
		(layer "F.Cu")
		(net "USB_COMP_DN")
	)
	(segment
		(start 96.439482 -160.58261)
		(end 94.23146 -160.58261)
		(width 0.14605)
		(layer "F.Cu")
		(net "USB_COMP_DN")
	)
	(segment
		(start 114.421412 -44.848272)
		(end 114.943382 -44.848272)
		(width 0.14605)
		(layer "F.Cu")
		(net "USB_COMP_DN")
	)
	(segment
		(start 114.105436 -21.954744)
		(end 110.706154 -21.954744)
		(width 0.14605)
		(layer "F.Cu")
		(net "USB_COMP_DN")
	)
	(segment
		(start 97.26803 -161.770568)
		(end 97.26803 -161.411158)
		(width 0.14605)
		(layer "F.Cu")
		(net "USB_COMP_DN")
	)
	(segment
		(start 93.600778 -159.951928)
		(end 93.600778 -159.45612)
		(width 0.14605)
		(layer "F.Cu")
		(net "USB_COMP_DN")
	)
	(segment
		(start 97.26803 -161.411158)
		(end 96.439482 -160.58261)
		(width 0.14605)
		(layer "F.Cu")
		(net "USB_COMP_DN")
	)
	(segment
		(start 102.135686 -40.47363)
		(end 101.940614 -40.47363)
		(width 0.14605)
		(layer "F.Cu")
		(net "USB_COMP_DN")
	)
	(segment
		(start 94.23146 -160.58261)
		(end 93.600778 -159.951928)
		(width 0.14605)
		(layer "F.Cu")
		(net "USB_COMP_DN")
	)
	(segment
		(start 101.940614 -40.47363)
		(end 101.65207 -40.185086)
		(width 0.14605)
		(layer "F.Cu")
		(net "USB_COMP_DN")
	)
	(segment
		(start 93.751654 -159.305244)
		(end 93.751654 -158.47568)
		(width 0.14605)
		(layer "F.Cu")
		(net "USB_COMP_DN")
	)
	(segment
		(start 114.3 -45.39996)
		(end 114.3 -44.969684)
		(width 0.14605)
		(layer "F.Cu")
		(net "USB_COMP_DN")
	)
	(segment
		(start 114.943382 -44.848272)
		(end 115.297712 -44.493942)
		(width 0.14605)
		(layer "F.Cu")
		(net "USB_COMP_DN")
	)
	(segment
		(start 104.563926 -24.974042)
		(end 102.244906 -27.293062)
		(width 0.14605)
		(layer "F.Cu")
		(net "USB_COMP_DN")
	)
	(segment
		(start 114.3 -44.969684)
		(end 114.421412 -44.848272)
		(width 0.14605)
		(layer "F.Cu")
		(net "USB_COMP_DN")
	)
	(segment
		(start 110.706154 -21.954744)
		(end 107.686856 -24.974042)
		(width 0.14605)
		(layer "F.Cu")
		(net "USB_COMP_DN")
	)
	(via
		(at 97.576132 -162.07867)
		(size 0.508)
		(drill 0.254)
		(layers "F.Cu" "B.Cu")
		(net "USB_COMP_DN")
	)
	(via
		(at 101.65207 -40.185086)
		(size 0.508)
		(drill 0.254)
		(layers "F.Cu" "B.Cu")
		(net "USB_COMP_DN")
	)
	(via
		(at 97.960942 -107.925362)
		(size 0.6096)
		(drill 0.3048)
		(layers "F.Cu" "B.Cu")
		(net "USB_COMP_DN")
	)
	(segment
		(start 97.522792 -163.383468)
		(end 98.457766 -163.383468)
		(width 0.14605)
		(layer "B.Cu")
		(net "USB_COMP_DN")
	)
	(segment
		(start 99.79025 -129.002028)
		(end 99.16668 -128.378458)
		(width 0.14605)
		(layer "B.Cu")
		(net "USB_COMP_DN")
	)
	(segment
		(start 98.295968 -156.97454)
		(end 98.295968 -154.983688)
		(width 0.14605)
		(layer "B.Cu")
		(net "USB_COMP_DN")
	)
	(segment
		(start 98.295968 -154.983688)
		(end 98.665284 -154.614372)
		(width 0.14605)
		(layer "B.Cu")
		(net "USB_COMP_DN")
	)
	(segment
		(start 99.79025 -139.486132)
		(end 99.79025 -129.002028)
		(width 0.14605)
		(layer "B.Cu")
		(net "USB_COMP_DN")
	)
	(segment
		(start 100.481384 -40.89527)
		(end 100.860606 -40.516048)
		(width 0.14605)
		(layer "B.Cu")
		(net "USB_COMP_DN")
	)
	(segment
		(start 96.870012 -115.593368)
		(end 98.230182 -114.233198)
		(width 0.14605)
		(layer "B.Cu")
		(net "USB_COMP_DN")
	)
	(segment
		(start 97.282 -163.142676)
		(end 97.522792 -163.383468)
		(width 0.14605)
		(layer "B.Cu")
		(net "USB_COMP_DN")
	)
	(segment
		(start 97.576132 -162.07867)
		(end 97.282 -162.372802)
		(width 0.14605)
		(layer "B.Cu")
		(net "USB_COMP_DN")
	)
	(segment
		(start 93.394784 -91.048078)
		(end 90.846402 -88.499696)
		(width 0.14605)
		(layer "B.Cu")
		(net "USB_COMP_DN")
	)
	(segment
		(start 98.665284 -147.196556)
		(end 99.158298 -146.703542)
		(width 0.14605)
		(layer "B.Cu")
		(net "USB_COMP_DN")
	)
	(segment
		(start 98.9965 -162.844734)
		(end 98.9965 -157.675072)
		(width 0.14605)
		(layer "B.Cu")
		(net "USB_COMP_DN")
	)
	(segment
		(start 99.16668 -128.378458)
		(end 99.16668 -125.187202)
		(width 0.14605)
		(layer "B.Cu")
		(net "USB_COMP_DN")
	)
	(segment
		(start 98.230182 -93.249242)
		(end 96.029018 -91.048078)
		(width 0.14605)
		(layer "B.Cu")
		(net "USB_COMP_DN")
	)
	(segment
		(start 98.230182 -107.925362)
		(end 97.960942 -107.925362)
		(width 0.14605)
		(layer "B.Cu")
		(net "USB_COMP_DN")
	)
	(segment
		(start 97.282 -162.372802)
		(end 97.282 -163.142676)
		(width 0.14605)
		(layer "B.Cu")
		(net "USB_COMP_DN")
	)
	(segment
		(start 96.870012 -122.890534)
		(end 96.870012 -115.593368)
		(width 0.14605)
		(layer "B.Cu")
		(net "USB_COMP_DN")
	)
	(segment
		(start 90.846402 -88.499696)
		(end 90.846402 -87.182706)
		(width 0.14605)
		(layer "B.Cu")
		(net "USB_COMP_DN")
	)
	(segment
		(start 101.00945 -42.889678)
		(end 100.481384 -42.361612)
		(width 0.14605)
		(layer "B.Cu")
		(net "USB_COMP_DN")
	)
	(segment
		(start 99.158298 -140.118084)
		(end 99.79025 -139.486132)
		(width 0.14605)
		(layer "B.Cu")
		(net "USB_COMP_DN")
	)
	(segment
		(start 99.158298 -146.703542)
		(end 99.158298 -140.118084)
		(width 0.14605)
		(layer "B.Cu")
		(net "USB_COMP_DN")
	)
	(segment
		(start 98.9965 -157.675072)
		(end 98.295968 -156.97454)
		(width 0.14605)
		(layer "B.Cu")
		(net "USB_COMP_DN")
	)
	(segment
		(start 99.16668 -125.187202)
		(end 96.870012 -122.890534)
		(width 0.14605)
		(layer "B.Cu")
		(net "USB_COMP_DN")
	)
	(segment
		(start 98.230182 -107.925362)
		(end 98.230182 -93.249242)
		(width 0.14605)
		(layer "B.Cu")
		(net "USB_COMP_DN")
	)
	(segment
		(start 100.481384 -42.361612)
		(end 100.481384 -40.89527)
		(width 0.14605)
		(layer "B.Cu")
		(net "USB_COMP_DN")
	)
	(segment
		(start 101.321108 -40.516048)
		(end 101.65207 -40.185086)
		(width 0.14605)
		(layer "B.Cu")
		(net "USB_COMP_DN")
	)
	(segment
		(start 98.230182 -114.233198)
		(end 98.230182 -107.925362)
		(width 0.14605)
		(layer "B.Cu")
		(net "USB_COMP_DN")
	)
	(segment
		(start 90.846402 -87.182706)
		(end 101.00945 -77.019658)
		(width 0.14605)
		(layer "B.Cu")
		(net "USB_COMP_DN")
	)
	(segment
		(start 96.029018 -91.048078)
		(end 93.394784 -91.048078)
		(width 0.14605)
		(layer "B.Cu")
		(net "USB_COMP_DN")
	)
	(segment
		(start 101.00945 -77.019658)
		(end 101.00945 -42.889678)
		(width 0.14605)
		(layer "B.Cu")
		(net "USB_COMP_DN")
	)
	(segment
		(start 98.457766 -163.383468)
		(end 98.9965 -162.844734)
		(width 0.14605)
		(layer "B.Cu")
		(net "USB_COMP_DN")
	)
	(segment
		(start 100.860606 -40.516048)
		(end 101.321108 -40.516048)
		(width 0.14605)
		(layer "B.Cu")
		(net "USB_COMP_DN")
	)
	(segment
		(start 98.665284 -154.614372)
		(end 98.665284 -147.196556)
		(width 0.14605)
		(layer "B.Cu")
		(net "USB_COMP_DN")
	)
	(via
		(at 93.3958 -174.1043)
		(size 0.508)
		(drill 0.254)
		(layers "F.Cu" "B.Cu")
		(net "UART_COMP_TX")
	)
	(via
		(at 97.63633 -114.074956)
		(size 0.508)
		(drill 0.254)
		(layers "F.Cu" "B.Cu")
		(net "UART_COMP_TX")
	)
	(via
		(at 99.593908 -44.547536)
		(size 0.508)
		(drill 0.254)
		(layers "F.Cu" "B.Cu")
		(net "UART_COMP_TX")
	)
	(via
		(at 92.1766 -173.6852)
		(size 0.6096)
		(drill 0.3048)
		(layers "F.Cu" "B.Cu")
		(net "UART_COMP_TX")
	)
	(segment
		(start 93.3958 -174.1043)
		(end 92.9767 -173.6852)
		(width 0.127)
		(layer "B.Cu")
		(net "UART_COMP_TX")
	)
	(segment
		(start 92.9767 -173.6852)
		(end 92.1766 -173.6852)
		(width 0.127)
		(layer "B.Cu")
		(net "UART_COMP_TX")
	)
	(segment
		(start 91.11234 -174.36846)
		(end 88.53424 -174.36846)
		(width 0.127)
		(layer "B.Cu")
		(net "UART_COMP_TX")
	)
	(segment
		(start 88.53424 -174.36846)
		(end 88.2777 -174.625)
		(width 0.127)
		(layer "B.Cu")
		(net "UART_COMP_TX")
	)
	(segment
		(start 91.7956 -173.6852)
		(end 91.11234 -174.36846)
		(width 0.127)
		(layer "B.Cu")
		(net "UART_COMP_TX")
	)
	(segment
		(start 92.1766 -173.6852)
		(end 91.7956 -173.6852)
		(width 0.127)
		(layer "B.Cu")
		(net "UART_COMP_TX")
	)
	(segment
		(start 97.76841 -173.5709)
		(end 97.76841 -164.280596)
		(width 0.127)
		(layer "In2.Cu")
		(net "UART_COMP_TX")
	)
	(segment
		(start 98.2472 -156.39161)
		(end 98.2472 -155.324302)
		(width 0.127)
		(layer "In2.Cu")
		(net "UART_COMP_TX")
	)
	(segment
		(start 94.008194 -174.526194)
		(end 96.813116 -174.526194)
		(width 0.127)
		(layer "In2.Cu")
		(net "UART_COMP_TX")
	)
	(segment
		(start 96.8121 -142.143226)
		(end 96.931988 -142.023338)
		(width 0.127)
		(layer "In2.Cu")
		(net "UART_COMP_TX")
	)
	(segment
		(start 102.905814 -30.99435)
		(end 102.905814 -38.04031)
		(width 0.127)
		(layer "In2.Cu")
		(net "UART_COMP_TX")
	)
	(segment
		(start 96.832166 -129.879852)
		(end 96.832166 -121.349516)
		(width 0.127)
		(layer "In2.Cu")
		(net "UART_COMP_TX")
	)
	(segment
		(start 115.506754 -38.606984)
		(end 115.506754 -30.76321)
		(width 0.127)
		(layer "In2.Cu")
		(net "UART_COMP_TX")
	)
	(segment
		(start 99.593908 -44.390564)
		(end 99.593908 -44.547536)
		(width 0.127)
		(layer "In2.Cu")
		(net "UART_COMP_TX")
	)
	(segment
		(start 98.465894 -155.105608)
		(end 98.465894 -150.407116)
		(width 0.127)
		(layer "In2.Cu")
		(net "UART_COMP_TX")
	)
	(segment
		(start 97.082864 -131.809998)
		(end 97.536 -131.356862)
		(width 0.127)
		(layer "In2.Cu")
		(net "UART_COMP_TX")
	)
	(segment
		(start 102.905814 -38.04031)
		(end 102.124764 -38.82136)
		(width 0.127)
		(layer "In2.Cu")
		(net "UART_COMP_TX")
	)
	(segment
		(start 97.76841 -164.280596)
		(end 98.556318 -163.492688)
		(width 0.127)
		(layer "In2.Cu")
		(net "UART_COMP_TX")
	)
	(segment
		(start 101.18217 -39.108888)
		(end 101.18217 -42.802302)
		(width 0.127)
		(layer "In2.Cu")
		(net "UART_COMP_TX")
	)
	(segment
		(start 98.556318 -163.492688)
		(end 98.556318 -156.700728)
		(width 0.127)
		(layer "In2.Cu")
		(net "UART_COMP_TX")
	)
	(segment
		(start 97.028 -118.380256)
		(end 97.504504 -117.903752)
		(width 0.127)
		(layer "In2.Cu")
		(net "UART_COMP_TX")
	)
	(segment
		(start 101.469698 -38.82136)
		(end 101.18217 -39.108888)
		(width 0.127)
		(layer "In2.Cu")
		(net "UART_COMP_TX")
	)
	(segment
		(start 98.453702 -149.996652)
		(end 96.8121 -148.35505)
		(width 0.127)
		(layer "In2.Cu")
		(net "UART_COMP_TX")
	)
	(segment
		(start 98.556318 -156.700728)
		(end 98.2472 -156.39161)
		(width 0.127)
		(layer "In2.Cu")
		(net "UART_COMP_TX")
	)
	(segment
		(start 102.124764 -38.82136)
		(end 101.469698 -38.82136)
		(width 0.127)
		(layer "In2.Cu")
		(net "UART_COMP_TX")
	)
	(segment
		(start 112.65916 -27.915616)
		(end 105.984548 -27.915616)
		(width 0.127)
		(layer "In2.Cu")
		(net "UART_COMP_TX")
	)
	(segment
		(start 97.536 -130.583686)
		(end 96.832166 -129.879852)
		(width 0.127)
		(layer "In2.Cu")
		(net "UART_COMP_TX")
	)
	(segment
		(start 115.506754 -30.76321)
		(end 112.65916 -27.915616)
		(width 0.127)
		(layer "In2.Cu")
		(net "UART_COMP_TX")
	)
	(segment
		(start 98.465894 -150.407116)
		(end 98.453702 -150.394924)
		(width 0.127)
		(layer "In2.Cu")
		(net "UART_COMP_TX")
	)
	(segment
		(start 116.099844 -39.200074)
		(end 115.506754 -38.606984)
		(width 0.127)
		(layer "In2.Cu")
		(net "UART_COMP_TX")
	)
	(segment
		(start 97.646744 -135.147812)
		(end 97.082864 -134.583932)
		(width 0.127)
		(layer "In2.Cu")
		(net "UART_COMP_TX")
	)
	(segment
		(start 96.931988 -142.023338)
		(end 96.931988 -138.950192)
		(width 0.127)
		(layer "In2.Cu")
		(net "UART_COMP_TX")
	)
	(segment
		(start 96.832166 -121.349516)
		(end 97.028 -121.153682)
		(width 0.127)
		(layer "In2.Cu")
		(net "UART_COMP_TX")
	)
	(segment
		(start 98.0186 -135.519414)
		(end 97.646998 -135.147812)
		(width 0.127)
		(layer "In2.Cu")
		(net "UART_COMP_TX")
	)
	(segment
		(start 96.813116 -174.526194)
		(end 97.76841 -173.5709)
		(width 0.127)
		(layer "In2.Cu")
		(net "UART_COMP_TX")
	)
	(segment
		(start 93.5863 -174.1043)
		(end 94.008194 -174.526194)
		(width 0.127)
		(layer "In2.Cu")
		(net "UART_COMP_TX")
	)
	(segment
		(start 93.3958 -174.1043)
		(end 93.5863 -174.1043)
		(width 0.127)
		(layer "In2.Cu")
		(net "UART_COMP_TX")
	)
	(segment
		(start 98.0186 -137.86358)
		(end 98.0186 -135.519414)
		(width 0.127)
		(layer "In2.Cu")
		(net "UART_COMP_TX")
	)
	(segment
		(start 97.504504 -114.206782)
		(end 97.63633 -114.074956)
		(width 0.127)
		(layer "In2.Cu")
		(net "UART_COMP_TX")
	)
	(segment
		(start 96.931988 -138.950192)
		(end 98.0186 -137.86358)
		(width 0.127)
		(layer "In2.Cu")
		(net "UART_COMP_TX")
	)
	(segment
		(start 97.646998 -135.147812)
		(end 97.646744 -135.147812)
		(width 0.127)
		(layer "In2.Cu")
		(net "UART_COMP_TX")
	)
	(segment
		(start 101.18217 -42.802302)
		(end 99.593908 -44.390564)
		(width 0.127)
		(layer "In2.Cu")
		(net "UART_COMP_TX")
	)
	(segment
		(start 98.2472 -155.324302)
		(end 98.465894 -155.105608)
		(width 0.127)
		(layer "In2.Cu")
		(net "UART_COMP_TX")
	)
	(segment
		(start 97.028 -121.153682)
		(end 97.028 -118.380256)
		(width 0.127)
		(layer "In2.Cu")
		(net "UART_COMP_TX")
	)
	(segment
		(start 97.536 -131.356862)
		(end 97.536 -130.583686)
		(width 0.127)
		(layer "In2.Cu")
		(net "UART_COMP_TX")
	)
	(segment
		(start 105.984548 -27.915616)
		(end 102.905814 -30.99435)
		(width 0.127)
		(layer "In2.Cu")
		(net "UART_COMP_TX")
	)
	(segment
		(start 96.8121 -148.35505)
		(end 96.8121 -142.143226)
		(width 0.127)
		(layer "In2.Cu")
		(net "UART_COMP_TX")
	)
	(segment
		(start 97.504504 -117.903752)
		(end 97.504504 -114.206782)
		(width 0.127)
		(layer "In2.Cu")
		(net "UART_COMP_TX")
	)
	(segment
		(start 97.082864 -134.583932)
		(end 97.082864 -131.809998)
		(width 0.127)
		(layer "In2.Cu")
		(net "UART_COMP_TX")
	)
	(segment
		(start 98.453702 -150.394924)
		(end 98.453702 -149.996652)
		(width 0.127)
		(layer "In2.Cu")
		(net "UART_COMP_TX")
	)
	(segment
		(start 92.736162 -90.5002)
		(end 93.234764 -90.001598)
		(width 0.127)
		(layer "In5.Cu")
		(net "UART_COMP_TX")
	)
	(segment
		(start 97.63633 -100.55733)
		(end 92.736162 -95.657162)
		(width 0.127)
		(layer "In5.Cu")
		(net "UART_COMP_TX")
	)
	(segment
		(start 93.234764 -90.001598)
		(end 93.234764 -85.614764)
		(width 0.127)
		(layer "In5.Cu")
		(net "UART_COMP_TX")
	)
	(segment
		(start 93.234764 -85.614764)
		(end 99.019106 -79.830422)
		(width 0.127)
		(layer "In5.Cu")
		(net "UART_COMP_TX")
	)
	(segment
		(start 97.63633 -114.074956)
		(end 97.63633 -100.55733)
		(width 0.127)
		(layer "In5.Cu")
		(net "UART_COMP_TX")
	)
	(segment
		(start 99.019106 -79.830422)
		(end 99.019106 -45.122338)
		(width 0.127)
		(layer "In5.Cu")
		(net "UART_COMP_TX")
	)
	(segment
		(start 92.736162 -95.657162)
		(end 92.736162 -90.5002)
		(width 0.127)
		(layer "In5.Cu")
		(net "UART_COMP_TX")
	)
	(segment
		(start 99.019106 -45.122338)
		(end 99.593908 -44.547536)
		(width 0.127)
		(layer "In5.Cu")
		(net "UART_COMP_TX")
	)
	(segment
		(start 98.413062 -130.169412)
		(end 98.782632 -130.538982)
		(width 0.127)
		(layer "F.Cu")
		(net "UART_COMP_RX")
	)
	(segment
		(start 98.782632 -135.12419)
		(end 99.154234 -135.495792)
		(width 0.127)
		(layer "F.Cu")
		(net "UART_COMP_RX")
	)
	(segment
		(start 97.220786 -126.254764)
		(end 98.22942 -127.263398)
		(width 0.127)
		(layer "F.Cu")
		(net "UART_COMP_RX")
	)
	(segment
		(start 98.229166 -127.789432)
		(end 98.229166 -129.98577)
		(width 0.127)
		(layer "F.Cu")
		(net "UART_COMP_RX")
	)
	(segment
		(start 97.220786 -121.289318)
		(end 97.220786 -126.254764)
		(width 0.127)
		(layer "F.Cu")
		(net "UART_COMP_RX")
	)
	(segment
		(start 97.936304 -120.5738)
		(end 97.220786 -121.289318)
		(width 0.127)
		(layer "F.Cu")
		(net "UART_COMP_RX")
	)
	(segment
		(start 99.3521 -135.693404)
		(end 99.3521 -138.998452)
		(width 0.127)
		(layer "F.Cu")
		(net "UART_COMP_RX")
	)
	(segment
		(start 99.154234 -135.495792)
		(end 99.154488 -135.495792)
		(width 0.127)
		(layer "F.Cu")
		(net "UART_COMP_RX")
	)
	(segment
		(start 99.154488 -135.495792)
		(end 99.3521 -135.693404)
		(width 0.127)
		(layer "F.Cu")
		(net "UART_COMP_RX")
	)
	(segment
		(start 98.782632 -130.538982)
		(end 98.782632 -135.12419)
		(width 0.127)
		(layer "F.Cu")
		(net "UART_COMP_RX")
	)
	(segment
		(start 98.22942 -127.789178)
		(end 98.229166 -127.789432)
		(width 0.127)
		(layer "F.Cu")
		(net "UART_COMP_RX")
	)
	(segment
		(start 98.137218 -120.5738)
		(end 97.936304 -120.5738)
		(width 0.127)
		(layer "F.Cu")
		(net "UART_COMP_RX")
	)
	(segment
		(start 98.412808 -130.169412)
		(end 98.413062 -130.169412)
		(width 0.127)
		(layer "F.Cu")
		(net "UART_COMP_RX")
	)
	(segment
		(start 98.229166 -129.98577)
		(end 98.412808 -130.169412)
		(width 0.127)
		(layer "F.Cu")
		(net "UART_COMP_RX")
	)
	(segment
		(start 98.22942 -127.263398)
		(end 98.22942 -127.789178)
		(width 0.127)
		(layer "F.Cu")
		(net "UART_COMP_RX")
	)
	(segment
		(start 99.3521 -138.998452)
		(end 98.714814 -139.635738)
		(width 0.127)
		(layer "F.Cu")
		(net "UART_COMP_RX")
	)
	(via
		(at 98.556318 -167.790876)
		(size 0.6096)
		(drill 0.3048)
		(layers "F.Cu" "B.Cu")
		(net "UART_COMP_RX")
	)
	(via
		(at 98.714814 -139.635738)
		(size 0.508)
		(drill 0.254)
		(layers "F.Cu" "B.Cu")
		(net "UART_COMP_RX")
	)
	(via
		(at 102.800658 -41.183814)
		(size 0.508)
		(drill 0.254)
		(layers "F.Cu" "B.Cu")
		(net "UART_COMP_RX")
	)
	(via
		(at 99.059746 -168.833038)
		(size 0.508)
		(drill 0.254)
		(layers "F.Cu" "B.Cu")
		(net "UART_COMP_RX")
	)
	(via
		(at 98.137218 -120.5738)
		(size 0.508)
		(drill 0.254)
		(layers "F.Cu" "B.Cu")
		(net "UART_COMP_RX")
	)
	(segment
		(start 99.059746 -168.833038)
		(end 99.059746 -168.294304)
		(width 0.127)
		(layer "B.Cu")
		(net "UART_COMP_RX")
	)
	(segment
		(start 92.9513 -168.7068)
		(end 94.615254 -168.7068)
		(width 0.127)
		(layer "B.Cu")
		(net "UART_COMP_RX")
	)
	(segment
		(start 94.615254 -168.7068)
		(end 95.531178 -167.790876)
		(width 0.127)
		(layer "B.Cu")
		(net "UART_COMP_RX")
	)
	(segment
		(start 95.531178 -167.790876)
		(end 98.556318 -167.790876)
		(width 0.127)
		(layer "B.Cu")
		(net "UART_COMP_RX")
	)
	(segment
		(start 99.059746 -168.294304)
		(end 98.556318 -167.790876)
		(width 0.127)
		(layer "B.Cu")
		(net "UART_COMP_RX")
	)
	(segment
		(start 103.5558 -40.428672)
		(end 103.5558 -31.242508)
		(width 0.127)
		(layer "In2.Cu")
		(net "UART_COMP_RX")
	)
	(segment
		(start 98.8822 -155.587446)
		(end 99.100894 -155.368752)
		(width 0.127)
		(layer "In2.Cu")
		(net "UART_COMP_RX")
	)
	(segment
		(start 99.191318 -156.43733)
		(end 98.8822 -156.128212)
		(width 0.127)
		(layer "In2.Cu")
		(net "UART_COMP_RX")
	)
	(segment
		(start 98.686366 -164.260784)
		(end 99.191318 -163.755832)
		(width 0.127)
		(layer "In2.Cu")
		(net "UART_COMP_RX")
	)
	(segment
		(start 98.279458 -140.071094)
		(end 98.714814 -139.635738)
		(width 0.127)
		(layer "In2.Cu")
		(net "UART_COMP_RX")
	)
	(segment
		(start 97.60458 -148.249386)
		(end 97.60458 -147.332954)
		(width 0.127)
		(layer "In2.Cu")
		(net "UART_COMP_RX")
	)
	(segment
		(start 114.8715 -31.026354)
		(end 114.8715 -39.371778)
		(width 0.127)
		(layer "In2.Cu")
		(net "UART_COMP_RX")
	)
	(segment
		(start 99.191318 -163.755832)
		(end 99.191318 -156.43733)
		(width 0.127)
		(layer "In2.Cu")
		(net "UART_COMP_RX")
	)
	(segment
		(start 99.058222 -167.778684)
		(end 99.057968 -167.778684)
		(width 0.127)
		(layer "In2.Cu")
		(net "UART_COMP_RX")
	)
	(segment
		(start 97.801938 -147.135596)
		(end 97.801938 -143.006064)
		(width 0.127)
		(layer "In2.Cu")
		(net "UART_COMP_RX")
	)
	(segment
		(start 99.100894 -149.7457)
		(end 97.60458 -148.249386)
		(width 0.127)
		(layer "In2.Cu")
		(net "UART_COMP_RX")
	)
	(segment
		(start 102.800658 -41.183814)
		(end 103.5558 -40.428672)
		(width 0.127)
		(layer "In2.Cu")
		(net "UART_COMP_RX")
	)
	(segment
		(start 98.279458 -142.528544)
		(end 98.279458 -140.071094)
		(width 0.127)
		(layer "In2.Cu")
		(net "UART_COMP_RX")
	)
	(segment
		(start 112.396016 -28.550616)
		(end 112.767618 -28.922218)
		(width 0.127)
		(layer "In2.Cu")
		(net "UART_COMP_RX")
	)
	(segment
		(start 97.60458 -147.332954)
		(end 97.801938 -147.135596)
		(width 0.127)
		(layer "In2.Cu")
		(net "UART_COMP_RX")
	)
	(segment
		(start 98.686366 -167.407082)
		(end 98.686366 -164.260784)
		(width 0.127)
		(layer "In2.Cu")
		(net "UART_COMP_RX")
	)
	(segment
		(start 112.767618 -28.922472)
		(end 114.8715 -31.026354)
		(width 0.127)
		(layer "In2.Cu")
		(net "UART_COMP_RX")
	)
	(segment
		(start 98.8822 -156.128212)
		(end 98.8822 -155.587446)
		(width 0.127)
		(layer "In2.Cu")
		(net "UART_COMP_RX")
	)
	(segment
		(start 106.247692 -28.550616)
		(end 112.396016 -28.550616)
		(width 0.127)
		(layer "In2.Cu")
		(net "UART_COMP_RX")
	)
	(segment
		(start 112.767618 -28.922218)
		(end 112.767618 -28.922472)
		(width 0.127)
		(layer "In2.Cu")
		(net "UART_COMP_RX")
	)
	(segment
		(start 99.057968 -167.778684)
		(end 98.686366 -167.407082)
		(width 0.127)
		(layer "In2.Cu")
		(net "UART_COMP_RX")
	)
	(segment
		(start 99.100894 -155.368752)
		(end 99.100894 -149.7457)
		(width 0.127)
		(layer "In2.Cu")
		(net "UART_COMP_RX")
	)
	(segment
		(start 114.8715 -39.371778)
		(end 116.099844 -40.600122)
		(width 0.127)
		(layer "In2.Cu")
		(net "UART_COMP_RX")
	)
	(segment
		(start 99.059746 -167.780208)
		(end 99.058222 -167.778684)
		(width 0.127)
		(layer "In2.Cu")
		(net "UART_COMP_RX")
	)
	(segment
		(start 97.801938 -143.006064)
		(end 98.279458 -142.528544)
		(width 0.127)
		(layer "In2.Cu")
		(net "UART_COMP_RX")
	)
	(segment
		(start 103.5558 -31.242508)
		(end 106.247692 -28.550616)
		(width 0.127)
		(layer "In2.Cu")
		(net "UART_COMP_RX")
	)
	(segment
		(start 99.059746 -168.833038)
		(end 99.059746 -167.780208)
		(width 0.127)
		(layer "In2.Cu")
		(net "UART_COMP_RX")
	)
	(segment
		(start 99.723956 -85.596984)
		(end 99.723956 -91.041728)
		(width 0.127)
		(layer "In5.Cu")
		(net "UART_COMP_RX")
	)
	(segment
		(start 101.077776 -117.954552)
		(end 98.458528 -120.5738)
		(width 0.127)
		(layer "In5.Cu")
		(net "UART_COMP_RX")
	)
	(segment
		(start 101.077776 -92.395548)
		(end 101.077776 -117.954552)
		(width 0.127)
		(layer "In5.Cu")
		(net "UART_COMP_RX")
	)
	(segment
		(start 101.305106 -84.015834)
		(end 99.723956 -85.596984)
		(width 0.127)
		(layer "In5.Cu")
		(net "UART_COMP_RX")
	)
	(segment
		(start 101.305106 -46.881034)
		(end 101.305106 -84.015834)
		(width 0.127)
		(layer "In5.Cu")
		(net "UART_COMP_RX")
	)
	(segment
		(start 99.723956 -91.041728)
		(end 101.077776 -92.395548)
		(width 0.127)
		(layer "In5.Cu")
		(net "UART_COMP_RX")
	)
	(segment
		(start 102.800658 -45.385482)
		(end 101.305106 -46.881034)
		(width 0.127)
		(layer "In5.Cu")
		(net "UART_COMP_RX")
	)
	(segment
		(start 102.800658 -41.183814)
		(end 102.800658 -45.385482)
		(width 0.127)
		(layer "In5.Cu")
		(net "UART_COMP_RX")
	)
	(segment
		(start 98.458528 -120.5738)
		(end 98.137218 -120.5738)
		(width 0.127)
		(layer "In5.Cu")
		(net "UART_COMP_RX")
	)
	(via
		(at 87.0204 -173.4312)
		(size 0.6096)
		(drill 0.3048)
		(layers "F.Cu" "B.Cu")
		(net "UART_COMP_R_TX")
	)
	(segment
		(start 87.0204 -173.4312)
		(end 87.677752 -172.773848)
		(width 0.127)
		(layer "B.Cu")
		(net "UART_COMP_R_TX")
	)
	(segment
		(start 87.5665 -171.1579)
		(end 87.72652 -170.99788)
		(width 0.127)
		(layer "B.Cu")
		(net "UART_COMP_R_TX")
	)
	(segment
		(start 87.0204 -173.4312)
		(end 87.0204 -174.2567)
		(width 0.127)
		(layer "B.Cu")
		(net "UART_COMP_R_TX")
	)
	(segment
		(start 87.72652 -170.99788)
		(end 88.519 -170.99788)
		(width 0.127)
		(layer "B.Cu")
		(net "UART_COMP_R_TX")
	)
	(segment
		(start 87.677752 -172.773848)
		(end 87.677752 -172.331126)
		(width 0.127)
		(layer "B.Cu")
		(net "UART_COMP_R_TX")
	)
	(segment
		(start 87.677752 -172.331126)
		(end 87.5665 -172.219874)
		(width 0.127)
		(layer "B.Cu")
		(net "UART_COMP_R_TX")
	)
	(segment
		(start 87.5665 -172.219874)
		(end 87.5665 -171.1579)
		(width 0.127)
		(layer "B.Cu")
		(net "UART_COMP_R_TX")
	)
	(segment
		(start 87.0204 -174.2567)
		(end 87.3887 -174.625)
		(width 0.127)
		(layer "B.Cu")
		(net "UART_COMP_R_TX")
	)
	(segment
		(start 88.519 -168.39692)
		(end 90.0176 -168.39692)
		(width 0.127)
		(layer "B.Cu")
		(net "UART_COMP_R_RX")
	)
	(segment
		(start 90.32748 -168.7068)
		(end 92.0623 -168.7068)
		(width 0.127)
		(layer "B.Cu")
		(net "UART_COMP_R_RX")
	)
	(segment
		(start 90.0176 -168.39692)
		(end 90.32748 -168.7068)
		(width 0.127)
		(layer "B.Cu")
		(net "UART_COMP_R_RX")
	)
	(segment
		(start 38.395148 -159.9692)
		(end 38.4937 -159.9692)
		(width 0.127)
		(layer "F.Cu")
		(net "UART_COMP_OUT_TX")
	)
	(segment
		(start 93.733874 -135.088122)
		(end 93.733874 -137.777474)
		(width 0.127)
		(layer "F.Cu")
		(net "UART_COMP_OUT_TX")
	)
	(segment
		(start 94.714568 -130.007106)
		(end 94.19717 -130.524504)
		(width 0.127)
		(layer "F.Cu")
		(net "UART_COMP_OUT_TX")
	)
	(segment
		(start 93.733874 -137.777474)
		(end 93.853 -137.8966)
		(width 0.127)
		(layer "F.Cu")
		(net "UART_COMP_OUT_TX")
	)
	(segment
		(start 39.0398 -159.078676)
		(end 38.6715 -159.446976)
		(width 0.127)
		(layer "F.Cu")
		(net "UART_COMP_OUT_TX")
	)
	(segment
		(start 94.19717 -134.624826)
		(end 93.733874 -135.088122)
		(width 0.127)
		(layer "F.Cu")
		(net "UART_COMP_OUT_TX")
	)
	(segment
		(start 37.5412 -160.823148)
		(end 38.395148 -159.9692)
		(width 0.127)
		(layer "F.Cu")
		(net "UART_COMP_OUT_TX")
	)
	(segment
		(start 39.0398 -159.0675)
		(end 39.0398 -159.078676)
		(width 0.127)
		(layer "F.Cu")
		(net "UART_COMP_OUT_TX")
	)
	(segment
		(start 95.945706 -130.007106)
		(end 94.714568 -130.007106)
		(width 0.127)
		(layer "F.Cu")
		(net "UART_COMP_OUT_TX")
	)
	(segment
		(start 38.6715 -159.446976)
		(end 38.6715 -159.7914)
		(width 0.127)
		(layer "F.Cu")
		(net "UART_COMP_OUT_TX")
	)
	(segment
		(start 94.19717 -130.524504)
		(end 94.19717 -134.624826)
		(width 0.127)
		(layer "F.Cu")
		(net "UART_COMP_OUT_TX")
	)
	(segment
		(start 37.5412 -160.9979)
		(end 37.5412 -160.823148)
		(width 0.127)
		(layer "F.Cu")
		(net "UART_COMP_OUT_TX")
	)
	(segment
		(start 38.6715 -159.7914)
		(end 38.4937 -159.9692)
		(width 0.127)
		(layer "F.Cu")
		(net "UART_COMP_OUT_TX")
	)
	(via
		(at 38.4937 -159.9692)
		(size 0.508)
		(drill 0.254)
		(layers "F.Cu" "B.Cu")
		(net "UART_COMP_OUT_TX")
	)
	(via
		(at 93.853 -137.8966)
		(size 0.508)
		(drill 0.254)
		(layers "F.Cu" "B.Cu")
		(net "UART_COMP_OUT_TX")
	)
	(via
		(at 87.1728 -169.5704)
		(size 0.508)
		(drill 0.254)
		(layers "F.Cu" "B.Cu")
		(net "UART_COMP_OUT_TX")
	)
	(segment
		(start 87.95004 -170.34764)
		(end 88.519 -170.34764)
		(width 0.127)
		(layer "B.Cu")
		(net "UART_COMP_OUT_TX")
	)
	(segment
		(start 87.1728 -169.5704)
		(end 87.95004 -170.34764)
		(width 0.127)
		(layer "B.Cu")
		(net "UART_COMP_OUT_TX")
	)
	(segment
		(start 88.2396 -168.5036)
		(end 88.2396 -166.836344)
		(width 0.127)
		(layer "In2.Cu")
		(net "UART_COMP_OUT_TX")
	)
	(segment
		(start 92.52966 -144.526)
		(end 92.52966 -142.11427)
		(width 0.127)
		(layer "In2.Cu")
		(net "UART_COMP_OUT_TX")
	)
	(segment
		(start 92.640404 -158.647384)
		(end 93.721682 -157.566106)
		(width 0.127)
		(layer "In2.Cu")
		(net "UART_COMP_OUT_TX")
	)
	(segment
		(start 89.07145 -163.73475)
		(end 89.07145 -163.141914)
		(width 0.127)
		(layer "In2.Cu")
		(net "UART_COMP_OUT_TX")
	)
	(segment
		(start 92.52966 -142.11427)
		(end 93.343222 -141.300708)
		(width 0.127)
		(layer "In2.Cu")
		(net "UART_COMP_OUT_TX")
	)
	(segment
		(start 92.5195 -147.648422)
		(end 92.5195 -144.53616)
		(width 0.127)
		(layer "In2.Cu")
		(net "UART_COMP_OUT_TX")
	)
	(segment
		(start 87.1728 -169.5704)
		(end 88.2396 -168.5036)
		(width 0.127)
		(layer "In2.Cu")
		(net "UART_COMP_OUT_TX")
	)
	(segment
		(start 93.414088 -150.931118)
		(end 92.192094 -149.709124)
		(width 0.127)
		(layer "In2.Cu")
		(net "UART_COMP_OUT_TX")
	)
	(segment
		(start 89.2683 -162.448494)
		(end 91.006168 -160.710626)
		(width 0.127)
		(layer "In2.Cu")
		(net "UART_COMP_OUT_TX")
	)
	(segment
		(start 92.640404 -159.872172)
		(end 92.640404 -158.647384)
		(width 0.127)
		(layer "In2.Cu")
		(net "UART_COMP_OUT_TX")
	)
	(segment
		(start 93.721682 -157.566106)
		(end 93.721682 -151.2062)
		(width 0.127)
		(layer "In2.Cu")
		(net "UART_COMP_OUT_TX")
	)
	(segment
		(start 92.192094 -147.975828)
		(end 92.5195 -147.648422)
		(width 0.127)
		(layer "In2.Cu")
		(net "UART_COMP_OUT_TX")
	)
	(segment
		(start 88.2396 -166.836344)
		(end 88.4936 -166.582344)
		(width 0.127)
		(layer "In2.Cu")
		(net "UART_COMP_OUT_TX")
	)
	(segment
		(start 89.07145 -163.141914)
		(end 89.2683 -162.945064)
		(width 0.127)
		(layer "In2.Cu")
		(net "UART_COMP_OUT_TX")
	)
	(segment
		(start 91.80195 -160.710626)
		(end 92.640404 -159.872172)
		(width 0.127)
		(layer "In2.Cu")
		(net "UART_COMP_OUT_TX")
	)
	(segment
		(start 91.006168 -160.710626)
		(end 91.80195 -160.710626)
		(width 0.127)
		(layer "In2.Cu")
		(net "UART_COMP_OUT_TX")
	)
	(segment
		(start 88.4936 -164.3126)
		(end 89.07145 -163.73475)
		(width 0.127)
		(layer "In2.Cu")
		(net "UART_COMP_OUT_TX")
	)
	(segment
		(start 93.721682 -151.2062)
		(end 93.4466 -150.931118)
		(width 0.127)
		(layer "In2.Cu")
		(net "UART_COMP_OUT_TX")
	)
	(segment
		(start 88.4936 -166.582344)
		(end 88.4936 -164.3126)
		(width 0.127)
		(layer "In2.Cu")
		(net "UART_COMP_OUT_TX")
	)
	(segment
		(start 92.5195 -144.53616)
		(end 92.52966 -144.526)
		(width 0.127)
		(layer "In2.Cu")
		(net "UART_COMP_OUT_TX")
	)
	(segment
		(start 93.343222 -138.406378)
		(end 93.853 -137.8966)
		(width 0.127)
		(layer "In2.Cu")
		(net "UART_COMP_OUT_TX")
	)
	(segment
		(start 93.343222 -141.300708)
		(end 93.343222 -138.406378)
		(width 0.127)
		(layer "In2.Cu")
		(net "UART_COMP_OUT_TX")
	)
	(segment
		(start 93.4466 -150.931118)
		(end 93.414088 -150.931118)
		(width 0.127)
		(layer "In2.Cu")
		(net "UART_COMP_OUT_TX")
	)
	(segment
		(start 92.192094 -149.709124)
		(end 92.192094 -147.975828)
		(width 0.127)
		(layer "In2.Cu")
		(net "UART_COMP_OUT_TX")
	)
	(segment
		(start 89.2683 -162.945064)
		(end 89.2683 -162.448494)
		(width 0.127)
		(layer "In2.Cu")
		(net "UART_COMP_OUT_TX")
	)
	(segment
		(start 42.0624 -159.9692)
		(end 43.024044 -160.930844)
		(width 0.127)
		(layer "In5.Cu")
		(net "UART_COMP_OUT_TX")
	)
	(segment
		(start 84.318348 -170.781472)
		(end 84.656676 -171.1198)
		(width 0.127)
		(layer "In5.Cu")
		(net "UART_COMP_OUT_TX")
	)
	(segment
		(start 57.983628 -169.3418)
		(end 64.753236 -169.3418)
		(width 0.127)
		(layer "In5.Cu")
		(net "UART_COMP_OUT_TX")
	)
	(segment
		(start 74.460608 -171.9453)
		(end 79.1337 -171.9453)
		(width 0.127)
		(layer "In5.Cu")
		(net "UART_COMP_OUT_TX")
	)
	(segment
		(start 53.912008 -165.6207)
		(end 55.055008 -166.7637)
		(width 0.127)
		(layer "In5.Cu")
		(net "UART_COMP_OUT_TX")
	)
	(segment
		(start 47.60214 -163.501832)
		(end 49.721008 -165.6207)
		(width 0.127)
		(layer "In5.Cu")
		(net "UART_COMP_OUT_TX")
	)
	(segment
		(start 46.922944 -161.86658)
		(end 47.21098 -161.86658)
		(width 0.127)
		(layer "In5.Cu")
		(net "UART_COMP_OUT_TX")
	)
	(segment
		(start 82.316828 -170.781472)
		(end 84.318348 -170.781472)
		(width 0.127)
		(layer "In5.Cu")
		(net "UART_COMP_OUT_TX")
	)
	(segment
		(start 72.847454 -170.332146)
		(end 74.460608 -171.9453)
		(width 0.127)
		(layer "In5.Cu")
		(net "UART_COMP_OUT_TX")
	)
	(segment
		(start 55.055008 -166.7637)
		(end 55.405528 -166.7637)
		(width 0.127)
		(layer "In5.Cu")
		(net "UART_COMP_OUT_TX")
	)
	(segment
		(start 45.987208 -160.930844)
		(end 46.922944 -161.86658)
		(width 0.127)
		(layer "In5.Cu")
		(net "UART_COMP_OUT_TX")
	)
	(segment
		(start 47.21098 -161.86658)
		(end 47.60214 -162.25774)
		(width 0.127)
		(layer "In5.Cu")
		(net "UART_COMP_OUT_TX")
	)
	(segment
		(start 49.721008 -165.6207)
		(end 53.912008 -165.6207)
		(width 0.127)
		(layer "In5.Cu")
		(net "UART_COMP_OUT_TX")
	)
	(segment
		(start 84.656676 -171.1198)
		(end 85.6234 -171.1198)
		(width 0.127)
		(layer "In5.Cu")
		(net "UART_COMP_OUT_TX")
	)
	(segment
		(start 47.60214 -162.25774)
		(end 47.60214 -163.501832)
		(width 0.127)
		(layer "In5.Cu")
		(net "UART_COMP_OUT_TX")
	)
	(segment
		(start 85.6234 -171.1198)
		(end 87.1728 -169.5704)
		(width 0.127)
		(layer "In5.Cu")
		(net "UART_COMP_OUT_TX")
	)
	(segment
		(start 64.753236 -169.3418)
		(end 65.743582 -170.332146)
		(width 0.127)
		(layer "In5.Cu")
		(net "UART_COMP_OUT_TX")
	)
	(segment
		(start 79.2988 -171.7802)
		(end 81.3181 -171.7802)
		(width 0.127)
		(layer "In5.Cu")
		(net "UART_COMP_OUT_TX")
	)
	(segment
		(start 81.3181 -171.7802)
		(end 82.316828 -170.781472)
		(width 0.127)
		(layer "In5.Cu")
		(net "UART_COMP_OUT_TX")
	)
	(segment
		(start 55.405528 -166.7637)
		(end 57.983628 -169.3418)
		(width 0.127)
		(layer "In5.Cu")
		(net "UART_COMP_OUT_TX")
	)
	(segment
		(start 43.024044 -160.930844)
		(end 45.987208 -160.930844)
		(width 0.127)
		(layer "In5.Cu")
		(net "UART_COMP_OUT_TX")
	)
	(segment
		(start 38.4937 -159.9692)
		(end 42.0624 -159.9692)
		(width 0.127)
		(layer "In5.Cu")
		(net "UART_COMP_OUT_TX")
	)
	(segment
		(start 79.1337 -171.9453)
		(end 79.2988 -171.7802)
		(width 0.127)
		(layer "In5.Cu")
		(net "UART_COMP_OUT_TX")
	)
	(segment
		(start 65.743582 -170.332146)
		(end 72.847454 -170.332146)
		(width 0.127)
		(layer "In5.Cu")
		(net "UART_COMP_OUT_TX")
	)
	(segment
		(start 96.898206 -127.728472)
		(end 96.898206 -128.73863)
		(width 0.127)
		(layer "F.Cu")
		(net "UART_COMP_IN_RX")
	)
	(segment
		(start 92.5068 -124.5616)
		(end 95.523558 -124.5616)
		(width 0.127)
		(layer "F.Cu")
		(net "UART_COMP_IN_RX")
	)
	(segment
		(start 95.609918 -125.814582)
		(end 95.609918 -126.440184)
		(width 0.127)
		(layer "F.Cu")
		(net "UART_COMP_IN_RX")
	)
	(segment
		(start 90.02776 -122.35434)
		(end 90.06332 -122.31878)
		(width 0.127)
		(layer "F.Cu")
		(net "UART_COMP_IN_RX")
	)
	(segment
		(start 91.271598 -124.108718)
		(end 92.053918 -124.108718)
		(width 0.127)
		(layer "F.Cu")
		(net "UART_COMP_IN_RX")
	)
	(segment
		(start 90.02776 -123.38812)
		(end 90.02776 -122.35434)
		(width 0.127)
		(layer "F.Cu")
		(net "UART_COMP_IN_RX")
	)
	(segment
		(start 95.921576 -125.502924)
		(end 95.609918 -125.814582)
		(width 0.127)
		(layer "F.Cu")
		(net "UART_COMP_IN_RX")
	)
	(segment
		(start 90.02776 -123.38812)
		(end 90.551 -123.38812)
		(width 0.127)
		(layer "F.Cu")
		(net "UART_COMP_IN_RX")
	)
	(segment
		(start 92.053918 -124.108718)
		(end 92.5068 -124.5616)
		(width 0.127)
		(layer "F.Cu")
		(net "UART_COMP_IN_RX")
	)
	(segment
		(start 96.898206 -128.73863)
		(end 96.63049 -129.006346)
		(width 0.127)
		(layer "F.Cu")
		(net "UART_COMP_IN_RX")
	)
	(segment
		(start 96.63049 -129.006346)
		(end 95.945706 -129.006346)
		(width 0.127)
		(layer "F.Cu")
		(net "UART_COMP_IN_RX")
	)
	(segment
		(start 95.609918 -126.440184)
		(end 96.898206 -127.728472)
		(width 0.127)
		(layer "F.Cu")
		(net "UART_COMP_IN_RX")
	)
	(segment
		(start 95.921576 -124.959618)
		(end 95.921576 -125.502924)
		(width 0.127)
		(layer "F.Cu")
		(net "UART_COMP_IN_RX")
	)
	(segment
		(start 90.551 -123.38812)
		(end 91.271598 -124.108718)
		(width 0.127)
		(layer "F.Cu")
		(net "UART_COMP_IN_RX")
	)
	(segment
		(start 95.523558 -124.5616)
		(end 95.921576 -124.959618)
		(width 0.127)
		(layer "F.Cu")
		(net "UART_COMP_IN_RX")
	)
	(via
		(at 95.921576 -124.959618)
		(size 0.6604)
		(drill 0.3302)
		(layers "F.Cu" "B.Cu")
		(net "UART_COMP_IN_RX")
	)
	(segment
		(start 50.6476 -159.676084)
		(end 51.16322 -159.676084)
		(width 0.127)
		(layer "F.Cu")
		(net "UART_BMC_TX")
	)
	(segment
		(start 50.482246 -160.531302)
		(end 50.17897 -160.834578)
		(width 0.127)
		(layer "F.Cu")
		(net "UART_BMC_TX")
	)
	(segment
		(start 90.668094 -130.007106)
		(end 91.805506 -130.007106)
		(width 0.127)
		(layer "F.Cu")
		(net "UART_BMC_TX")
	)
	(segment
		(start 50.6476 -159.676084)
		(end 50.482246 -159.841438)
		(width 0.127)
		(layer "F.Cu")
		(net "UART_BMC_TX")
	)
	(segment
		(start 50.482246 -159.841438)
		(end 50.482246 -160.531302)
		(width 0.127)
		(layer "F.Cu")
		(net "UART_BMC_TX")
	)
	(segment
		(start 90.2462 -130.429)
		(end 90.668094 -130.007106)
		(width 0.127)
		(layer "F.Cu")
		(net "UART_BMC_TX")
	)
	(segment
		(start 51.16322 -159.676084)
		(end 51.45024 -159.389064)
		(width 0.127)
		(layer "F.Cu")
		(net "UART_BMC_TX")
	)
	(via
		(at 75.7174 -160.1851)
		(size 0.508)
		(drill 0.254)
		(layers "F.Cu" "B.Cu")
		(net "UART_BMC_TX")
	)
	(via
		(at 90.2462 -130.429)
		(size 0.508)
		(drill 0.254)
		(layers "F.Cu" "B.Cu")
		(net "UART_BMC_TX")
	)
	(via
		(at 75.5396 -131.567174)
		(size 0.508)
		(drill 0.254)
		(layers "F.Cu" "B.Cu")
		(net "UART_BMC_TX")
	)
	(via
		(at 50.6476 -159.676084)
		(size 0.508)
		(drill 0.254)
		(layers "F.Cu" "B.Cu")
		(net "UART_BMC_TX")
	)
	(segment
		(start 74.644504 -140.781786)
		(end 76.1619 -142.299182)
		(width 0.127)
		(layer "In2.Cu")
		(net "UART_BMC_TX")
	)
	(segment
		(start 76.1619 -146.958558)
		(end 75.8825 -147.237958)
		(width 0.127)
		(layer "In2.Cu")
		(net "UART_BMC_TX")
	)
	(segment
		(start 74.644504 -138.558016)
		(end 74.644504 -140.781786)
		(width 0.127)
		(layer "In2.Cu")
		(net "UART_BMC_TX")
	)
	(segment
		(start 76.74102 -153.835354)
		(end 76.74102 -159.16148)
		(width 0.127)
		(layer "In2.Cu")
		(net "UART_BMC_TX")
	)
	(segment
		(start 74.687684 -131.567174)
		(end 73.79843 -132.456428)
		(width 0.127)
		(layer "In2.Cu")
		(net "UART_BMC_TX")
	)
	(segment
		(start 76.74102 -159.16148)
		(end 75.7174 -160.1851)
		(width 0.127)
		(layer "In2.Cu")
		(net "UART_BMC_TX")
	)
	(segment
		(start 75.5396 -131.567174)
		(end 74.687684 -131.567174)
		(width 0.127)
		(layer "In2.Cu")
		(net "UART_BMC_TX")
	)
	(segment
		(start 76.1619 -142.299182)
		(end 76.1619 -146.958558)
		(width 0.127)
		(layer "In2.Cu")
		(net "UART_BMC_TX")
	)
	(segment
		(start 75.8825 -152.976834)
		(end 76.74102 -153.835354)
		(width 0.127)
		(layer "In2.Cu")
		(net "UART_BMC_TX")
	)
	(segment
		(start 73.79843 -137.711942)
		(end 74.644504 -138.558016)
		(width 0.127)
		(layer "In2.Cu")
		(net "UART_BMC_TX")
	)
	(segment
		(start 75.8825 -147.237958)
		(end 75.8825 -152.976834)
		(width 0.127)
		(layer "In2.Cu")
		(net "UART_BMC_TX")
	)
	(segment
		(start 73.79843 -132.456428)
		(end 73.79843 -137.711942)
		(width 0.127)
		(layer "In2.Cu")
		(net "UART_BMC_TX")
	)
	(segment
		(start 90.2208 -130.4544)
		(end 90.2462 -130.429)
		(width 0.127)
		(layer "In5.Cu")
		(net "UART_BMC_TX")
	)
	(segment
		(start 74.03084 -163.45916)
		(end 73.071482 -163.45916)
		(width 0.127)
		(layer "In5.Cu")
		(net "UART_BMC_TX")
	)
	(segment
		(start 84.062824 -131.4323)
		(end 84.726018 -131.4323)
		(width 0.127)
		(layer "In5.Cu")
		(net "UART_BMC_TX")
	)
	(segment
		(start 76.8731 -131.6482)
		(end 77.1652 -131.3561)
		(width 0.127)
		(layer "In5.Cu")
		(net "UART_BMC_TX")
	)
	(segment
		(start 83.986624 -131.3561)
		(end 84.062824 -131.4323)
		(width 0.127)
		(layer "In5.Cu")
		(net "UART_BMC_TX")
	)
	(segment
		(start 75.7174 -160.1851)
		(end 75.7174 -161.7726)
		(width 0.127)
		(layer "In5.Cu")
		(net "UART_BMC_TX")
	)
	(segment
		(start 52.507388 -159.676084)
		(end 50.6476 -159.676084)
		(width 0.127)
		(layer "In5.Cu")
		(net "UART_BMC_TX")
	)
	(segment
		(start 85.786214 -130.4544)
		(end 90.2208 -130.4544)
		(width 0.127)
		(layer "In5.Cu")
		(net "UART_BMC_TX")
	)
	(segment
		(start 77.1652 -131.3561)
		(end 83.986624 -131.3561)
		(width 0.127)
		(layer "In5.Cu")
		(net "UART_BMC_TX")
	)
	(segment
		(start 75.7174 -161.7726)
		(end 74.03084 -163.45916)
		(width 0.127)
		(layer "In5.Cu")
		(net "UART_BMC_TX")
	)
	(segment
		(start 73.071482 -163.45916)
		(end 72.601582 -163.92906)
		(width 0.127)
		(layer "In5.Cu")
		(net "UART_BMC_TX")
	)
	(segment
		(start 57.15254 -162.927538)
		(end 57.15254 -162.927284)
		(width 0.127)
		(layer "In5.Cu")
		(net "UART_BMC_TX")
	)
	(segment
		(start 75.620626 -131.6482)
		(end 76.8731 -131.6482)
		(width 0.127)
		(layer "In5.Cu")
		(net "UART_BMC_TX")
	)
	(segment
		(start 85.255608 -130.90271)
		(end 85.337904 -130.90271)
		(width 0.127)
		(layer "In5.Cu")
		(net "UART_BMC_TX")
	)
	(segment
		(start 75.5396 -131.567174)
		(end 75.620626 -131.6482)
		(width 0.127)
		(layer "In5.Cu")
		(net "UART_BMC_TX")
	)
	(segment
		(start 65.6844 -163.92906)
		(end 65.05448 -163.29914)
		(width 0.127)
		(layer "In5.Cu")
		(net "UART_BMC_TX")
	)
	(segment
		(start 65.05448 -163.29914)
		(end 57.524142 -163.29914)
		(width 0.127)
		(layer "In5.Cu")
		(net "UART_BMC_TX")
	)
	(segment
		(start 85.337904 -130.90271)
		(end 85.786214 -130.4544)
		(width 0.127)
		(layer "In5.Cu")
		(net "UART_BMC_TX")
	)
	(segment
		(start 57.524142 -163.29914)
		(end 57.15254 -162.927538)
		(width 0.127)
		(layer "In5.Cu")
		(net "UART_BMC_TX")
	)
	(segment
		(start 84.726018 -131.4323)
		(end 85.255608 -130.90271)
		(width 0.127)
		(layer "In5.Cu")
		(net "UART_BMC_TX")
	)
	(segment
		(start 57.15254 -162.927284)
		(end 56.772556 -162.5473)
		(width 0.127)
		(layer "In5.Cu")
		(net "UART_BMC_TX")
	)
	(segment
		(start 56.772556 -162.5473)
		(end 55.378604 -162.5473)
		(width 0.127)
		(layer "In5.Cu")
		(net "UART_BMC_TX")
	)
	(segment
		(start 55.378604 -162.5473)
		(end 52.507388 -159.676084)
		(width 0.127)
		(layer "In5.Cu")
		(net "UART_BMC_TX")
	)
	(segment
		(start 72.601582 -163.92906)
		(end 65.6844 -163.92906)
		(width 0.127)
		(layer "In5.Cu")
		(net "UART_BMC_TX")
	)
	(segment
		(start 49.847246 -160.012126)
		(end 49.81194 -159.97682)
		(width 0.127)
		(layer "F.Cu")
		(net "UART_BMC_RX")
	)
	(segment
		(start 90.2462 -128.5494)
		(end 90.703146 -129.006346)
		(width 0.127)
		(layer "F.Cu")
		(net "UART_BMC_RX")
	)
	(segment
		(start 49.81194 -159.97682)
		(end 49.81194 -159.271208)
		(width 0.127)
		(layer "F.Cu")
		(net "UART_BMC_RX")
	)
	(segment
		(start 90.703146 -129.006346)
		(end 91.805506 -129.006346)
		(width 0.127)
		(layer "F.Cu")
		(net "UART_BMC_RX")
	)
	(segment
		(start 49.81194 -159.271208)
		(end 50.11801 -158.965138)
		(width 0.127)
		(layer "F.Cu")
		(net "UART_BMC_RX")
	)
	(segment
		(start 49.847246 -160.043114)
		(end 49.847246 -160.012126)
		(width 0.127)
		(layer "F.Cu")
		(net "UART_BMC_RX")
	)
	(via
		(at 90.2462 -128.5494)
		(size 0.508)
		(drill 0.254)
		(layers "F.Cu" "B.Cu")
		(net "UART_BMC_RX")
	)
	(via
		(at 74.1934 -131.064)
		(size 0.508)
		(drill 0.254)
		(layers "F.Cu" "B.Cu")
		(net "UART_BMC_RX")
	)
	(via
		(at 74.803 -160.1724)
		(size 0.508)
		(drill 0.254)
		(layers "F.Cu" "B.Cu")
		(net "UART_BMC_RX")
	)
	(via
		(at 49.847246 -160.043114)
		(size 0.508)
		(drill 0.254)
		(layers "F.Cu" "B.Cu")
		(net "UART_BMC_RX")
	)
	(segment
		(start 75.602846 -153.595324)
		(end 75.602592 -153.595324)
		(width 0.127)
		(layer "In2.Cu")
		(net "UART_BMC_RX")
	)
	(segment
		(start 74.009504 -138.82116)
		(end 73.16343 -137.975086)
		(width 0.127)
		(layer "In2.Cu")
		(net "UART_BMC_RX")
	)
	(segment
		(start 73.16343 -132.09397)
		(end 74.1934 -131.064)
		(width 0.127)
		(layer "In2.Cu")
		(net "UART_BMC_RX")
	)
	(segment
		(start 76.10602 -154.098498)
		(end 75.602846 -153.595324)
		(width 0.127)
		(layer "In2.Cu")
		(net "UART_BMC_RX")
	)
	(segment
		(start 75.23099 -153.223722)
		(end 75.23099 -153.223468)
		(width 0.127)
		(layer "In2.Cu")
		(net "UART_BMC_RX")
	)
	(segment
		(start 76.10602 -158.86938)
		(end 76.10602 -154.098498)
		(width 0.127)
		(layer "In2.Cu")
		(net "UART_BMC_RX")
	)
	(segment
		(start 75.602592 -153.595324)
		(end 75.23099 -153.223722)
		(width 0.127)
		(layer "In2.Cu")
		(net "UART_BMC_RX")
	)
	(segment
		(start 74.92619 -148.33219)
		(end 74.5998 -148.0058)
		(width 0.127)
		(layer "In2.Cu")
		(net "UART_BMC_RX")
	)
	(segment
		(start 75.23099 -153.223468)
		(end 74.92619 -152.918668)
		(width 0.127)
		(layer "In2.Cu")
		(net "UART_BMC_RX")
	)
	(segment
		(start 75.0189 -143.805148)
		(end 74.009504 -142.795752)
		(width 0.127)
		(layer "In2.Cu")
		(net "UART_BMC_RX")
	)
	(segment
		(start 73.16343 -137.975086)
		(end 73.16343 -132.09397)
		(width 0.127)
		(layer "In2.Cu")
		(net "UART_BMC_RX")
	)
	(segment
		(start 75.0189 -145.443702)
		(end 75.0189 -143.805148)
		(width 0.127)
		(layer "In2.Cu")
		(net "UART_BMC_RX")
	)
	(segment
		(start 74.92619 -152.918668)
		(end 74.92619 -148.33219)
		(width 0.127)
		(layer "In2.Cu")
		(net "UART_BMC_RX")
	)
	(segment
		(start 74.5998 -145.862802)
		(end 75.0189 -145.443702)
		(width 0.127)
		(layer "In2.Cu")
		(net "UART_BMC_RX")
	)
	(segment
		(start 74.803 -160.1724)
		(end 76.10602 -158.86938)
		(width 0.127)
		(layer "In2.Cu")
		(net "UART_BMC_RX")
	)
	(segment
		(start 74.5998 -148.0058)
		(end 74.5998 -145.862802)
		(width 0.127)
		(layer "In2.Cu")
		(net "UART_BMC_RX")
	)
	(segment
		(start 74.009504 -142.795752)
		(end 74.009504 -138.82116)
		(width 0.127)
		(layer "In2.Cu")
		(net "UART_BMC_RX")
	)
	(segment
		(start 76.5429 -130.9751)
		(end 74.2823 -130.9751)
		(width 0.127)
		(layer "In5.Cu")
		(net "UART_BMC_RX")
	)
	(segment
		(start 52.353972 -158.2928)
		(end 51.769772 -158.877)
		(width 0.127)
		(layer "In5.Cu")
		(net "UART_BMC_RX")
	)
	(segment
		(start 49.847246 -159.578294)
		(end 49.847246 -160.043114)
		(width 0.127)
		(layer "In5.Cu")
		(net "UART_BMC_RX")
	)
	(segment
		(start 90.2462 -128.5494)
		(end 88.9762 -129.8194)
		(width 0.127)
		(layer "In5.Cu")
		(net "UART_BMC_RX")
	)
	(segment
		(start 65.947544 -163.29406)
		(end 65.317624 -162.66414)
		(width 0.127)
		(layer "In5.Cu")
		(net "UART_BMC_RX")
	)
	(segment
		(start 74.7014 -160.274)
		(end 74.7014 -161.7726)
		(width 0.127)
		(layer "In5.Cu")
		(net "UART_BMC_RX")
	)
	(segment
		(start 88.9762 -129.8194)
		(end 87.3506 -129.8194)
		(width 0.127)
		(layer "In5.Cu")
		(net "UART_BMC_RX")
	)
	(segment
		(start 73.0631 -162.2425)
		(end 72.01154 -163.29406)
		(width 0.127)
		(layer "In5.Cu")
		(net "UART_BMC_RX")
	)
	(segment
		(start 53.4162 -158.2928)
		(end 52.353972 -158.2928)
		(width 0.127)
		(layer "In5.Cu")
		(net "UART_BMC_RX")
	)
	(segment
		(start 76.7969 -130.7211)
		(end 76.5429 -130.9751)
		(width 0.127)
		(layer "In5.Cu")
		(net "UART_BMC_RX")
	)
	(segment
		(start 85.8393 -129.4765)
		(end 85.3186 -129.9972)
		(width 0.127)
		(layer "In5.Cu")
		(net "UART_BMC_RX")
	)
	(segment
		(start 74.7014 -161.7726)
		(end 74.2315 -162.2425)
		(width 0.127)
		(layer "In5.Cu")
		(net "UART_BMC_RX")
	)
	(segment
		(start 74.2315 -162.2425)
		(end 73.0631 -162.2425)
		(width 0.127)
		(layer "In5.Cu")
		(net "UART_BMC_RX")
	)
	(segment
		(start 83.641184 -130.7211)
		(end 76.7969 -130.7211)
		(width 0.127)
		(layer "In5.Cu")
		(net "UART_BMC_RX")
	)
	(segment
		(start 84.365084 -129.9972)
		(end 83.641184 -130.7211)
		(width 0.127)
		(layer "In5.Cu")
		(net "UART_BMC_RX")
	)
	(segment
		(start 74.2823 -130.9751)
		(end 74.1934 -131.064)
		(width 0.127)
		(layer "In5.Cu")
		(net "UART_BMC_RX")
	)
	(segment
		(start 50.54854 -158.877)
		(end 49.847246 -159.578294)
		(width 0.127)
		(layer "In5.Cu")
		(net "UART_BMC_RX")
	)
	(segment
		(start 74.803 -160.1724)
		(end 74.7014 -160.274)
		(width 0.127)
		(layer "In5.Cu")
		(net "UART_BMC_RX")
	)
	(segment
		(start 85.3186 -129.9972)
		(end 84.365084 -129.9972)
		(width 0.127)
		(layer "In5.Cu")
		(net "UART_BMC_RX")
	)
	(segment
		(start 87.0077 -129.4765)
		(end 85.8393 -129.4765)
		(width 0.127)
		(layer "In5.Cu")
		(net "UART_BMC_RX")
	)
	(segment
		(start 51.769772 -158.877)
		(end 50.54854 -158.877)
		(width 0.127)
		(layer "In5.Cu")
		(net "UART_BMC_RX")
	)
	(segment
		(start 57.78754 -162.66414)
		(end 53.4162 -158.2928)
		(width 0.127)
		(layer "In5.Cu")
		(net "UART_BMC_RX")
	)
	(segment
		(start 72.01154 -163.29406)
		(end 65.947544 -163.29406)
		(width 0.127)
		(layer "In5.Cu")
		(net "UART_BMC_RX")
	)
	(segment
		(start 65.317624 -162.66414)
		(end 57.78754 -162.66414)
		(width 0.127)
		(layer "In5.Cu")
		(net "UART_BMC_RX")
	)
	(segment
		(start 87.3506 -129.8194)
		(end 87.0077 -129.4765)
		(width 0.127)
		(layer "In5.Cu")
		(net "UART_BMC_RX")
	)
	(segment
		(start 51.442366 -156.671518)
		(end 51.442366 -155.96997)
		(width 0.127)
		(layer "F.Cu")
		(net "UART_BMC_R_TX")
	)
	(segment
		(start 51.168046 -156.945838)
		(end 51.442366 -156.671518)
		(width 0.127)
		(layer "F.Cu")
		(net "UART_BMC_R_TX")
	)
	(segment
		(start 48.899826 -153.427684)
		(end 48.899826 -153.399998)
		(width 0.127)
		(layer "F.Cu")
		(net "UART_BMC_R_TX")
	)
	(segment
		(start 48.943768 -153.471626)
		(end 48.899826 -153.427684)
		(width 0.127)
		(layer "F.Cu")
		(net "UART_BMC_R_TX")
	)
	(segment
		(start 51.168046 -157.249876)
		(end 51.168046 -156.945838)
		(width 0.127)
		(layer "F.Cu")
		(net "UART_BMC_R_TX")
	)
	(segment
		(start 51.442366 -155.96997)
		(end 48.944022 -153.471626)
		(width 0.127)
		(layer "F.Cu")
		(net "UART_BMC_R_TX")
	)
	(segment
		(start 48.944022 -153.471626)
		(end 48.943768 -153.471626)
		(width 0.127)
		(layer "F.Cu")
		(net "UART_BMC_R_TX")
	)
	(segment
		(start 51.168046 -158.21787)
		(end 51.168046 -157.249876)
		(width 0.127)
		(layer "F.Cu")
		(net "UART_BMC_R_TX")
	)
	(segment
		(start 51.45024 -158.500064)
		(end 51.168046 -158.21787)
		(width 0.127)
		(layer "F.Cu")
		(net "UART_BMC_R_TX")
	)
	(via
		(at 51.168046 -157.249876)
		(size 0.6604)
		(drill 0.3302)
		(layers "F.Cu" "B.Cu")
		(net "UART_BMC_R_TX")
	)
	(segment
		(start 50.11801 -156.915612)
		(end 50.3936 -156.640022)
		(width 0.127)
		(layer "F.Cu")
		(net "UART_BMC_R_RX")
	)
	(segment
		(start 48.776382 -153.83256)
		(end 48.499776 -153.555954)
		(width 0.127)
		(layer "F.Cu")
		(net "UART_BMC_R_RX")
	)
	(segment
		(start 50.3936 -156.640022)
		(end 50.3936 -155.349702)
		(width 0.127)
		(layer "F.Cu")
		(net "UART_BMC_R_RX")
	)
	(segment
		(start 50.11801 -158.076138)
		(end 50.11801 -156.915612)
		(width 0.127)
		(layer "F.Cu")
		(net "UART_BMC_R_RX")
	)
	(segment
		(start 50.3936 -155.349702)
		(end 48.876458 -153.83256)
		(width 0.127)
		(layer "F.Cu")
		(net "UART_BMC_R_RX")
	)
	(segment
		(start 48.499776 -153.555954)
		(end 48.499776 -152.999948)
		(width 0.127)
		(layer "F.Cu")
		(net "UART_BMC_R_RX")
	)
	(segment
		(start 48.499776 -152.999948)
		(end 48.899826 -152.599898)
		(width 0.127)
		(layer "F.Cu")
		(net "UART_BMC_R_RX")
	)
	(segment
		(start 48.876458 -153.83256)
		(end 48.776382 -153.83256)
		(width 0.127)
		(layer "F.Cu")
		(net "UART_BMC_R_RX")
	)
	(via
		(at 50.11801 -156.915612)
		(size 0.6604)
		(drill 0.3302)
		(layers "F.Cu" "B.Cu")
		(net "UART_BMC_R_RX")
	)
	(segment
		(start 96.657668 -155.105354)
		(end 95.621856 -155.105354)
		(width 0.127)
		(layer "F.Cu")
		(net "TP_USB_SDA")
	)
	(segment
		(start 97.139252 -154.62377)
		(end 96.657668 -155.105354)
		(width 0.127)
		(layer "F.Cu")
		(net "TP_USB_SDA")
	)
	(via
		(at 97.139252 -154.62377)
		(size 0.508)
		(drill 0.254)
		(layers "F.Cu" "B.Cu")
		(net "TP_USB_SDA")
	)
	(segment
		(start 97.62871 -154.134312)
		(end 97.139252 -154.62377)
		(width 0.127)
		(layer "B.Cu")
		(net "TP_USB_SDA")
	)
	(segment
		(start 97.62871 -153.851102)
		(end 97.62871 -154.134312)
		(width 0.127)
		(layer "B.Cu")
		(net "TP_USB_SDA")
	)
	(segment
		(start 40.899842 -150.999952)
		(end 40.499792 -151.400002)
		(width 0.127)
		(layer "F.Cu")
		(net "SCC_B_HB_IN_R")
	)
	(via
		(at 38.30066 -152.02916)
		(size 0.6096)
		(drill 0.3048)
		(layers "F.Cu" "B.Cu")
		(net "SCC_B_HB_IN_R")
	)
	(via
		(at 40.499792 -151.400002)
		(size 0.4572)
		(drill 0.2032)
		(layers "F.Cu" "B.Cu")
		(net "SCC_B_HB_IN_R")
	)
	(segment
		(start 38.30066 -152.86863)
		(end 38.30066 -152.02916)
		(width 0.127)
		(layer "B.Cu")
		(net "SCC_B_HB_IN_R")
	)
	(segment
		(start 38.30066 -152.02916)
		(end 38.929818 -151.400002)
		(width 0.127)
		(layer "B.Cu")
		(net "SCC_B_HB_IN_R")
	)
	(segment
		(start 38.482778 -153.050748)
		(end 38.30066 -152.86863)
		(width 0.127)
		(layer "B.Cu")
		(net "SCC_B_HB_IN_R")
	)
	(segment
		(start 38.929818 -151.400002)
		(end 40.499792 -151.400002)
		(width 0.127)
		(layer "B.Cu")
		(net "SCC_B_HB_IN_R")
	)
	(segment
		(start 37.3126 -153.742898)
		(end 37.3126 -154.909012)
		(width 0.127)
		(layer "F.Cu")
		(net "SCC_A_HB_IN_R")
	)
	(segment
		(start 37.3126 -154.909012)
		(end 36.043616 -156.177996)
		(width 0.127)
		(layer "F.Cu")
		(net "SCC_A_HB_IN_R")
	)
	(segment
		(start 34.840672 -156.889958)
		(end 35.552634 -156.177996)
		(width 0.127)
		(layer "F.Cu")
		(net "SCC_A_HB_IN_R")
	)
	(segment
		(start 39.255446 -151.800052)
		(end 37.3126 -153.742898)
		(width 0.127)
		(layer "F.Cu")
		(net "SCC_A_HB_IN_R")
	)
	(segment
		(start 39.299896 -151.800052)
		(end 39.255446 -151.800052)
		(width 0.127)
		(layer "F.Cu")
		(net "SCC_A_HB_IN_R")
	)
	(segment
		(start 34.408872 -156.889958)
		(end 34.840672 -156.889958)
		(width 0.127)
		(layer "F.Cu")
		(net "SCC_A_HB_IN_R")
	)
	(segment
		(start 36.043616 -156.177996)
		(end 35.552634 -156.177996)
		(width 0.127)
		(layer "F.Cu")
		(net "SCC_A_HB_IN_R")
	)
	(via
		(at 35.552634 -156.177996)
		(size 0.6604)
		(drill 0.3302)
		(layers "F.Cu" "B.Cu")
		(net "SCC_A_HB_IN_R")
	)
	(segment
		(start 57.785 -130.0988)
		(end 57.3024 -130.5814)
		(width 0.127)
		(layer "F.Cu")
		(net "RSTBTN_OUT_N")
	)
	(segment
		(start 66.512186 -138.114786)
		(end 66.2432 -137.8458)
		(width 0.127)
		(layer "F.Cu")
		(net "RSTBTN_OUT_N")
	)
	(segment
		(start 67.002914 -138.114786)
		(end 66.512186 -138.114786)
		(width 0.127)
		(layer "F.Cu")
		(net "RSTBTN_OUT_N")
	)
	(segment
		(start 57.3024 -130.5814)
		(end 57.3024 -130.89382)
		(width 0.127)
		(layer "F.Cu")
		(net "RSTBTN_OUT_N")
	)
	(segment
		(start 66.2432 -137.8458)
		(end 66.228214 -137.8458)
		(width 0.127)
		(layer "F.Cu")
		(net "RSTBTN_OUT_N")
	)
	(via
		(at 61.454538 -130.633724)
		(size 0.6096)
		(drill 0.3048)
		(layers "F.Cu" "B.Cu")
		(net "RSTBTN_OUT_N")
	)
	(via
		(at 66.228214 -137.8458)
		(size 0.508)
		(drill 0.254)
		(layers "F.Cu" "B.Cu")
		(net "RSTBTN_OUT_N")
	)
	(via
		(at 57.785 -130.0988)
		(size 0.508)
		(drill 0.254)
		(layers "F.Cu" "B.Cu")
		(net "RSTBTN_OUT_N")
	)
	(via
		(at 65.5574 -131.1656)
		(size 0.508)
		(drill 0.254)
		(layers "F.Cu" "B.Cu")
		(net "RSTBTN_OUT_N")
	)
	(segment
		(start 57.785 -130.0988)
		(end 58.319924 -130.633724)
		(width 0.127)
		(layer "B.Cu")
		(net "RSTBTN_OUT_N")
	)
	(segment
		(start 65.5574 -131.1656)
		(end 65.29832 -131.1656)
		(width 0.127)
		(layer "B.Cu")
		(net "RSTBTN_OUT_N")
	)
	(segment
		(start 64.766444 -130.633724)
		(end 61.454538 -130.633724)
		(width 0.127)
		(layer "B.Cu")
		(net "RSTBTN_OUT_N")
	)
	(segment
		(start 65.29832 -131.1656)
		(end 64.766444 -130.633724)
		(width 0.127)
		(layer "B.Cu")
		(net "RSTBTN_OUT_N")
	)
	(segment
		(start 58.319924 -130.633724)
		(end 61.454538 -130.633724)
		(width 0.127)
		(layer "B.Cu")
		(net "RSTBTN_OUT_N")
	)
	(segment
		(start 66.2813 -135.445754)
		(end 66.2813 -137.792714)
		(width 0.127)
		(layer "In2.Cu")
		(net "RSTBTN_OUT_N")
	)
	(segment
		(start 66.2813 -137.792714)
		(end 66.228214 -137.8458)
		(width 0.127)
		(layer "In2.Cu")
		(net "RSTBTN_OUT_N")
	)
	(segment
		(start 66.670682 -135.056372)
		(end 66.2813 -135.445754)
		(width 0.127)
		(layer "In2.Cu")
		(net "RSTBTN_OUT_N")
	)
	(segment
		(start 65.5574 -131.42468)
		(end 66.8274 -132.69468)
		(width 0.127)
		(layer "In2.Cu")
		(net "RSTBTN_OUT_N")
	)
	(segment
		(start 66.670682 -134.152386)
		(end 66.670682 -135.056372)
		(width 0.127)
		(layer "In2.Cu")
		(net "RSTBTN_OUT_N")
	)
	(segment
		(start 66.8274 -132.69468)
		(end 66.8274 -133.995668)
		(width 0.127)
		(layer "In2.Cu")
		(net "RSTBTN_OUT_N")
	)
	(segment
		(start 65.5574 -131.1656)
		(end 65.5574 -131.42468)
		(width 0.127)
		(layer "In2.Cu")
		(net "RSTBTN_OUT_N")
	)
	(segment
		(start 66.8274 -133.995668)
		(end 66.670682 -134.152386)
		(width 0.127)
		(layer "In2.Cu")
		(net "RSTBTN_OUT_N")
	)
	(segment
		(start 46.47438 -120.395492)
		(end 53.848508 -120.395492)
		(width 0.127)
		(layer "F.Cu")
		(net "RST_BMC_EXTRST_N")
	)
	(segment
		(start 53.848508 -120.395492)
		(end 54.1274 -120.1166)
		(width 0.127)
		(layer "F.Cu")
		(net "RST_BMC_EXTRST_N")
	)
	(segment
		(start 68.9229 -120.523)
		(end 69.9008 -120.523)
		(width 0.127)
		(layer "F.Cu")
		(net "RST_BMC_EXTRST_N")
	)
	(via
		(at 39.243 -123.698)
		(size 0.508)
		(drill 0.254)
		(layers "F.Cu" "B.Cu")
		(net "RST_BMC_EXTRST_N")
	)
	(via
		(at 69.9008 -120.523)
		(size 0.508)
		(drill 0.254)
		(layers "F.Cu" "B.Cu")
		(net "RST_BMC_EXTRST_N")
	)
	(via
		(at 56.517032 -121.689368)
		(size 0.6096)
		(drill 0.3048)
		(layers "F.Cu" "B.Cu")
		(net "RST_BMC_EXTRST_N")
	)
	(via
		(at 54.1274 -120.1166)
		(size 0.508)
		(drill 0.254)
		(layers "F.Cu" "B.Cu")
		(net "RST_BMC_EXTRST_N")
	)
	(segment
		(start 56.515 -121.6914)
		(end 56.515 -126.111)
		(width 0.127)
		(layer "B.Cu")
		(net "RST_BMC_EXTRST_N")
	)
	(segment
		(start 56.515 -126.111)
		(end 56.20258 -126.42342)
		(width 0.127)
		(layer "B.Cu")
		(net "RST_BMC_EXTRST_N")
	)
	(segment
		(start 39.37 -126.0729)
		(end 39.37 -124.6886)
		(width 0.127)
		(layer "B.Cu")
		(net "RST_BMC_EXTRST_N")
	)
	(segment
		(start 54.1274 -120.1166)
		(end 55.1688 -120.1166)
		(width 0.127)
		(layer "B.Cu")
		(net "RST_BMC_EXTRST_N")
	)
	(segment
		(start 39.37 -124.6886)
		(end 39.243 -124.5616)
		(width 0.127)
		(layer "B.Cu")
		(net "RST_BMC_EXTRST_N")
	)
	(segment
		(start 56.20258 -126.42342)
		(end 55.66664 -126.42342)
		(width 0.127)
		(layer "B.Cu")
		(net "RST_BMC_EXTRST_N")
	)
	(segment
		(start 55.1688 -120.1166)
		(end 56.517032 -121.464832)
		(width 0.127)
		(layer "B.Cu")
		(net "RST_BMC_EXTRST_N")
	)
	(segment
		(start 56.517032 -121.689368)
		(end 56.515 -121.6914)
		(width 0.127)
		(layer "B.Cu")
		(net "RST_BMC_EXTRST_N")
	)
	(segment
		(start 56.517032 -121.464832)
		(end 56.517032 -121.689368)
		(width 0.127)
		(layer "B.Cu")
		(net "RST_BMC_EXTRST_N")
	)
	(segment
		(start 39.243 -124.5616)
		(end 39.243 -123.698)
		(width 0.127)
		(layer "B.Cu")
		(net "RST_BMC_EXTRST_N")
	)
	(segment
		(start 68.044314 -119.635778)
		(end 67.83959 -119.4308)
		(width 0.127)
		(layer "In5.Cu")
		(net "RST_BMC_EXTRST_N")
	)
	(segment
		(start 67.83959 -119.4308)
		(end 54.8132 -119.4308)
		(width 0.127)
		(layer "In5.Cu")
		(net "RST_BMC_EXTRST_N")
	)
	(segment
		(start 48.3235 -123.4059)
		(end 40.166544 -123.4059)
		(width 0.127)
		(layer "In5.Cu")
		(net "RST_BMC_EXTRST_N")
	)
	(segment
		(start 51.6382 -122.103134)
		(end 50.602134 -123.1392)
		(width 0.127)
		(layer "In5.Cu")
		(net "RST_BMC_EXTRST_N")
	)
	(segment
		(start 51.6382 -121.787412)
		(end 51.6382 -122.103134)
		(width 0.127)
		(layer "In5.Cu")
		(net "RST_BMC_EXTRST_N")
	)
	(segment
		(start 53.6448 -120.5992)
		(end 52.826412 -120.5992)
		(width 0.127)
		(layer "In5.Cu")
		(net "RST_BMC_EXTRST_N")
	)
	(segment
		(start 39.874444 -123.698)
		(end 39.243 -123.698)
		(width 0.127)
		(layer "In5.Cu")
		(net "RST_BMC_EXTRST_N")
	)
	(segment
		(start 50.602134 -123.1392)
		(end 48.5902 -123.1392)
		(width 0.127)
		(layer "In5.Cu")
		(net "RST_BMC_EXTRST_N")
	)
	(segment
		(start 54.1274 -120.1166)
		(end 53.6448 -120.5992)
		(width 0.127)
		(layer "In5.Cu")
		(net "RST_BMC_EXTRST_N")
	)
	(segment
		(start 54.8132 -119.4308)
		(end 54.1274 -120.1166)
		(width 0.127)
		(layer "In5.Cu")
		(net "RST_BMC_EXTRST_N")
	)
	(segment
		(start 52.826412 -120.5992)
		(end 51.6382 -121.787412)
		(width 0.127)
		(layer "In5.Cu")
		(net "RST_BMC_EXTRST_N")
	)
	(segment
		(start 69.9008 -120.523)
		(end 68.931536 -120.523)
		(width 0.127)
		(layer "In5.Cu")
		(net "RST_BMC_EXTRST_N")
	)
	(segment
		(start 40.166544 -123.4059)
		(end 39.874444 -123.698)
		(width 0.127)
		(layer "In5.Cu")
		(net "RST_BMC_EXTRST_N")
	)
	(segment
		(start 68.931536 -120.523)
		(end 68.044314 -119.635778)
		(width 0.127)
		(layer "In5.Cu")
		(net "RST_BMC_EXTRST_N")
	)
	(segment
		(start 48.5902 -123.1392)
		(end 48.3235 -123.4059)
		(width 0.127)
		(layer "In5.Cu")
		(net "RST_BMC_EXTRST_N")
	)
	(segment
		(start 155.961588 -98.851212)
		(end 155.961588 -97.11563)
		(width 0.127)
		(layer "F.Cu")
		(net "IOM_IOC_UART_TX")
	)
	(segment
		(start 155.758642 -96.912684)
		(end 155.961588 -97.11563)
		(width 0.127)
		(layer "F.Cu")
		(net "IOM_IOC_UART_TX")
	)
	(segment
		(start 154.051 -144.9324)
		(end 154.051 -141.5796)
		(width 0.127)
		(layer "F.Cu")
		(net "IOM_IOC_UART_TX")
	)
	(segment
		(start 149.479 -105.3338)
		(end 155.961588 -98.851212)
		(width 0.127)
		(layer "F.Cu")
		(net "IOM_IOC_UART_TX")
	)
	(segment
		(start 154.051 -141.5796)
		(end 149.479 -137.0076)
		(width 0.127)
		(layer "F.Cu")
		(net "IOM_IOC_UART_TX")
	)
	(segment
		(start 155.0162 -145.8976)
		(end 154.051 -144.9324)
		(width 0.127)
		(layer "F.Cu")
		(net "IOM_IOC_UART_TX")
	)
	(segment
		(start 155.758642 -95.498158)
		(end 155.758642 -96.912684)
		(width 0.127)
		(layer "F.Cu")
		(net "IOM_IOC_UART_TX")
	)
	(segment
		(start 149.479 -137.0076)
		(end 149.479 -105.3338)
		(width 0.127)
		(layer "F.Cu")
		(net "IOM_IOC_UART_TX")
	)
	(via
		(at 155.961588 -97.11563)
		(size 0.6604)
		(drill 0.3302)
		(layers "F.Cu" "B.Cu")
		(net "IOM_IOC_UART_TX")
	)
	(segment
		(start 152.4762 -145.8976)
		(end 153.416 -144.9578)
		(width 0.127)
		(layer "F.Cu")
		(net "IOM_IOC_UART_RX")
	)
	(segment
		(start 153.313638 -85.3313)
		(end 152.92705 -85.717888)
		(width 0.127)
		(layer "F.Cu")
		(net "IOM_IOC_UART_RX")
	)
	(segment
		(start 148.844 -104.9528)
		(end 153.7716 -100.0252)
		(width 0.127)
		(layer "F.Cu")
		(net "IOM_IOC_UART_RX")
	)
	(segment
		(start 153.7716 -100.0252)
		(end 153.7716 -99.9236)
		(width 0.127)
		(layer "F.Cu")
		(net "IOM_IOC_UART_RX")
	)
	(segment
		(start 153.416 -144.9578)
		(end 153.416 -141.842744)
		(width 0.127)
		(layer "F.Cu")
		(net "IOM_IOC_UART_RX")
	)
	(segment
		(start 152.92705 -85.717888)
		(end 152.92705 -86.35238)
		(width 0.127)
		(layer "F.Cu")
		(net "IOM_IOC_UART_RX")
	)
	(segment
		(start 148.844 -137.270744)
		(end 148.844 -104.9528)
		(width 0.127)
		(layer "F.Cu")
		(net "IOM_IOC_UART_RX")
	)
	(segment
		(start 154.559 -85.3313)
		(end 153.313638 -85.3313)
		(width 0.127)
		(layer "F.Cu")
		(net "IOM_IOC_UART_RX")
	)
	(segment
		(start 153.416 -141.842744)
		(end 148.844 -137.270744)
		(width 0.127)
		(layer "F.Cu")
		(net "IOM_IOC_UART_RX")
	)
	(via
		(at 152.92705 -86.35238)
		(size 0.508)
		(drill 0.254)
		(layers "F.Cu" "B.Cu")
		(net "IOM_IOC_UART_RX")
	)
	(via
		(at 153.313638 -85.3313)
		(size 0.6604)
		(drill 0.3302)
		(layers "F.Cu" "B.Cu")
		(net "IOM_IOC_UART_RX")
	)
	(via
		(at 153.7716 -99.9236)
		(size 0.508)
		(drill 0.254)
		(layers "F.Cu" "B.Cu")
		(net "IOM_IOC_UART_RX")
	)
	(segment
		(start 153.2763 -92.149168)
		(end 153.2763 -98.440748)
		(width 0.127)
		(layer "In2.Cu")
		(net "IOM_IOC_UART_RX")
	)
	(segment
		(start 153.631392 -99.783392)
		(end 153.7716 -99.9236)
		(width 0.127)
		(layer "In2.Cu")
		(net "IOM_IOC_UART_RX")
	)
	(segment
		(start 152.92705 -86.35238)
		(end 152.92705 -91.799918)
		(width 0.127)
		(layer "In2.Cu")
		(net "IOM_IOC_UART_RX")
	)
	(segment
		(start 152.92705 -91.799918)
		(end 153.2763 -92.149168)
		(width 0.127)
		(layer "In2.Cu")
		(net "IOM_IOC_UART_RX")
	)
	(segment
		(start 153.631392 -98.79584)
		(end 153.631392 -99.783392)
		(width 0.127)
		(layer "In2.Cu")
		(net "IOM_IOC_UART_RX")
	)
	(segment
		(start 153.2763 -98.440748)
		(end 153.631392 -98.79584)
		(width 0.127)
		(layer "In2.Cu")
		(net "IOM_IOC_UART_RX")
	)
	(segment
		(start 56.780176 -170.405044)
		(end 56.780176 -169.19829)
		(width 0.127)
		(layer "F.Cu")
		(net "I2C_TPM_SDA")
	)
	(segment
		(start 57.88152 -168.85412)
		(end 57.039764 -168.012364)
		(width 0.127)
		(layer "F.Cu")
		(net "I2C_TPM_SDA")
	)
	(segment
		(start 57.039764 -168.012364)
		(end 57.039764 -167.377618)
		(width 0.127)
		(layer "F.Cu")
		(net "I2C_TPM_SDA")
	)
	(segment
		(start 59.69 -175.9966)
		(end 60.1853 -175.5013)
		(width 0.127)
		(layer "F.Cu")
		(net "I2C_TPM_SDA")
	)
	(segment
		(start 60.1853 -175.5013)
		(end 60.1853 -171.951142)
		(width 0.127)
		(layer "F.Cu")
		(net "I2C_TPM_SDA")
	)
	(segment
		(start 58.54319 -168.85412)
		(end 57.88152 -168.85412)
		(width 0.127)
		(layer "F.Cu")
		(net "I2C_TPM_SDA")
	)
	(segment
		(start 55.91937 -168.337484)
		(end 55.91937 -166.33063)
		(width 0.127)
		(layer "F.Cu")
		(net "I2C_TPM_SDA")
	)
	(segment
		(start 60.1853 -171.951142)
		(end 59.857386 -171.623228)
		(width 0.127)
		(layer "F.Cu")
		(net "I2C_TPM_SDA")
	)
	(segment
		(start 59.857386 -171.623228)
		(end 59.857386 -170.168316)
		(width 0.127)
		(layer "F.Cu")
		(net "I2C_TPM_SDA")
	)
	(segment
		(start 56.771286 -166.2684)
		(end 55.9816 -166.2684)
		(width 0.127)
		(layer "F.Cu")
		(net "I2C_TPM_SDA")
	)
	(segment
		(start 57.039764 -166.536878)
		(end 56.771286 -166.2684)
		(width 0.127)
		(layer "F.Cu")
		(net "I2C_TPM_SDA")
	)
	(segment
		(start 57.039764 -167.377618)
		(end 57.039764 -166.536878)
		(width 0.127)
		(layer "F.Cu")
		(net "I2C_TPM_SDA")
	)
	(segment
		(start 59.857386 -170.168316)
		(end 58.54319 -168.85412)
		(width 0.127)
		(layer "F.Cu")
		(net "I2C_TPM_SDA")
	)
	(segment
		(start 56.780176 -169.19829)
		(end 55.91937 -168.337484)
		(width 0.127)
		(layer "F.Cu")
		(net "I2C_TPM_SDA")
	)
	(segment
		(start 55.91937 -166.33063)
		(end 55.9816 -166.2684)
		(width 0.127)
		(layer "F.Cu")
		(net "I2C_TPM_SDA")
	)
	(segment
		(start 48.5394 -131.1783)
		(end 48.5394 -130.395218)
		(width 0.127)
		(layer "F.Cu")
		(net "I2C_TPM_SDA")
	)
	(via
		(at 48.5394 -130.395218)
		(size 0.508)
		(drill 0.254)
		(layers "F.Cu" "B.Cu")
		(net "I2C_TPM_SDA")
	)
	(via
		(at 75.922378 -128.486154)
		(size 0.508)
		(drill 0.254)
		(layers "F.Cu" "B.Cu")
		(net "I2C_TPM_SDA")
	)
	(via
		(at 59.69 -175.9966)
		(size 0.508)
		(drill 0.254)
		(layers "F.Cu" "B.Cu")
		(net "I2C_TPM_SDA")
	)
	(via
		(at 55.9816 -166.2684)
		(size 0.6604)
		(drill 0.3302)
		(layers "F.Cu" "B.Cu")
		(net "I2C_TPM_SDA")
	)
	(via
		(at 83.099148 -176.981104)
		(size 0.508)
		(drill 0.254)
		(layers "F.Cu" "B.Cu")
		(net "I2C_TPM_SDA")
	)
	(segment
		(start 78.803246 -153.818082)
		(end 78.803246 -154.238706)
		(width 0.127)
		(layer "In2.Cu")
		(net "I2C_TPM_SDA")
	)
	(segment
		(start 77.978 -174.5869)
		(end 80.372204 -176.981104)
		(width 0.127)
		(layer "In2.Cu")
		(net "I2C_TPM_SDA")
	)
	(segment
		(start 75.438 -129.913634)
		(end 76.75499 -131.230624)
		(width 0.127)
		(layer "In2.Cu")
		(net "I2C_TPM_SDA")
	)
	(segment
		(start 76.330556 -133.863588)
		(end 76.330556 -137.79373)
		(width 0.127)
		(layer "In2.Cu")
		(net "I2C_TPM_SDA")
	)
	(segment
		(start 76.62418 -140.06957)
		(end 77.153008 -140.598398)
		(width 0.127)
		(layer "In2.Cu")
		(net "I2C_TPM_SDA")
	)
	(segment
		(start 76.330556 -137.79373)
		(end 76.790804 -138.253978)
		(width 0.127)
		(layer "In2.Cu")
		(net "I2C_TPM_SDA")
	)
	(segment
		(start 78.8924 -166.5605)
		(end 78.440534 -167.012366)
		(width 0.127)
		(layer "In2.Cu")
		(net "I2C_TPM_SDA")
	)
	(segment
		(start 78.8035 -154.23896)
		(end 78.8035 -159.132524)
		(width 0.127)
		(layer "In2.Cu")
		(net "I2C_TPM_SDA")
	)
	(segment
		(start 78.8035 -153.817828)
		(end 78.803246 -153.818082)
		(width 0.127)
		(layer "In2.Cu")
		(net "I2C_TPM_SDA")
	)
	(segment
		(start 77.3049 -141.825472)
		(end 77.3049 -147.429982)
		(width 0.127)
		(layer "In2.Cu")
		(net "I2C_TPM_SDA")
	)
	(segment
		(start 76.75499 -131.230624)
		(end 76.75499 -133.439154)
		(width 0.127)
		(layer "In2.Cu")
		(net "I2C_TPM_SDA")
	)
	(segment
		(start 78.8924 -165.481)
		(end 78.8924 -166.5605)
		(width 0.127)
		(layer "In2.Cu")
		(net "I2C_TPM_SDA")
	)
	(segment
		(start 80.372204 -176.981104)
		(end 83.099148 -176.981104)
		(width 0.127)
		(layer "In2.Cu")
		(net "I2C_TPM_SDA")
	)
	(segment
		(start 78.440534 -169.204132)
		(end 77.978 -169.666666)
		(width 0.127)
		(layer "In2.Cu")
		(net "I2C_TPM_SDA")
	)
	(segment
		(start 77.3049 -147.429982)
		(end 77.5589 -147.683982)
		(width 0.127)
		(layer "In2.Cu")
		(net "I2C_TPM_SDA")
	)
	(segment
		(start 76.790804 -138.253978)
		(end 76.790804 -139.279122)
		(width 0.127)
		(layer "In2.Cu")
		(net "I2C_TPM_SDA")
	)
	(segment
		(start 77.153008 -140.598398)
		(end 77.153008 -141.67358)
		(width 0.127)
		(layer "In2.Cu")
		(net "I2C_TPM_SDA")
	)
	(segment
		(start 80.095598 -164.277802)
		(end 78.8924 -165.481)
		(width 0.127)
		(layer "In2.Cu")
		(net "I2C_TPM_SDA")
	)
	(segment
		(start 75.438 -128.970532)
		(end 75.438 -129.913634)
		(width 0.127)
		(layer "In2.Cu")
		(net "I2C_TPM_SDA")
	)
	(segment
		(start 75.922378 -128.486154)
		(end 75.438 -128.970532)
		(width 0.127)
		(layer "In2.Cu")
		(net "I2C_TPM_SDA")
	)
	(segment
		(start 76.790804 -139.279122)
		(end 76.62418 -139.445746)
		(width 0.127)
		(layer "In2.Cu")
		(net "I2C_TPM_SDA")
	)
	(segment
		(start 78.803246 -154.238706)
		(end 78.8035 -154.23896)
		(width 0.127)
		(layer "In2.Cu")
		(net "I2C_TPM_SDA")
	)
	(segment
		(start 80.095598 -160.424622)
		(end 80.095598 -164.277802)
		(width 0.127)
		(layer "In2.Cu")
		(net "I2C_TPM_SDA")
	)
	(segment
		(start 77.5589 -147.683982)
		(end 77.5589 -150.699216)
		(width 0.127)
		(layer "In2.Cu")
		(net "I2C_TPM_SDA")
	)
	(segment
		(start 78.8035 -151.943816)
		(end 78.8035 -153.817828)
		(width 0.127)
		(layer "In2.Cu")
		(net "I2C_TPM_SDA")
	)
	(segment
		(start 78.440534 -167.012366)
		(end 78.440534 -169.204132)
		(width 0.127)
		(layer "In2.Cu")
		(net "I2C_TPM_SDA")
	)
	(segment
		(start 77.978 -169.666666)
		(end 77.978 -174.5869)
		(width 0.127)
		(layer "In2.Cu")
		(net "I2C_TPM_SDA")
	)
	(segment
		(start 78.8035 -159.132524)
		(end 80.095598 -160.424622)
		(width 0.127)
		(layer "In2.Cu")
		(net "I2C_TPM_SDA")
	)
	(segment
		(start 77.5589 -150.699216)
		(end 78.8035 -151.943816)
		(width 0.127)
		(layer "In2.Cu")
		(net "I2C_TPM_SDA")
	)
	(segment
		(start 76.62418 -139.445746)
		(end 76.62418 -140.06957)
		(width 0.127)
		(layer "In2.Cu")
		(net "I2C_TPM_SDA")
	)
	(segment
		(start 77.153008 -141.67358)
		(end 77.3049 -141.825472)
		(width 0.127)
		(layer "In2.Cu")
		(net "I2C_TPM_SDA")
	)
	(segment
		(start 76.75499 -133.439154)
		(end 76.330556 -133.863588)
		(width 0.127)
		(layer "In2.Cu")
		(net "I2C_TPM_SDA")
	)
	(segment
		(start 48.5394 -130.395218)
		(end 49.156366 -129.778252)
		(width 0.127)
		(layer "In5.Cu")
		(net "I2C_TPM_SDA")
	)
	(segment
		(start 71.562976 -129.424176)
		(end 72.500998 -128.486154)
		(width 0.127)
		(layer "In5.Cu")
		(net "I2C_TPM_SDA")
	)
	(segment
		(start 50.689764 -129.888996)
		(end 52.679854 -129.888996)
		(width 0.127)
		(layer "In5.Cu")
		(net "I2C_TPM_SDA")
	)
	(segment
		(start 68.845176 -129.424176)
		(end 71.562976 -129.424176)
		(width 0.127)
		(layer "In5.Cu")
		(net "I2C_TPM_SDA")
	)
	(segment
		(start 66.8401 -127.4191)
		(end 68.845176 -129.424176)
		(width 0.127)
		(layer "In5.Cu")
		(net "I2C_TPM_SDA")
	)
	(segment
		(start 49.156366 -129.778252)
		(end 49.156366 -129.385314)
		(width 0.127)
		(layer "In5.Cu")
		(net "I2C_TPM_SDA")
	)
	(segment
		(start 66.7131 -175.6537)
		(end 66.928746 -175.438054)
		(width 0.127)
		(layer "In5.Cu")
		(net "I2C_TPM_SDA")
	)
	(segment
		(start 75.416918 -175.4378)
		(end 81.555844 -175.4378)
		(width 0.127)
		(layer "In5.Cu")
		(net "I2C_TPM_SDA")
	)
	(segment
		(start 49.911 -129.110232)
		(end 50.689764 -129.888996)
		(width 0.127)
		(layer "In5.Cu")
		(net "I2C_TPM_SDA")
	)
	(segment
		(start 75.416664 -175.438054)
		(end 75.416918 -175.4378)
		(width 0.127)
		(layer "In5.Cu")
		(net "I2C_TPM_SDA")
	)
	(segment
		(start 66.928746 -175.438054)
		(end 75.416664 -175.438054)
		(width 0.127)
		(layer "In5.Cu")
		(net "I2C_TPM_SDA")
	)
	(segment
		(start 49.431448 -129.110232)
		(end 49.911 -129.110232)
		(width 0.127)
		(layer "In5.Cu")
		(net "I2C_TPM_SDA")
	)
	(segment
		(start 72.500998 -128.486154)
		(end 75.922378 -128.486154)
		(width 0.127)
		(layer "In5.Cu")
		(net "I2C_TPM_SDA")
	)
	(segment
		(start 56.049164 -127.4191)
		(end 66.8401 -127.4191)
		(width 0.127)
		(layer "In5.Cu")
		(net "I2C_TPM_SDA")
	)
	(segment
		(start 49.156366 -129.385314)
		(end 49.431448 -129.110232)
		(width 0.127)
		(layer "In5.Cu")
		(net "I2C_TPM_SDA")
	)
	(segment
		(start 54.220364 -129.2479)
		(end 56.049164 -127.4191)
		(width 0.127)
		(layer "In5.Cu")
		(net "I2C_TPM_SDA")
	)
	(segment
		(start 53.32095 -129.2479)
		(end 54.220364 -129.2479)
		(width 0.127)
		(layer "In5.Cu")
		(net "I2C_TPM_SDA")
	)
	(segment
		(start 81.555844 -175.4378)
		(end 83.099148 -176.981104)
		(width 0.127)
		(layer "In5.Cu")
		(net "I2C_TPM_SDA")
	)
	(segment
		(start 52.679854 -129.888996)
		(end 53.32095 -129.2479)
		(width 0.127)
		(layer "In5.Cu")
		(net "I2C_TPM_SDA")
	)
	(segment
		(start 59.69 -175.9966)
		(end 60.0329 -175.6537)
		(width 0.127)
		(layer "In5.Cu")
		(net "I2C_TPM_SDA")
	)
	(segment
		(start 60.0329 -175.6537)
		(end 66.7131 -175.6537)
		(width 0.127)
		(layer "In5.Cu")
		(net "I2C_TPM_SDA")
	)
	(segment
		(start 55.280052 -174.994824)
		(end 55.280052 -176.672748)
		(width 0.127)
		(layer "F.Cu")
		(net "I2C_TPM_SCL")
	)
	(segment
		(start 46.778418 -129.582418)
		(end 47.540418 -130.344418)
		(width 0.127)
		(layer "F.Cu")
		(net "I2C_TPM_SCL")
	)
	(segment
		(start 46.778418 -128.634236)
		(end 46.778418 -129.582418)
		(width 0.127)
		(layer "F.Cu")
		(net "I2C_TPM_SCL")
	)
	(segment
		(start 47.498 -131.3053)
		(end 47.498 -130.386836)
		(width 0.127)
		(layer "F.Cu")
		(net "I2C_TPM_SCL")
	)
	(segment
		(start 47.498 -130.386836)
		(end 47.540418 -130.344418)
		(width 0.127)
		(layer "F.Cu")
		(net "I2C_TPM_SCL")
	)
	(via
		(at 76.785978 -128.472946)
		(size 0.508)
		(drill 0.254)
		(layers "F.Cu" "B.Cu")
		(net "I2C_TPM_SCL")
	)
	(via
		(at 47.540418 -130.344418)
		(size 0.508)
		(drill 0.254)
		(layers "F.Cu" "B.Cu")
		(net "I2C_TPM_SCL")
	)
	(via
		(at 55.280052 -176.672748)
		(size 0.508)
		(drill 0.254)
		(layers "F.Cu" "B.Cu")
		(net "I2C_TPM_SCL")
	)
	(via
		(at 83.1215 -178.181)
		(size 0.508)
		(drill 0.254)
		(layers "F.Cu" "B.Cu")
		(net "I2C_TPM_SCL")
	)
	(segment
		(start 80.0862 -166.3065)
		(end 78.948534 -167.444166)
		(width 0.127)
		(layer "In2.Cu")
		(net "I2C_TPM_SCL")
	)
	(segment
		(start 77.661008 -141.463014)
		(end 77.8129 -141.614906)
		(width 0.127)
		(layer "In2.Cu")
		(net "I2C_TPM_SCL")
	)
	(segment
		(start 76.838556 -137.583164)
		(end 77.38491 -138.129518)
		(width 0.127)
		(layer "In2.Cu")
		(net "I2C_TPM_SCL")
	)
	(segment
		(start 77.26299 -130.995674)
		(end 77.26299 -133.64972)
		(width 0.127)
		(layer "In2.Cu")
		(net "I2C_TPM_SCL")
	)
	(segment
		(start 80.6069 -160.217358)
		(end 80.6069 -164.5412)
		(width 0.127)
		(layer "In2.Cu")
		(net "I2C_TPM_SCL")
	)
	(segment
		(start 76.838556 -134.074154)
		(end 76.838556 -137.583164)
		(width 0.127)
		(layer "In2.Cu")
		(net "I2C_TPM_SCL")
	)
	(segment
		(start 78.486 -174.376334)
		(end 80.436466 -176.3268)
		(width 0.127)
		(layer "In2.Cu")
		(net "I2C_TPM_SCL")
	)
	(segment
		(start 77.8129 -147.219416)
		(end 78.0669 -147.473416)
		(width 0.127)
		(layer "In2.Cu")
		(net "I2C_TPM_SCL")
	)
	(segment
		(start 79.3115 -151.655018)
		(end 79.3115 -158.921958)
		(width 0.127)
		(layer "In2.Cu")
		(net "I2C_TPM_SCL")
	)
	(segment
		(start 76.785978 -128.472946)
		(end 76.785978 -130.518662)
		(width 0.127)
		(layer "In2.Cu")
		(net "I2C_TPM_SCL")
	)
	(segment
		(start 76.785978 -130.518662)
		(end 77.26299 -130.995674)
		(width 0.127)
		(layer "In2.Cu")
		(net "I2C_TPM_SCL")
	)
	(segment
		(start 78.7654 -150.08606)
		(end 78.7654 -151.108918)
		(width 0.127)
		(layer "In2.Cu")
		(net "I2C_TPM_SCL")
	)
	(segment
		(start 77.38491 -138.658854)
		(end 77.661008 -138.934952)
		(width 0.127)
		(layer "In2.Cu")
		(net "I2C_TPM_SCL")
	)
	(segment
		(start 77.8129 -141.614906)
		(end 77.8129 -147.219416)
		(width 0.127)
		(layer "In2.Cu")
		(net "I2C_TPM_SCL")
	)
	(segment
		(start 78.948534 -167.444166)
		(end 78.948534 -169.414698)
		(width 0.127)
		(layer "In2.Cu")
		(net "I2C_TPM_SCL")
	)
	(segment
		(start 83.2104 -176.3268)
		(end 83.6295 -176.7459)
		(width 0.127)
		(layer "In2.Cu")
		(net "I2C_TPM_SCL")
	)
	(segment
		(start 79.3115 -158.921958)
		(end 80.6069 -160.217358)
		(width 0.127)
		(layer "In2.Cu")
		(net "I2C_TPM_SCL")
	)
	(segment
		(start 78.486 -169.877232)
		(end 78.486 -174.376334)
		(width 0.127)
		(layer "In2.Cu")
		(net "I2C_TPM_SCL")
	)
	(segment
		(start 83.6295 -177.673)
		(end 83.1215 -178.181)
		(width 0.127)
		(layer "In2.Cu")
		(net "I2C_TPM_SCL")
	)
	(segment
		(start 77.38491 -138.129518)
		(end 77.38491 -138.658854)
		(width 0.127)
		(layer "In2.Cu")
		(net "I2C_TPM_SCL")
	)
	(segment
		(start 78.7654 -151.108918)
		(end 79.3115 -151.655018)
		(width 0.127)
		(layer "In2.Cu")
		(net "I2C_TPM_SCL")
	)
	(segment
		(start 78.948534 -169.414698)
		(end 78.486 -169.877232)
		(width 0.127)
		(layer "In2.Cu")
		(net "I2C_TPM_SCL")
	)
	(segment
		(start 77.26299 -133.64972)
		(end 76.838556 -134.074154)
		(width 0.127)
		(layer "In2.Cu")
		(net "I2C_TPM_SCL")
	)
	(segment
		(start 80.6069 -164.5412)
		(end 80.0862 -165.0619)
		(width 0.127)
		(layer "In2.Cu")
		(net "I2C_TPM_SCL")
	)
	(segment
		(start 83.6295 -176.7459)
		(end 83.6295 -177.673)
		(width 0.127)
		(layer "In2.Cu")
		(net "I2C_TPM_SCL")
	)
	(segment
		(start 80.0862 -165.0619)
		(end 80.0862 -166.3065)
		(width 0.127)
		(layer "In2.Cu")
		(net "I2C_TPM_SCL")
	)
	(segment
		(start 77.661008 -138.934952)
		(end 77.661008 -141.463014)
		(width 0.127)
		(layer "In2.Cu")
		(net "I2C_TPM_SCL")
	)
	(segment
		(start 78.0669 -149.38756)
		(end 78.7654 -150.08606)
		(width 0.127)
		(layer "In2.Cu")
		(net "I2C_TPM_SCL")
	)
	(segment
		(start 80.436466 -176.3268)
		(end 83.2104 -176.3268)
		(width 0.127)
		(layer "In2.Cu")
		(net "I2C_TPM_SCL")
	)
	(segment
		(start 78.0669 -147.473416)
		(end 78.0669 -149.38756)
		(width 0.127)
		(layer "In2.Cu")
		(net "I2C_TPM_SCL")
	)
	(segment
		(start 83.1215 -178.181)
		(end 82.826606 -178.153568)
		(width 0.127)
		(layer "In5.Cu")
		(net "I2C_TPM_SCL")
	)
	(segment
		(start 71.549514 -128.719072)
		(end 72.506332 -127.762254)
		(width 0.127)
		(layer "In5.Cu")
		(net "I2C_TPM_SCL")
	)
	(segment
		(start 47.540418 -130.344418)
		(end 47.540418 -129.66573)
		(width 0.127)
		(layer "In5.Cu")
		(net "I2C_TPM_SCL")
	)
	(segment
		(start 47.540418 -129.66573)
		(end 48.603916 -128.602232)
		(width 0.127)
		(layer "In5.Cu")
		(net "I2C_TPM_SCL")
	)
	(segment
		(start 54.009798 -128.7399)
		(end 55.881524 -126.868174)
		(width 0.127)
		(layer "In5.Cu")
		(net "I2C_TPM_SCL")
	)
	(segment
		(start 82.4738 -178.0286)
		(end 80.391 -175.9458)
		(width 0.127)
		(layer "In5.Cu")
		(net "I2C_TPM_SCL")
	)
	(segment
		(start 50.243232 -128.602232)
		(end 50.7365 -129.0955)
		(width 0.127)
		(layer "In5.Cu")
		(net "I2C_TPM_SCL")
	)
	(segment
		(start 75.627484 -175.9458)
		(end 75.62723 -175.946054)
		(width 0.127)
		(layer "In5.Cu")
		(net "I2C_TPM_SCL")
	)
	(segment
		(start 57.7977 -176.1617)
		(end 55.7911 -176.1617)
		(width 0.127)
		(layer "In5.Cu")
		(net "I2C_TPM_SCL")
	)
	(segment
		(start 73.4314 -176.784)
		(end 58.42 -176.784)
		(width 0.127)
		(layer "In5.Cu")
		(net "I2C_TPM_SCL")
	)
	(segment
		(start 82.701638 -178.0286)
		(end 82.4738 -178.0286)
		(width 0.127)
		(layer "In5.Cu")
		(net "I2C_TPM_SCL")
	)
	(segment
		(start 74.269346 -175.946054)
		(end 73.4314 -176.784)
		(width 0.127)
		(layer "In5.Cu")
		(net "I2C_TPM_SCL")
	)
	(segment
		(start 52.190396 -128.7399)
		(end 54.009798 -128.7399)
		(width 0.127)
		(layer "In5.Cu")
		(net "I2C_TPM_SCL")
	)
	(segment
		(start 75.62723 -175.946054)
		(end 74.269346 -175.946054)
		(width 0.127)
		(layer "In5.Cu")
		(net "I2C_TPM_SCL")
	)
	(segment
		(start 68.876672 -128.719072)
		(end 71.549514 -128.719072)
		(width 0.127)
		(layer "In5.Cu")
		(net "I2C_TPM_SCL")
	)
	(segment
		(start 48.603916 -128.602232)
		(end 50.243232 -128.602232)
		(width 0.127)
		(layer "In5.Cu")
		(net "I2C_TPM_SCL")
	)
	(segment
		(start 80.391 -175.9458)
		(end 75.627484 -175.9458)
		(width 0.127)
		(layer "In5.Cu")
		(net "I2C_TPM_SCL")
	)
	(segment
		(start 51.834796 -129.0955)
		(end 52.190396 -128.7399)
		(width 0.127)
		(layer "In5.Cu")
		(net "I2C_TPM_SCL")
	)
	(segment
		(start 55.881524 -126.868174)
		(end 67.025774 -126.868174)
		(width 0.127)
		(layer "In5.Cu")
		(net "I2C_TPM_SCL")
	)
	(segment
		(start 67.025774 -126.868174)
		(end 68.876672 -128.719072)
		(width 0.127)
		(layer "In5.Cu")
		(net "I2C_TPM_SCL")
	)
	(segment
		(start 55.7911 -176.1617)
		(end 55.280052 -176.672748)
		(width 0.127)
		(layer "In5.Cu")
		(net "I2C_TPM_SCL")
	)
	(segment
		(start 72.506332 -127.762254)
		(end 76.075286 -127.762254)
		(width 0.127)
		(layer "In5.Cu")
		(net "I2C_TPM_SCL")
	)
	(segment
		(start 58.42 -176.784)
		(end 57.7977 -176.1617)
		(width 0.127)
		(layer "In5.Cu")
		(net "I2C_TPM_SCL")
	)
	(segment
		(start 82.826606 -178.153568)
		(end 82.701638 -178.0286)
		(width 0.127)
		(layer "In5.Cu")
		(net "I2C_TPM_SCL")
	)
	(segment
		(start 76.075286 -127.762254)
		(end 76.785978 -128.472946)
		(width 0.127)
		(layer "In5.Cu")
		(net "I2C_TPM_SCL")
	)
	(segment
		(start 50.7365 -129.0955)
		(end 51.834796 -129.0955)
		(width 0.127)
		(layer "In5.Cu")
		(net "I2C_TPM_SCL")
	)
	(segment
		(start 62.188598 -141.391132)
		(end 63.499492 -140.080238)
		(width 0.127)
		(layer "F.Cu")
		(net "I2C_M2_2_SDA")
	)
	(segment
		(start 64.725296 -140.223494)
		(end 64.554862 -140.05306)
		(width 0.127)
		(layer "F.Cu")
		(net "I2C_M2_2_SDA")
	)
	(segment
		(start 63.499492 -140.080238)
		(end 63.499492 -139.755626)
		(width 0.127)
		(layer "F.Cu")
		(net "I2C_M2_2_SDA")
	)
	(segment
		(start 63.930276 -139.755626)
		(end 63.499492 -139.755626)
		(width 0.127)
		(layer "F.Cu")
		(net "I2C_M2_2_SDA")
	)
	(segment
		(start 61.72708 -141.391132)
		(end 62.188598 -141.391132)
		(width 0.127)
		(layer "F.Cu")
		(net "I2C_M2_2_SDA")
	)
	(segment
		(start 64.554862 -140.05306)
		(end 64.22771 -140.05306)
		(width 0.127)
		(layer "F.Cu")
		(net "I2C_M2_2_SDA")
	)
	(segment
		(start 64.22771 -140.05306)
		(end 63.930276 -139.755626)
		(width 0.127)
		(layer "F.Cu")
		(net "I2C_M2_2_SDA")
	)
	(segment
		(start 57.876186 -141.745462)
		(end 58.185304 -141.745462)
		(width 0.127)
		(layer "B.Cu")
		(net "I2C_M2_2_SCL")
	)
	(segment
		(start 58.185304 -141.745462)
		(end 58.970418 -140.960348)
		(width 0.127)
		(layer "B.Cu")
		(net "I2C_M2_2_SCL")
	)
	(segment
		(start 58.970418 -140.960348)
		(end 59.667648 -140.960348)
		(width 0.127)
		(layer "B.Cu")
		(net "I2C_M2_2_SCL")
	)
	(segment
		(start 59.667648 -140.960348)
		(end 60.5663 -141.859)
		(width 0.127)
		(layer "B.Cu")
		(net "I2C_M2_2_SCL")
	)
	(segment
		(start 42.8752 -159.3977)
		(end 43.9166 -158.3563)
		(width 0.127)
		(layer "F.Cu")
		(net "I2C_M2_1_SDA")
	)
	(segment
		(start 42.8752 -159.8549)
		(end 43.942 -160.9217)
		(width 0.127)
		(layer "F.Cu")
		(net "I2C_M2_1_SDA")
	)
	(segment
		(start 42.8752 -159.6136)
		(end 42.8752 -159.8549)
		(width 0.127)
		(layer "F.Cu")
		(net "I2C_M2_1_SDA")
	)
	(segment
		(start 42.8752 -159.6136)
		(end 42.8752 -159.3977)
		(width 0.127)
		(layer "F.Cu")
		(net "I2C_M2_1_SDA")
	)
	(segment
		(start 44.2214 -160.1597)
		(end 44.9834 -160.9217)
		(width 0.127)
		(layer "F.Cu")
		(net "I2C_M2_1_SCL")
	)
	(segment
		(start 44.2214 -159.7406)
		(end 44.2214 -159.2072)
		(width 0.127)
		(layer "F.Cu")
		(net "I2C_M2_1_SCL")
	)
	(segment
		(start 44.2214 -159.7406)
		(end 44.2214 -160.1597)
		(width 0.127)
		(layer "F.Cu")
		(net "I2C_M2_1_SCL")
	)
	(segment
		(start 44.958 -158.4706)
		(end 44.958 -158.3563)
		(width 0.127)
		(layer "F.Cu")
		(net "I2C_M2_1_SCL")
	)
	(segment
		(start 44.2214 -159.2072)
		(end 44.958 -158.4706)
		(width 0.127)
		(layer "F.Cu")
		(net "I2C_M2_1_SCL")
	)
	(segment
		(start 97.751646 -132.506974)
		(end 96.288352 -132.506974)
		(width 0.127)
		(layer "F.Cu")
		(net "I2C_IOM_SDA")
	)
	(segment
		(start 125.3363 -5.5372)
		(end 125.2855 -5.588)
		(width 0.127)
		(layer "F.Cu")
		(net "I2C_IOM_SDA")
	)
	(segment
		(start 107.52836 -18.191734)
		(end 106.412792 -19.307302)
		(width 0.127)
		(layer "F.Cu")
		(net "I2C_IOM_SDA")
	)
	(segment
		(start 97.962212 -26.401014)
		(end 97.962212 -40.718994)
		(width 0.127)
		(layer "F.Cu")
		(net "I2C_IOM_SDA")
	)
	(segment
		(start 105.055924 -19.307302)
		(end 97.962212 -26.401014)
		(width 0.127)
		(layer "F.Cu")
		(net "I2C_IOM_SDA")
	)
	(segment
		(start 124.784358 -4.79298)
		(end 124.93498 -4.79298)
		(width 0.127)
		(layer "F.Cu")
		(net "I2C_IOM_SDA")
	)
	(segment
		(start 124.78258 -4.794758)
		(end 124.784358 -4.79298)
		(width 0.127)
		(layer "F.Cu")
		(net "I2C_IOM_SDA")
	)
	(segment
		(start 97.962212 -40.718994)
		(end 98.101404 -40.858186)
		(width 0.127)
		(layer "F.Cu")
		(net "I2C_IOM_SDA")
	)
	(segment
		(start 98.101404 -40.858186)
		(end 98.397822 -40.858186)
		(width 0.127)
		(layer "F.Cu")
		(net "I2C_IOM_SDA")
	)
	(segment
		(start 124.93498 -4.79298)
		(end 125.3363 -5.1943)
		(width 0.127)
		(layer "F.Cu")
		(net "I2C_IOM_SDA")
	)
	(segment
		(start 106.412792 -19.307302)
		(end 105.055924 -19.307302)
		(width 0.127)
		(layer "F.Cu")
		(net "I2C_IOM_SDA")
	)
	(segment
		(start 125.3363 -5.1943)
		(end 125.3363 -5.5372)
		(width 0.127)
		(layer "F.Cu")
		(net "I2C_IOM_SDA")
	)
	(via
		(at 46.93412 -133.85546)
		(size 0.508)
		(drill 0.254)
		(layers "F.Cu" "B.Cu")
		(net "I2C_IOM_SDA")
	)
	(via
		(at 51.376834 -120.888252)
		(size 0.6096)
		(drill 0.3048)
		(layers "F.Cu" "B.Cu")
		(net "I2C_IOM_SDA")
	)
	(via
		(at 98.398584 -116.364004)
		(size 0.508)
		(drill 0.254)
		(layers "F.Cu" "B.Cu")
		(net "I2C_IOM_SDA")
	)
	(via
		(at 124.78258 -4.794758)
		(size 0.508)
		(drill 0.254)
		(layers "F.Cu" "B.Cu")
		(net "I2C_IOM_SDA")
	)
	(via
		(at 98.397822 -40.858186)
		(size 0.508)
		(drill 0.254)
		(layers "F.Cu" "B.Cu")
		(net "I2C_IOM_SDA")
	)
	(via
		(at 97.751646 -132.506974)
		(size 0.508)
		(drill 0.254)
		(layers "F.Cu" "B.Cu")
		(net "I2C_IOM_SDA")
	)
	(via
		(at 107.52836 -18.191734)
		(size 0.508)
		(drill 0.254)
		(layers "F.Cu" "B.Cu")
		(net "I2C_IOM_SDA")
	)
	(via
		(at 110.1344 -5.0546)
		(size 0.508)
		(drill 0.254)
		(layers "F.Cu" "B.Cu")
		(net "I2C_IOM_SDA")
	)
	(via
		(at 49.196244 -116.788946)
		(size 0.508)
		(drill 0.254)
		(layers "F.Cu" "B.Cu")
		(net "I2C_IOM_SDA")
	)
	(segment
		(start 45.5168 -134.2263)
		(end 46.56328 -134.2263)
		(width 0.127)
		(layer "B.Cu")
		(net "I2C_IOM_SDA")
	)
	(segment
		(start 108.76534 -14.335252)
		(end 108.76534 -16.954754)
		(width 0.127)
		(layer "B.Cu")
		(net "I2C_IOM_SDA")
	)
	(segment
		(start 110.1344 -5.0546)
		(end 110.0836 -5.1054)
		(width 0.127)
		(layer "B.Cu")
		(net "I2C_IOM_SDA")
	)
	(segment
		(start 51.8922 -119.311674)
		(end 49.369472 -116.788946)
		(width 0.127)
		(layer "B.Cu")
		(net "I2C_IOM_SDA")
	)
	(segment
		(start 110.0836 -5.1054)
		(end 110.0836 -6.617462)
		(width 0.127)
		(layer "B.Cu")
		(net "I2C_IOM_SDA")
	)
	(segment
		(start 109.918754 -6.782308)
		(end 109.918754 -13.181838)
		(width 0.127)
		(layer "B.Cu")
		(net "I2C_IOM_SDA")
	)
	(segment
		(start 108.76534 -16.954754)
		(end 107.52836 -18.191734)
		(width 0.127)
		(layer "B.Cu")
		(net "I2C_IOM_SDA")
	)
	(segment
		(start 51.376834 -120.888252)
		(end 51.501548 -120.888252)
		(width 0.127)
		(layer "B.Cu")
		(net "I2C_IOM_SDA")
	)
	(segment
		(start 109.918754 -13.181838)
		(end 108.76534 -14.335252)
		(width 0.127)
		(layer "B.Cu")
		(net "I2C_IOM_SDA")
	)
	(segment
		(start 49.369472 -116.788946)
		(end 49.196244 -116.788946)
		(width 0.127)
		(layer "B.Cu")
		(net "I2C_IOM_SDA")
	)
	(segment
		(start 50.25771 -120.888252)
		(end 51.376834 -120.888252)
		(width 0.127)
		(layer "B.Cu")
		(net "I2C_IOM_SDA")
	)
	(segment
		(start 51.501548 -120.888252)
		(end 51.8922 -120.4976)
		(width 0.127)
		(layer "B.Cu")
		(net "I2C_IOM_SDA")
	)
	(segment
		(start 46.56328 -134.2263)
		(end 46.93412 -133.85546)
		(width 0.127)
		(layer "B.Cu")
		(net "I2C_IOM_SDA")
	)
	(segment
		(start 51.8922 -120.4976)
		(end 51.8922 -119.311674)
		(width 0.127)
		(layer "B.Cu")
		(net "I2C_IOM_SDA")
	)
	(segment
		(start 45.3644 -134.3787)
		(end 45.5168 -134.2263)
		(width 0.127)
		(layer "B.Cu")
		(net "I2C_IOM_SDA")
	)
	(segment
		(start 45.3644 -135.2169)
		(end 45.3644 -134.3787)
		(width 0.127)
		(layer "B.Cu")
		(net "I2C_IOM_SDA")
	)
	(segment
		(start 110.0836 -6.617462)
		(end 109.918754 -6.782308)
		(width 0.127)
		(layer "B.Cu")
		(net "I2C_IOM_SDA")
	)
	(segment
		(start 47.5488 -122.587766)
		(end 47.5488 -124.1425)
		(width 0.127)
		(layer "In2.Cu")
		(net "I2C_IOM_SDA")
	)
	(segment
		(start 98.398584 -117.907816)
		(end 97.663 -118.6434)
		(width 0.127)
		(layer "In2.Cu")
		(net "I2C_IOM_SDA")
	)
	(segment
		(start 47.523146 -129.692654)
		(end 47.070518 -130.145282)
		(width 0.127)
		(layer "In2.Cu")
		(net "I2C_IOM_SDA")
	)
	(segment
		(start 97.663 -118.6434)
		(end 97.663 -121.416826)
		(width 0.127)
		(layer "In2.Cu")
		(net "I2C_IOM_SDA")
	)
	(segment
		(start 49.196244 -120.940322)
		(end 47.5488 -122.587766)
		(width 0.127)
		(layer "In2.Cu")
		(net "I2C_IOM_SDA")
	)
	(segment
		(start 97.467166 -121.61266)
		(end 97.467166 -129.616708)
		(width 0.127)
		(layer "In2.Cu")
		(net "I2C_IOM_SDA")
	)
	(segment
		(start 48.5013 -127.775716)
		(end 47.523146 -128.75387)
		(width 0.127)
		(layer "In2.Cu")
		(net "I2C_IOM_SDA")
	)
	(segment
		(start 98.398584 -116.364004)
		(end 98.398584 -117.907816)
		(width 0.127)
		(layer "In2.Cu")
		(net "I2C_IOM_SDA")
	)
	(segment
		(start 97.467166 -129.616708)
		(end 98.229166 -130.378708)
		(width 0.127)
		(layer "In2.Cu")
		(net "I2C_IOM_SDA")
	)
	(segment
		(start 98.229166 -130.378708)
		(end 98.229166 -132.029454)
		(width 0.127)
		(layer "In2.Cu")
		(net "I2C_IOM_SDA")
	)
	(segment
		(start 98.229166 -132.029454)
		(end 97.751646 -132.506974)
		(width 0.127)
		(layer "In2.Cu")
		(net "I2C_IOM_SDA")
	)
	(segment
		(start 47.070518 -130.145282)
		(end 47.070518 -133.719062)
		(width 0.127)
		(layer "In2.Cu")
		(net "I2C_IOM_SDA")
	)
	(segment
		(start 47.5488 -124.1425)
		(end 48.5013 -125.095)
		(width 0.127)
		(layer "In2.Cu")
		(net "I2C_IOM_SDA")
	)
	(segment
		(start 48.5013 -125.095)
		(end 48.5013 -127.775716)
		(width 0.127)
		(layer "In2.Cu")
		(net "I2C_IOM_SDA")
	)
	(segment
		(start 47.523146 -128.75387)
		(end 47.523146 -129.692654)
		(width 0.127)
		(layer "In2.Cu")
		(net "I2C_IOM_SDA")
	)
	(segment
		(start 47.070518 -133.719062)
		(end 46.93412 -133.85546)
		(width 0.127)
		(layer "In2.Cu")
		(net "I2C_IOM_SDA")
	)
	(segment
		(start 49.196244 -116.788946)
		(end 49.196244 -120.940322)
		(width 0.127)
		(layer "In2.Cu")
		(net "I2C_IOM_SDA")
	)
	(segment
		(start 97.663 -121.416826)
		(end 97.467166 -121.61266)
		(width 0.127)
		(layer "In2.Cu")
		(net "I2C_IOM_SDA")
	)
	(segment
		(start 101.292914 -42.334434)
		(end 101.292914 -45.995082)
		(width 0.127)
		(layer "In5.Cu")
		(net "I2C_IOM_SDA")
	)
	(segment
		(start 99.426776 -93.690694)
		(end 99.426776 -115.335812)
		(width 0.127)
		(layer "In5.Cu")
		(net "I2C_IOM_SDA")
	)
	(segment
		(start 116.5098 -5.0546)
		(end 110.1344 -5.0546)
		(width 0.127)
		(layer "In5.Cu")
		(net "I2C_IOM_SDA")
	)
	(segment
		(start 124.78258 -4.794758)
		(end 124.741686 -4.794758)
		(width 0.127)
		(layer "In5.Cu")
		(net "I2C_IOM_SDA")
	)
	(segment
		(start 100.670106 -46.61789)
		(end 100.670106 -83.064096)
		(width 0.127)
		(layer "In5.Cu")
		(net "I2C_IOM_SDA")
	)
	(segment
		(start 100.670106 -83.064096)
		(end 96.15678 -87.577422)
		(width 0.127)
		(layer "In5.Cu")
		(net "I2C_IOM_SDA")
	)
	(segment
		(start 98.397822 -40.858186)
		(end 99.816666 -40.858186)
		(width 0.127)
		(layer "In5.Cu")
		(net "I2C_IOM_SDA")
	)
	(segment
		(start 96.15678 -90.420698)
		(end 99.426776 -93.690694)
		(width 0.127)
		(layer "In5.Cu")
		(net "I2C_IOM_SDA")
	)
	(segment
		(start 99.426776 -115.335812)
		(end 98.398584 -116.364004)
		(width 0.127)
		(layer "In5.Cu")
		(net "I2C_IOM_SDA")
	)
	(segment
		(start 49.678844 -116.306346)
		(end 55.221632 -116.306346)
		(width 0.127)
		(layer "In5.Cu")
		(net "I2C_IOM_SDA")
	)
	(segment
		(start 101.292914 -45.995082)
		(end 100.670106 -46.61789)
		(width 0.127)
		(layer "In5.Cu")
		(net "I2C_IOM_SDA")
	)
	(segment
		(start 87.0458 -117.0432)
		(end 89.0524 -119.0498)
		(width 0.127)
		(layer "In5.Cu")
		(net "I2C_IOM_SDA")
	)
	(segment
		(start 123.587256 -5.949188)
		(end 117.404388 -5.949188)
		(width 0.127)
		(layer "In5.Cu")
		(net "I2C_IOM_SDA")
	)
	(segment
		(start 99.816666 -40.858186)
		(end 101.292914 -42.334434)
		(width 0.127)
		(layer "In5.Cu")
		(net "I2C_IOM_SDA")
	)
	(segment
		(start 66.634868 -116.6368)
		(end 67.879468 -115.3922)
		(width 0.127)
		(layer "In5.Cu")
		(net "I2C_IOM_SDA")
	)
	(segment
		(start 95.304864 -119.0498)
		(end 97.99066 -116.364004)
		(width 0.127)
		(layer "In5.Cu")
		(net "I2C_IOM_SDA")
	)
	(segment
		(start 55.221632 -116.306346)
		(end 55.552086 -116.6368)
		(width 0.127)
		(layer "In5.Cu")
		(net "I2C_IOM_SDA")
	)
	(segment
		(start 67.879468 -115.3922)
		(end 70.2564 -115.3922)
		(width 0.127)
		(layer "In5.Cu")
		(net "I2C_IOM_SDA")
	)
	(segment
		(start 96.15678 -87.577422)
		(end 96.15678 -90.420698)
		(width 0.127)
		(layer "In5.Cu")
		(net "I2C_IOM_SDA")
	)
	(segment
		(start 87.0458 -115.842034)
		(end 87.0458 -117.0432)
		(width 0.127)
		(layer "In5.Cu")
		(net "I2C_IOM_SDA")
	)
	(segment
		(start 124.741686 -4.794758)
		(end 123.587256 -5.949188)
		(width 0.127)
		(layer "In5.Cu")
		(net "I2C_IOM_SDA")
	)
	(segment
		(start 83.344766 -112.141)
		(end 87.0458 -115.842034)
		(width 0.127)
		(layer "In5.Cu")
		(net "I2C_IOM_SDA")
	)
	(segment
		(start 55.552086 -116.6368)
		(end 66.634868 -116.6368)
		(width 0.127)
		(layer "In5.Cu")
		(net "I2C_IOM_SDA")
	)
	(segment
		(start 117.404388 -5.949188)
		(end 116.5098 -5.0546)
		(width 0.127)
		(layer "In5.Cu")
		(net "I2C_IOM_SDA")
	)
	(segment
		(start 89.0524 -119.0498)
		(end 95.304864 -119.0498)
		(width 0.127)
		(layer "In5.Cu")
		(net "I2C_IOM_SDA")
	)
	(segment
		(start 49.196244 -116.788946)
		(end 49.678844 -116.306346)
		(width 0.127)
		(layer "In5.Cu")
		(net "I2C_IOM_SDA")
	)
	(segment
		(start 70.9676 -114.681)
		(end 74.549 -114.681)
		(width 0.127)
		(layer "In5.Cu")
		(net "I2C_IOM_SDA")
	)
	(segment
		(start 97.99066 -116.364004)
		(end 98.398584 -116.364004)
		(width 0.127)
		(layer "In5.Cu")
		(net "I2C_IOM_SDA")
	)
	(segment
		(start 77.089 -112.141)
		(end 83.344766 -112.141)
		(width 0.127)
		(layer "In5.Cu")
		(net "I2C_IOM_SDA")
	)
	(segment
		(start 74.549 -114.681)
		(end 77.089 -112.141)
		(width 0.127)
		(layer "In5.Cu")
		(net "I2C_IOM_SDA")
	)
	(segment
		(start 70.2564 -115.3922)
		(end 70.9676 -114.681)
		(width 0.127)
		(layer "In5.Cu")
		(net "I2C_IOM_SDA")
	)
	(segment
		(start 97.751646 -133.476746)
		(end 97.451418 -133.776974)
		(width 0.127)
		(layer "F.Cu")
		(net "I2C_IOM_SCL")
	)
	(segment
		(start 106.594148 -18.142204)
		(end 105.93705 -18.799302)
		(width 0.127)
		(layer "F.Cu")
		(net "I2C_IOM_SCL")
	)
	(segment
		(start 126.09322 -5.81406)
		(end 125.88494 -5.81406)
		(width 0.127)
		(layer "F.Cu")
		(net "I2C_IOM_SCL")
	)
	(segment
		(start 97.451418 -133.776974)
		(end 96.288352 -133.776974)
		(width 0.127)
		(layer "F.Cu")
		(net "I2C_IOM_SCL")
	)
	(segment
		(start 97.454212 -40.92956)
		(end 98.349308 -41.824656)
		(width 0.127)
		(layer "F.Cu")
		(net "I2C_IOM_SCL")
	)
	(segment
		(start 125.88494 -5.81406)
		(end 125.2855 -6.4135)
		(width 0.127)
		(layer "F.Cu")
		(net "I2C_IOM_SCL")
	)
	(segment
		(start 97.454212 -26.115264)
		(end 97.454212 -40.92956)
		(width 0.127)
		(layer "F.Cu")
		(net "I2C_IOM_SCL")
	)
	(segment
		(start 125.2855 -6.4135)
		(end 125.2855 -6.604)
		(width 0.127)
		(layer "F.Cu")
		(net "I2C_IOM_SCL")
	)
	(segment
		(start 104.770174 -18.799302)
		(end 97.454212 -26.115264)
		(width 0.127)
		(layer "F.Cu")
		(net "I2C_IOM_SCL")
	)
	(segment
		(start 105.93705 -18.799302)
		(end 104.770174 -18.799302)
		(width 0.127)
		(layer "F.Cu")
		(net "I2C_IOM_SCL")
	)
	(via
		(at 109.4232 -5.6388)
		(size 0.508)
		(drill 0.254)
		(layers "F.Cu" "B.Cu")
		(net "I2C_IOM_SCL")
	)
	(via
		(at 98.349308 -41.824656)
		(size 0.508)
		(drill 0.254)
		(layers "F.Cu" "B.Cu")
		(net "I2C_IOM_SCL")
	)
	(via
		(at 126.09322 -5.81406)
		(size 0.508)
		(drill 0.254)
		(layers "F.Cu" "B.Cu")
		(net "I2C_IOM_SCL")
	)
	(via
		(at 98.4123 -115.457732)
		(size 0.508)
		(drill 0.254)
		(layers "F.Cu" "B.Cu")
		(net "I2C_IOM_SCL")
	)
	(via
		(at 51.35626 -119.637556)
		(size 0.6096)
		(drill 0.3048)
		(layers "F.Cu" "B.Cu")
		(net "I2C_IOM_SCL")
	)
	(via
		(at 46.3042 -129.4384)
		(size 0.508)
		(drill 0.254)
		(layers "F.Cu" "B.Cu")
		(net "I2C_IOM_SCL")
	)
	(via
		(at 97.751646 -133.476746)
		(size 0.508)
		(drill 0.254)
		(layers "F.Cu" "B.Cu")
		(net "I2C_IOM_SCL")
	)
	(via
		(at 48.330612 -116.80571)
		(size 0.508)
		(drill 0.254)
		(layers "F.Cu" "B.Cu")
		(net "I2C_IOM_SCL")
	)
	(via
		(at 106.594148 -18.142204)
		(size 0.508)
		(drill 0.254)
		(layers "F.Cu" "B.Cu")
		(net "I2C_IOM_SCL")
	)
	(segment
		(start 48.929036 -117.404134)
		(end 49.205134 -117.404134)
		(width 0.127)
		(layer "B.Cu")
		(net "I2C_IOM_SCL")
	)
	(segment
		(start 109.4232 -5.6388)
		(end 109.4232 -6.559296)
		(width 0.127)
		(layer "B.Cu")
		(net "I2C_IOM_SCL")
	)
	(segment
		(start 51.146964 -119.846852)
		(end 50.23231 -119.846852)
		(width 0.127)
		(layer "B.Cu")
		(net "I2C_IOM_SCL")
	)
	(segment
		(start 46.449996 -128.721104)
		(end 46.449996 -129.267204)
		(width 0.127)
		(layer "B.Cu")
		(net "I2C_IOM_SCL")
	)
	(segment
		(start 108.25734 -16.479012)
		(end 106.594148 -18.142204)
		(width 0.127)
		(layer "B.Cu")
		(net "I2C_IOM_SCL")
	)
	(segment
		(start 46.3042 -129.413)
		(end 46.3042 -129.4384)
		(width 0.127)
		(layer "B.Cu")
		(net "I2C_IOM_SCL")
	)
	(segment
		(start 108.25734 -14.124686)
		(end 108.25734 -16.479012)
		(width 0.127)
		(layer "B.Cu")
		(net "I2C_IOM_SCL")
	)
	(segment
		(start 48.330612 -116.80571)
		(end 48.929036 -117.404134)
		(width 0.127)
		(layer "B.Cu")
		(net "I2C_IOM_SCL")
	)
	(segment
		(start 46.449996 -129.267204)
		(end 46.3042 -129.413)
		(width 0.127)
		(layer "B.Cu")
		(net "I2C_IOM_SCL")
	)
	(segment
		(start 51.35626 -119.55526)
		(end 51.35626 -119.637556)
		(width 0.127)
		(layer "B.Cu")
		(net "I2C_IOM_SCL")
	)
	(segment
		(start 109.4232 -6.559296)
		(end 109.410754 -6.571742)
		(width 0.127)
		(layer "B.Cu")
		(net "I2C_IOM_SCL")
	)
	(segment
		(start 109.410754 -12.971272)
		(end 108.25734 -14.124686)
		(width 0.127)
		(layer "B.Cu")
		(net "I2C_IOM_SCL")
	)
	(segment
		(start 109.410754 -6.571742)
		(end 109.410754 -12.971272)
		(width 0.127)
		(layer "B.Cu")
		(net "I2C_IOM_SCL")
	)
	(segment
		(start 49.205134 -117.404134)
		(end 51.35626 -119.55526)
		(width 0.127)
		(layer "B.Cu")
		(net "I2C_IOM_SCL")
	)
	(segment
		(start 47.5742 -128.6383)
		(end 47.54118 -128.67132)
		(width 0.127)
		(layer "B.Cu")
		(net "I2C_IOM_SCL")
	)
	(segment
		(start 51.35626 -119.637556)
		(end 51.146964 -119.846852)
		(width 0.127)
		(layer "B.Cu")
		(net "I2C_IOM_SCL")
	)
	(segment
		(start 47.54118 -128.67132)
		(end 46.51502 -128.67132)
		(width 0.127)
		(layer "B.Cu")
		(net "I2C_IOM_SCL")
	)
	(segment
		(start 46.51502 -128.67132)
		(end 46.5074 -128.6637)
		(width 0.127)
		(layer "B.Cu")
		(net "I2C_IOM_SCL")
	)
	(segment
		(start 46.5074 -128.6637)
		(end 46.449996 -128.721104)
		(width 0.127)
		(layer "B.Cu")
		(net "I2C_IOM_SCL")
	)
	(segment
		(start 46.449996 -129.267204)
		(end 46.3042 -129.413)
		(width 0.127)
		(layer "In2.Cu")
		(net "I2C_IOM_SCL")
	)
	(segment
		(start 98.737166 -130.168142)
		(end 98.737166 -132.491226)
		(width 0.127)
		(layer "In2.Cu")
		(net "I2C_IOM_SCL")
	)
	(segment
		(start 46.9773 -127.862584)
		(end 46.449996 -128.389888)
		(width 0.127)
		(layer "In2.Cu")
		(net "I2C_IOM_SCL")
	)
	(segment
		(start 98.915474 -120.882918)
		(end 97.975166 -121.823226)
		(width 0.127)
		(layer "In2.Cu")
		(net "I2C_IOM_SCL")
	)
	(segment
		(start 97.975166 -129.406142)
		(end 98.737166 -130.168142)
		(width 0.127)
		(layer "In2.Cu")
		(net "I2C_IOM_SCL")
	)
	(segment
		(start 47.0408 -126.5047)
		(end 46.9773 -126.5682)
		(width 0.127)
		(layer "In2.Cu")
		(net "I2C_IOM_SCL")
	)
	(segment
		(start 97.975166 -121.823226)
		(end 97.975166 -129.406142)
		(width 0.127)
		(layer "In2.Cu")
		(net "I2C_IOM_SCL")
	)
	(segment
		(start 48.330612 -116.80571)
		(end 48.330612 -121.087388)
		(width 0.127)
		(layer "In2.Cu")
		(net "I2C_IOM_SCL")
	)
	(segment
		(start 46.3042 -129.413)
		(end 46.3042 -129.4384)
		(width 0.127)
		(layer "In2.Cu")
		(net "I2C_IOM_SCL")
	)
	(segment
		(start 98.4123 -115.457732)
		(end 98.4123 -115.503706)
		(width 0.127)
		(layer "In2.Cu")
		(net "I2C_IOM_SCL")
	)
	(segment
		(start 46.9773 -126.5682)
		(end 46.9773 -127.862584)
		(width 0.127)
		(layer "In2.Cu")
		(net "I2C_IOM_SCL")
	)
	(segment
		(start 98.915474 -116.00688)
		(end 98.915474 -120.882918)
		(width 0.127)
		(layer "In2.Cu")
		(net "I2C_IOM_SCL")
	)
	(segment
		(start 46.449996 -128.389888)
		(end 46.449996 -129.267204)
		(width 0.127)
		(layer "In2.Cu")
		(net "I2C_IOM_SCL")
	)
	(segment
		(start 98.737166 -132.491226)
		(end 97.751646 -133.476746)
		(width 0.127)
		(layer "In2.Cu")
		(net "I2C_IOM_SCL")
	)
	(segment
		(start 47.0408 -122.3772)
		(end 47.0408 -126.5047)
		(width 0.127)
		(layer "In2.Cu")
		(net "I2C_IOM_SCL")
	)
	(segment
		(start 48.330612 -121.087388)
		(end 47.0408 -122.3772)
		(width 0.127)
		(layer "In2.Cu")
		(net "I2C_IOM_SCL")
	)
	(segment
		(start 98.4123 -115.503706)
		(end 98.915474 -116.00688)
		(width 0.127)
		(layer "In2.Cu")
		(net "I2C_IOM_SCL")
	)
	(segment
		(start 100.162106 -46.407324)
		(end 100.162106 -82.85353)
		(width 0.127)
		(layer "In5.Cu")
		(net "I2C_IOM_SCL")
	)
	(segment
		(start 87.5538 -115.631468)
		(end 83.326732 -111.4044)
		(width 0.127)
		(layer "In5.Cu")
		(net "I2C_IOM_SCL")
	)
	(segment
		(start 95.494856 -90.930476)
		(end 98.918776 -94.354396)
		(width 0.127)
		(layer "In5.Cu")
		(net "I2C_IOM_SCL")
	)
	(segment
		(start 95.494856 -87.52078)
		(end 95.494856 -90.930476)
		(width 0.127)
		(layer "In5.Cu")
		(net "I2C_IOM_SCL")
	)
	(segment
		(start 125.98654 -5.81406)
		(end 126.09322 -5.81406)
		(width 0.127)
		(layer "In5.Cu")
		(net "I2C_IOM_SCL")
	)
	(segment
		(start 77.0636 -111.4044)
		(end 74.453496 -114.014504)
		(width 0.127)
		(layer "In5.Cu")
		(net "I2C_IOM_SCL")
	)
	(segment
		(start 109.4232 -5.6388)
		(end 109.9566 -6.1722)
		(width 0.127)
		(layer "In5.Cu")
		(net "I2C_IOM_SCL")
	)
	(segment
		(start 98.121216 -115.457732)
		(end 95.062548 -118.5164)
		(width 0.127)
		(layer "In5.Cu")
		(net "I2C_IOM_SCL")
	)
	(segment
		(start 109.9566 -6.1722)
		(end 116.80952 -6.1722)
		(width 0.127)
		(layer "In5.Cu")
		(net "I2C_IOM_SCL")
	)
	(segment
		(start 100.06457 -41.824656)
		(end 100.784914 -42.545)
		(width 0.127)
		(layer "In5.Cu")
		(net "I2C_IOM_SCL")
	)
	(segment
		(start 74.453496 -114.014504)
		(end 70.719696 -114.014504)
		(width 0.127)
		(layer "In5.Cu")
		(net "I2C_IOM_SCL")
	)
	(segment
		(start 89.237566 -118.5164)
		(end 87.5538 -116.832634)
		(width 0.127)
		(layer "In5.Cu")
		(net "I2C_IOM_SCL")
	)
	(segment
		(start 55.762652 -116.1288)
		(end 55.432198 -115.798346)
		(width 0.127)
		(layer "In5.Cu")
		(net "I2C_IOM_SCL")
	)
	(segment
		(start 98.4123 -115.411758)
		(end 98.4123 -115.457732)
		(width 0.127)
		(layer "In5.Cu")
		(net "I2C_IOM_SCL")
	)
	(segment
		(start 98.349308 -41.824656)
		(end 100.06457 -41.824656)
		(width 0.127)
		(layer "In5.Cu")
		(net "I2C_IOM_SCL")
	)
	(segment
		(start 98.918776 -114.905282)
		(end 98.4123 -115.411758)
		(width 0.127)
		(layer "In5.Cu")
		(net "I2C_IOM_SCL")
	)
	(segment
		(start 66.424302 -116.1288)
		(end 55.762652 -116.1288)
		(width 0.127)
		(layer "In5.Cu")
		(net "I2C_IOM_SCL")
	)
	(segment
		(start 100.784914 -45.784516)
		(end 100.162106 -46.407324)
		(width 0.127)
		(layer "In5.Cu")
		(net "I2C_IOM_SCL")
	)
	(segment
		(start 117.2972 -6.65988)
		(end 125.14072 -6.65988)
		(width 0.127)
		(layer "In5.Cu")
		(net "I2C_IOM_SCL")
	)
	(segment
		(start 98.918776 -94.354396)
		(end 98.918776 -114.905282)
		(width 0.127)
		(layer "In5.Cu")
		(net "I2C_IOM_SCL")
	)
	(segment
		(start 125.14072 -6.65988)
		(end 125.98654 -5.81406)
		(width 0.127)
		(layer "In5.Cu")
		(net "I2C_IOM_SCL")
	)
	(segment
		(start 100.162106 -82.85353)
		(end 95.494856 -87.52078)
		(width 0.127)
		(layer "In5.Cu")
		(net "I2C_IOM_SCL")
	)
	(segment
		(start 49.337976 -115.798346)
		(end 48.330612 -116.80571)
		(width 0.127)
		(layer "In5.Cu")
		(net "I2C_IOM_SCL")
	)
	(segment
		(start 95.062548 -118.5164)
		(end 89.237566 -118.5164)
		(width 0.127)
		(layer "In5.Cu")
		(net "I2C_IOM_SCL")
	)
	(segment
		(start 83.326732 -111.4044)
		(end 77.0636 -111.4044)
		(width 0.127)
		(layer "In5.Cu")
		(net "I2C_IOM_SCL")
	)
	(segment
		(start 87.5538 -116.832634)
		(end 87.5538 -115.631468)
		(width 0.127)
		(layer "In5.Cu")
		(net "I2C_IOM_SCL")
	)
	(segment
		(start 55.432198 -115.798346)
		(end 49.337976 -115.798346)
		(width 0.127)
		(layer "In5.Cu")
		(net "I2C_IOM_SCL")
	)
	(segment
		(start 100.784914 -42.545)
		(end 100.784914 -45.784516)
		(width 0.127)
		(layer "In5.Cu")
		(net "I2C_IOM_SCL")
	)
	(segment
		(start 98.4123 -115.457732)
		(end 98.121216 -115.457732)
		(width 0.127)
		(layer "In5.Cu")
		(net "I2C_IOM_SCL")
	)
	(segment
		(start 70.719696 -114.014504)
		(end 69.85 -114.8842)
		(width 0.127)
		(layer "In5.Cu")
		(net "I2C_IOM_SCL")
	)
	(segment
		(start 69.85 -114.8842)
		(end 67.668902 -114.8842)
		(width 0.127)
		(layer "In5.Cu")
		(net "I2C_IOM_SCL")
	)
	(segment
		(start 116.80952 -6.1722)
		(end 117.2972 -6.65988)
		(width 0.127)
		(layer "In5.Cu")
		(net "I2C_IOM_SCL")
	)
	(segment
		(start 67.668902 -114.8842)
		(end 66.424302 -116.1288)
		(width 0.127)
		(layer "In5.Cu")
		(net "I2C_IOM_SCL")
	)
	(segment
		(start 163.13658 -97.502726)
		(end 163.3728 -97.266506)
		(width 0.127)
		(layer "F.Cu")
		(net "I2C_IOC_SDA")
	)
	(segment
		(start 122.7836 -22.824948)
		(end 121.492772 -21.53412)
		(width 0.127)
		(layer "F.Cu")
		(net "I2C_IOC_SDA")
	)
	(segment
		(start 162.323018 -91.958414)
		(end 163.071048 -91.958414)
		(width 0.127)
		(layer "F.Cu")
		(net "I2C_IOC_SDA")
	)
	(segment
		(start 96.549972 -84.072222)
		(end 97.365058 -84.887308)
		(width 0.127)
		(layer "F.Cu")
		(net "I2C_IOC_SDA")
	)
	(segment
		(start 96.549972 -42.94251)
		(end 96.549972 -84.072222)
		(width 0.127)
		(layer "F.Cu")
		(net "I2C_IOC_SDA")
	)
	(segment
		(start 99.66452 -21.677376)
		(end 98.896424 -21.677376)
		(width 0.127)
		(layer "F.Cu")
		(net "I2C_IOC_SDA")
	)
	(segment
		(start 163.3728 -92.260166)
		(end 163.3728 -93.0402)
		(width 0.127)
		(layer "F.Cu")
		(net "I2C_IOC_SDA")
	)
	(segment
		(start 44.37761 -131.31038)
		(end 44.37761 -130.53441)
		(width 0.127)
		(layer "F.Cu")
		(net "I2C_IOC_SDA")
	)
	(segment
		(start 141.867382 -22.824948)
		(end 122.7836 -22.824948)
		(width 0.127)
		(layer "F.Cu")
		(net "I2C_IOC_SDA")
	)
	(segment
		(start 142.681706 -22.961854)
		(end 142.004288 -22.961854)
		(width 0.127)
		(layer "F.Cu")
		(net "I2C_IOC_SDA")
	)
	(segment
		(start 44.37761 -130.53441)
		(end 44.3738 -130.5306)
		(width 0.127)
		(layer "F.Cu")
		(net "I2C_IOC_SDA")
	)
	(segment
		(start 116.08054 -17.402302)
		(end 103.939594 -17.402302)
		(width 0.127)
		(layer "F.Cu")
		(net "I2C_IOC_SDA")
	)
	(segment
		(start 163.3728 -97.266506)
		(end 163.3728 -93.0402)
		(width 0.127)
		(layer "F.Cu")
		(net "I2C_IOC_SDA")
	)
	(segment
		(start 121.492772 -21.53412)
		(end 120.212358 -21.53412)
		(width 0.127)
		(layer "F.Cu")
		(net "I2C_IOC_SDA")
	)
	(segment
		(start 98.896424 -21.677376)
		(end 98.239326 -22.334474)
		(width 0.127)
		(layer "F.Cu")
		(net "I2C_IOC_SDA")
	)
	(segment
		(start 98.239326 -22.334474)
		(end 98.239326 -23.276052)
		(width 0.127)
		(layer "F.Cu")
		(net "I2C_IOC_SDA")
	)
	(segment
		(start 162.323018 -91.958414)
		(end 161.973768 -91.958414)
		(width 0.127)
		(layer "F.Cu")
		(net "I2C_IOC_SDA")
	)
	(segment
		(start 98.239326 -23.276052)
		(end 97.705164 -23.810214)
		(width 0.127)
		(layer "F.Cu")
		(net "I2C_IOC_SDA")
	)
	(segment
		(start 97.365058 -84.887308)
		(end 97.365058 -87.218266)
		(width 0.127)
		(layer "F.Cu")
		(net "I2C_IOC_SDA")
	)
	(segment
		(start 94.204028 -41.576752)
		(end 94.561914 -41.934638)
		(width 0.127)
		(layer "F.Cu")
		(net "I2C_IOC_SDA")
	)
	(segment
		(start 143.070072 -22.573488)
		(end 142.681706 -22.961854)
		(width 0.127)
		(layer "F.Cu")
		(net "I2C_IOC_SDA")
	)
	(segment
		(start 163.071048 -91.958414)
		(end 163.3728 -92.260166)
		(width 0.127)
		(layer "F.Cu")
		(net "I2C_IOC_SDA")
	)
	(segment
		(start 103.939594 -17.402302)
		(end 99.66452 -21.677376)
		(width 0.127)
		(layer "F.Cu")
		(net "I2C_IOC_SDA")
	)
	(segment
		(start 95.5421 -41.934638)
		(end 96.549972 -42.94251)
		(width 0.127)
		(layer "F.Cu")
		(net "I2C_IOC_SDA")
	)
	(segment
		(start 94.561914 -41.934638)
		(end 95.5421 -41.934638)
		(width 0.127)
		(layer "F.Cu")
		(net "I2C_IOC_SDA")
	)
	(segment
		(start 161.973768 -91.958414)
		(end 161.607754 -91.5924)
		(width 0.127)
		(layer "F.Cu")
		(net "I2C_IOC_SDA")
	)
	(segment
		(start 161.607754 -91.5924)
		(end 160.927796 -91.5924)
		(width 0.127)
		(layer "F.Cu")
		(net "I2C_IOC_SDA")
	)
	(segment
		(start 142.004288 -22.961854)
		(end 141.867382 -22.824948)
		(width 0.127)
		(layer "F.Cu")
		(net "I2C_IOC_SDA")
	)
	(segment
		(start 120.212358 -21.53412)
		(end 116.08054 -17.402302)
		(width 0.127)
		(layer "F.Cu")
		(net "I2C_IOC_SDA")
	)
	(via
		(at 94.204028 -41.576752)
		(size 0.508)
		(drill 0.254)
		(layers "F.Cu" "B.Cu")
		(net "I2C_IOC_SDA")
	)
	(via
		(at 44.7294 -120.1928)
		(size 0.508)
		(drill 0.254)
		(layers "F.Cu" "B.Cu")
		(net "I2C_IOC_SDA")
	)
	(via
		(at 97.365058 -87.218266)
		(size 0.508)
		(drill 0.254)
		(layers "F.Cu" "B.Cu")
		(net "I2C_IOC_SDA")
	)
	(via
		(at 163.13658 -97.502726)
		(size 0.508)
		(drill 0.254)
		(layers "F.Cu" "B.Cu")
		(net "I2C_IOC_SDA")
	)
	(via
		(at 143.070072 -22.573488)
		(size 0.508)
		(drill 0.254)
		(layers "F.Cu" "B.Cu")
		(net "I2C_IOC_SDA")
	)
	(via
		(at 97.705164 -23.810214)
		(size 0.508)
		(drill 0.254)
		(layers "F.Cu" "B.Cu")
		(net "I2C_IOC_SDA")
	)
	(via
		(at 44.3738 -130.5306)
		(size 0.508)
		(drill 0.254)
		(layers "F.Cu" "B.Cu")
		(net "I2C_IOC_SDA")
	)
	(via
		(at 163.3728 -93.0402)
		(size 0.6604)
		(drill 0.3302)
		(layers "F.Cu" "B.Cu")
		(net "I2C_IOC_SDA")
	)
	(via
		(at 150.680166 -100.916232)
		(size 0.508)
		(drill 0.254)
		(layers "F.Cu" "B.Cu")
		(net "I2C_IOC_SDA")
	)
	(segment
		(start 155.505658 -100.916232)
		(end 159.446976 -96.974914)
		(width 0.127)
		(layer "B.Cu")
		(net "I2C_IOC_SDA")
	)
	(segment
		(start 162.608768 -96.974914)
		(end 163.13658 -97.502726)
		(width 0.127)
		(layer "B.Cu")
		(net "I2C_IOC_SDA")
	)
	(segment
		(start 150.680166 -100.916232)
		(end 155.505658 -100.916232)
		(width 0.127)
		(layer "B.Cu")
		(net "I2C_IOC_SDA")
	)
	(segment
		(start 159.446976 -96.974914)
		(end 162.608768 -96.974914)
		(width 0.127)
		(layer "B.Cu")
		(net "I2C_IOC_SDA")
	)
	(segment
		(start 143.018256 -22.91207)
		(end 143.018256 -22.625304)
		(width 0.127)
		(layer "In2.Cu")
		(net "I2C_IOC_SDA")
	)
	(segment
		(start 149.357588 -87.838788)
		(end 148.615654 -87.096854)
		(width 0.127)
		(layer "In2.Cu")
		(net "I2C_IOC_SDA")
	)
	(segment
		(start 45.4152 -121.2088)
		(end 44.7294 -120.523)
		(width 0.127)
		(layer "In2.Cu")
		(net "I2C_IOC_SDA")
	)
	(segment
		(start 94.01175 -30.209236)
		(end 94.01175 -41.384474)
		(width 0.127)
		(layer "In2.Cu")
		(net "I2C_IOC_SDA")
	)
	(segment
		(start 146.475196 -26.36901)
		(end 143.018256 -22.91207)
		(width 0.127)
		(layer "In2.Cu")
		(net "I2C_IOC_SDA")
	)
	(segment
		(start 44.7294 -120.523)
		(end 44.7294 -120.1928)
		(width 0.127)
		(layer "In2.Cu")
		(net "I2C_IOC_SDA")
	)
	(segment
		(start 150.680166 -100.916232)
		(end 150.065232 -100.301298)
		(width 0.127)
		(layer "In2.Cu")
		(net "I2C_IOC_SDA")
	)
	(segment
		(start 45.4152 -125.302518)
		(end 45.4152 -121.2088)
		(width 0.127)
		(layer "In2.Cu")
		(net "I2C_IOC_SDA")
	)
	(segment
		(start 44.958 -125.759718)
		(end 45.4152 -125.302518)
		(width 0.127)
		(layer "In2.Cu")
		(net "I2C_IOC_SDA")
	)
	(segment
		(start 94.01175 -41.384474)
		(end 94.204028 -41.576752)
		(width 0.127)
		(layer "In2.Cu")
		(net "I2C_IOC_SDA")
	)
	(segment
		(start 148.615654 -47.515272)
		(end 146.475196 -45.374814)
		(width 0.127)
		(layer "In2.Cu")
		(net "I2C_IOC_SDA")
	)
	(segment
		(start 44.37761 -130.52679)
		(end 44.37761 -127.956818)
		(width 0.127)
		(layer "In2.Cu")
		(net "I2C_IOC_SDA")
	)
	(segment
		(start 97.705164 -23.810214)
		(end 97.350326 -24.165052)
		(width 0.127)
		(layer "In2.Cu")
		(net "I2C_IOC_SDA")
	)
	(segment
		(start 97.350326 -26.87066)
		(end 94.01175 -30.209236)
		(width 0.127)
		(layer "In2.Cu")
		(net "I2C_IOC_SDA")
	)
	(segment
		(start 149.357588 -96.152462)
		(end 149.357588 -87.838788)
		(width 0.127)
		(layer "In2.Cu")
		(net "I2C_IOC_SDA")
	)
	(segment
		(start 44.958 -127.376428)
		(end 44.958 -125.759718)
		(width 0.127)
		(layer "In2.Cu")
		(net "I2C_IOC_SDA")
	)
	(segment
		(start 97.350326 -24.165052)
		(end 97.350326 -26.87066)
		(width 0.127)
		(layer "In2.Cu")
		(net "I2C_IOC_SDA")
	)
	(segment
		(start 44.3738 -130.5306)
		(end 44.37761 -130.52679)
		(width 0.127)
		(layer "In2.Cu")
		(net "I2C_IOC_SDA")
	)
	(segment
		(start 150.065232 -100.301298)
		(end 150.065232 -96.860106)
		(width 0.127)
		(layer "In2.Cu")
		(net "I2C_IOC_SDA")
	)
	(segment
		(start 44.37761 -127.956818)
		(end 44.958 -127.376428)
		(width 0.127)
		(layer "In2.Cu")
		(net "I2C_IOC_SDA")
	)
	(segment
		(start 150.065232 -96.860106)
		(end 149.357588 -96.152462)
		(width 0.127)
		(layer "In2.Cu")
		(net "I2C_IOC_SDA")
	)
	(segment
		(start 146.475196 -45.374814)
		(end 146.475196 -26.36901)
		(width 0.127)
		(layer "In2.Cu")
		(net "I2C_IOC_SDA")
	)
	(segment
		(start 143.018256 -22.625304)
		(end 143.070072 -22.573488)
		(width 0.127)
		(layer "In2.Cu")
		(net "I2C_IOC_SDA")
	)
	(segment
		(start 148.615654 -87.096854)
		(end 148.615654 -47.515272)
		(width 0.127)
		(layer "In2.Cu")
		(net "I2C_IOC_SDA")
	)
	(segment
		(start 98.295206 -117.547136)
		(end 98.698812 -117.547136)
		(width 0.127)
		(layer "In5.Cu")
		(net "I2C_IOC_SDA")
	)
	(segment
		(start 72.644 -115.697)
		(end 75.107546 -115.697)
		(width 0.127)
		(layer "In5.Cu")
		(net "I2C_IOC_SDA")
	)
	(segment
		(start 54.851554 -117.3734)
		(end 55.130954 -117.6528)
		(width 0.127)
		(layer "In5.Cu")
		(net "I2C_IOC_SDA")
	)
	(segment
		(start 95.776542 -120.0658)
		(end 98.295206 -117.547136)
		(width 0.127)
		(layer "In5.Cu")
		(net "I2C_IOC_SDA")
	)
	(segment
		(start 100.442776 -92.658692)
		(end 98.406458 -90.622374)
		(width 0.127)
		(layer "In5.Cu")
		(net "I2C_IOC_SDA")
	)
	(segment
		(start 82.912966 -113.157)
		(end 86.0298 -116.273834)
		(width 0.127)
		(layer "In5.Cu")
		(net "I2C_IOC_SDA")
	)
	(segment
		(start 86.0298 -116.273834)
		(end 86.0298 -117.487446)
		(width 0.127)
		(layer "In5.Cu")
		(net "I2C_IOC_SDA")
	)
	(segment
		(start 44.7548 -120.2182)
		(end 47.85233 -120.2182)
		(width 0.127)
		(layer "In5.Cu")
		(net "I2C_IOC_SDA")
	)
	(segment
		(start 68.2752 -116.4336)
		(end 71.9074 -116.4336)
		(width 0.127)
		(layer "In5.Cu")
		(net "I2C_IOC_SDA")
	)
	(segment
		(start 98.698812 -117.547136)
		(end 100.442776 -115.803172)
		(width 0.127)
		(layer "In5.Cu")
		(net "I2C_IOC_SDA")
	)
	(segment
		(start 75.107546 -115.697)
		(end 77.647546 -113.157)
		(width 0.127)
		(layer "In5.Cu")
		(net "I2C_IOC_SDA")
	)
	(segment
		(start 98.406458 -90.622374)
		(end 98.406458 -88.259666)
		(width 0.127)
		(layer "In5.Cu")
		(net "I2C_IOC_SDA")
	)
	(segment
		(start 47.85233 -120.2182)
		(end 50.69713 -117.3734)
		(width 0.127)
		(layer "In5.Cu")
		(net "I2C_IOC_SDA")
	)
	(segment
		(start 44.7294 -120.1928)
		(end 44.7548 -120.2182)
		(width 0.127)
		(layer "In5.Cu")
		(net "I2C_IOC_SDA")
	)
	(segment
		(start 88.608154 -120.0658)
		(end 95.776542 -120.0658)
		(width 0.127)
		(layer "In5.Cu")
		(net "I2C_IOC_SDA")
	)
	(segment
		(start 50.69713 -117.3734)
		(end 54.851554 -117.3734)
		(width 0.127)
		(layer "In5.Cu")
		(net "I2C_IOC_SDA")
	)
	(segment
		(start 77.647546 -113.157)
		(end 82.912966 -113.157)
		(width 0.127)
		(layer "In5.Cu")
		(net "I2C_IOC_SDA")
	)
	(segment
		(start 71.9074 -116.4336)
		(end 72.644 -115.697)
		(width 0.127)
		(layer "In5.Cu")
		(net "I2C_IOC_SDA")
	)
	(segment
		(start 98.406458 -88.259666)
		(end 97.365058 -87.218266)
		(width 0.127)
		(layer "In5.Cu")
		(net "I2C_IOC_SDA")
	)
	(segment
		(start 86.0298 -117.487446)
		(end 88.608154 -120.0658)
		(width 0.127)
		(layer "In5.Cu")
		(net "I2C_IOC_SDA")
	)
	(segment
		(start 67.056 -117.6528)
		(end 68.2752 -116.4336)
		(width 0.127)
		(layer "In5.Cu")
		(net "I2C_IOC_SDA")
	)
	(segment
		(start 55.130954 -117.6528)
		(end 67.056 -117.6528)
		(width 0.127)
		(layer "In5.Cu")
		(net "I2C_IOC_SDA")
	)
	(segment
		(start 100.442776 -115.803172)
		(end 100.442776 -92.658692)
		(width 0.127)
		(layer "In5.Cu")
		(net "I2C_IOC_SDA")
	)
	(segment
		(start 162.80384 -96.82607)
		(end 162.80384 -95.832676)
		(width 0.127)
		(layer "F.Cu")
		(net "I2C_IOC_SCL")
	)
	(segment
		(start 161.302954 -93.295724)
		(end 161.203894 -93.295724)
		(width 0.127)
		(layer "F.Cu")
		(net "I2C_IOC_SCL")
	)
	(segment
		(start 120.422924 -21.02612)
		(end 121.703338 -21.02612)
		(width 0.127)
		(layer "F.Cu")
		(net "I2C_IOC_SCL")
	)
	(segment
		(start 96.041972 -43.153076)
		(end 95.392494 -42.503598)
		(width 0.127)
		(layer "F.Cu")
		(net "I2C_IOC_SCL")
	)
	(segment
		(start 121.703338 -21.02612)
		(end 122.994166 -22.316948)
		(width 0.127)
		(layer "F.Cu")
		(net "I2C_IOC_SCL")
	)
	(segment
		(start 96.842326 -24.125174)
		(end 96.842326 -23.781004)
		(width 0.127)
		(layer "F.Cu")
		(net "I2C_IOC_SCL")
	)
	(segment
		(start 99.453954 -21.169376)
		(end 103.729028 -16.894302)
		(width 0.127)
		(layer "F.Cu")
		(net "I2C_IOC_SCL")
	)
	(segment
		(start 103.729028 -16.894302)
		(end 116.291106 -16.894302)
		(width 0.127)
		(layer "F.Cu")
		(net "I2C_IOC_SCL")
	)
	(segment
		(start 122.994166 -22.316948)
		(end 142.077948 -22.316948)
		(width 0.127)
		(layer "F.Cu")
		(net "I2C_IOC_SCL")
	)
	(segment
		(start 142.077948 -22.316948)
		(end 142.2146 -22.4536)
		(width 0.127)
		(layer "F.Cu")
		(net "I2C_IOC_SCL")
	)
	(segment
		(start 161.203894 -93.295724)
		(end 161.059368 -93.295724)
		(width 0.127)
		(layer "F.Cu")
		(net "I2C_IOC_SCL")
	)
	(segment
		(start 160.277556 -92.513912)
		(end 160.277556 -91.5924)
		(width 0.127)
		(layer "F.Cu")
		(net "I2C_IOC_SCL")
	)
	(segment
		(start 96.041972 -84.282788)
		(end 96.041972 -43.153076)
		(width 0.127)
		(layer "F.Cu")
		(net "I2C_IOC_SCL")
	)
	(segment
		(start 95.392494 -42.503598)
		(end 94.017846 -42.503598)
		(width 0.127)
		(layer "F.Cu")
		(net "I2C_IOC_SCL")
	)
	(segment
		(start 96.842326 -23.781004)
		(end 97.731326 -22.892004)
		(width 0.127)
		(layer "F.Cu")
		(net "I2C_IOC_SCL")
	)
	(segment
		(start 116.291106 -16.894302)
		(end 120.422924 -21.02612)
		(width 0.127)
		(layer "F.Cu")
		(net "I2C_IOC_SCL")
	)
	(segment
		(start 96.683576 -87.496142)
		(end 96.683576 -84.924392)
		(width 0.127)
		(layer "F.Cu")
		(net "I2C_IOC_SCL")
	)
	(segment
		(start 161.059368 -93.295724)
		(end 160.277556 -92.513912)
		(width 0.127)
		(layer "F.Cu")
		(net "I2C_IOC_SCL")
	)
	(segment
		(start 98.685858 -21.169376)
		(end 99.453954 -21.169376)
		(width 0.127)
		(layer "F.Cu")
		(net "I2C_IOC_SCL")
	)
	(segment
		(start 97.35439 -88.166956)
		(end 96.683576 -87.496142)
		(width 0.127)
		(layer "F.Cu")
		(net "I2C_IOC_SCL")
	)
	(segment
		(start 162.14344 -97.48647)
		(end 162.80384 -96.82607)
		(width 0.127)
		(layer "F.Cu")
		(net "I2C_IOC_SCL")
	)
	(segment
		(start 97.731326 -22.123908)
		(end 98.685858 -21.169376)
		(width 0.127)
		(layer "F.Cu")
		(net "I2C_IOC_SCL")
	)
	(segment
		(start 162.80384 -95.832676)
		(end 162.80384 -94.79661)
		(width 0.127)
		(layer "F.Cu")
		(net "I2C_IOC_SCL")
	)
	(segment
		(start 96.683576 -84.924392)
		(end 96.041972 -84.282788)
		(width 0.127)
		(layer "F.Cu")
		(net "I2C_IOC_SCL")
	)
	(segment
		(start 97.731326 -22.892004)
		(end 97.731326 -22.123908)
		(width 0.127)
		(layer "F.Cu")
		(net "I2C_IOC_SCL")
	)
	(segment
		(start 162.80384 -94.79661)
		(end 161.302954 -93.295724)
		(width 0.127)
		(layer "F.Cu")
		(net "I2C_IOC_SCL")
	)
	(via
		(at 150.638256 -101.83114)
		(size 0.508)
		(drill 0.254)
		(layers "F.Cu" "B.Cu")
		(net "I2C_IOC_SCL")
	)
	(via
		(at 97.35439 -88.166956)
		(size 0.508)
		(drill 0.254)
		(layers "F.Cu" "B.Cu")
		(net "I2C_IOC_SCL")
	)
	(via
		(at 162.14344 -97.48647)
		(size 0.508)
		(drill 0.254)
		(layers "F.Cu" "B.Cu")
		(net "I2C_IOC_SCL")
	)
	(via
		(at 94.017846 -42.503598)
		(size 0.508)
		(drill 0.254)
		(layers "F.Cu" "B.Cu")
		(net "I2C_IOC_SCL")
	)
	(via
		(at 96.842326 -24.125174)
		(size 0.508)
		(drill 0.254)
		(layers "F.Cu" "B.Cu")
		(net "I2C_IOC_SCL")
	)
	(via
		(at 162.80384 -95.832676)
		(size 0.6604)
		(drill 0.3302)
		(layers "F.Cu" "B.Cu")
		(net "I2C_IOC_SCL")
	)
	(via
		(at 50.05959 -116.814346)
		(size 0.508)
		(drill 0.254)
		(layers "F.Cu" "B.Cu")
		(net "I2C_IOC_SCL")
	)
	(via
		(at 46.94682 -134.60984)
		(size 0.508)
		(drill 0.254)
		(layers "F.Cu" "B.Cu")
		(net "I2C_IOC_SCL")
	)
	(via
		(at 142.2146 -22.4536)
		(size 0.508)
		(drill 0.254)
		(layers "F.Cu" "B.Cu")
		(net "I2C_IOC_SCL")
	)
	(segment
		(start 150.638256 -101.83114)
		(end 155.568904 -101.83114)
		(width 0.127)
		(layer "B.Cu")
		(net "I2C_IOC_SCL")
	)
	(segment
		(start 159.913574 -97.48647)
		(end 162.14344 -97.48647)
		(width 0.127)
		(layer "B.Cu")
		(net "I2C_IOC_SCL")
	)
	(segment
		(start 46.3804 -134.7724)
		(end 46.5074 -134.6454)
		(width 0.127)
		(layer "B.Cu")
		(net "I2C_IOC_SCL")
	)
	(segment
		(start 46.5074 -134.6454)
		(end 46.91126 -134.6454)
		(width 0.127)
		(layer "B.Cu")
		(net "I2C_IOC_SCL")
	)
	(segment
		(start 46.91126 -134.6454)
		(end 46.94682 -134.60984)
		(width 0.127)
		(layer "B.Cu")
		(net "I2C_IOC_SCL")
	)
	(segment
		(start 46.3804 -135.2677)
		(end 46.3804 -134.7724)
		(width 0.127)
		(layer "B.Cu")
		(net "I2C_IOC_SCL")
	)
	(segment
		(start 155.568904 -101.83114)
		(end 159.913574 -97.48647)
		(width 0.127)
		(layer "B.Cu")
		(net "I2C_IOC_SCL")
	)
	(segment
		(start 96.842326 -26.660094)
		(end 93.50375 -29.99867)
		(width 0.127)
		(layer "In2.Cu")
		(net "I2C_IOC_SCL")
	)
	(segment
		(start 148.107654 -87.30742)
		(end 148.107654 -47.725838)
		(width 0.127)
		(layer "In2.Cu")
		(net "I2C_IOC_SCL")
	)
	(segment
		(start 148.849588 -88.049354)
		(end 148.107654 -87.30742)
		(width 0.127)
		(layer "In2.Cu")
		(net "I2C_IOC_SCL")
	)
	(segment
		(start 145.966688 -26.640028)
		(end 142.2146 -22.88794)
		(width 0.127)
		(layer "In2.Cu")
		(net "I2C_IOC_SCL")
	)
	(segment
		(start 148.107654 -47.725838)
		(end 145.966688 -45.584872)
		(width 0.127)
		(layer "In2.Cu")
		(net "I2C_IOC_SCL")
	)
	(segment
		(start 47.436278 -134.120382)
		(end 47.436278 -132.999734)
		(width 0.127)
		(layer "In2.Cu")
		(net "I2C_IOC_SCL")
	)
	(segment
		(start 93.50375 -41.989502)
		(end 94.017846 -42.503598)
		(width 0.127)
		(layer "In2.Cu")
		(net "I2C_IOC_SCL")
	)
	(segment
		(start 149.464268 -100.657152)
		(end 149.464268 -97.086928)
		(width 0.127)
		(layer "In2.Cu")
		(net "I2C_IOC_SCL")
	)
	(segment
		(start 145.966688 -45.584872)
		(end 145.966688 -26.640028)
		(width 0.127)
		(layer "In2.Cu")
		(net "I2C_IOC_SCL")
	)
	(segment
		(start 46.94682 -134.60984)
		(end 47.436278 -134.120382)
		(width 0.127)
		(layer "In2.Cu")
		(net "I2C_IOC_SCL")
	)
	(segment
		(start 49.022 -121.833132)
		(end 50.05959 -120.795542)
		(width 0.127)
		(layer "In2.Cu")
		(net "I2C_IOC_SCL")
	)
	(segment
		(start 47.436278 -132.999734)
		(end 48.0695 -132.366512)
		(width 0.127)
		(layer "In2.Cu")
		(net "I2C_IOC_SCL")
	)
	(segment
		(start 148.849588 -96.472248)
		(end 148.849588 -88.049354)
		(width 0.127)
		(layer "In2.Cu")
		(net "I2C_IOC_SCL")
	)
	(segment
		(start 48.0695 -132.366512)
		(end 48.0695 -129.062734)
		(width 0.127)
		(layer "In2.Cu")
		(net "I2C_IOC_SCL")
	)
	(segment
		(start 150.638256 -101.83114)
		(end 149.464268 -100.657152)
		(width 0.127)
		(layer "In2.Cu")
		(net "I2C_IOC_SCL")
	)
	(segment
		(start 48.0695 -129.062734)
		(end 49.022 -128.110234)
		(width 0.127)
		(layer "In2.Cu")
		(net "I2C_IOC_SCL")
	)
	(segment
		(start 142.2146 -22.88794)
		(end 142.2146 -22.4536)
		(width 0.127)
		(layer "In2.Cu")
		(net "I2C_IOC_SCL")
	)
	(segment
		(start 49.022 -128.110234)
		(end 49.022 -121.833132)
		(width 0.127)
		(layer "In2.Cu")
		(net "I2C_IOC_SCL")
	)
	(segment
		(start 96.842326 -24.125174)
		(end 96.842326 -26.660094)
		(width 0.127)
		(layer "In2.Cu")
		(net "I2C_IOC_SCL")
	)
	(segment
		(start 93.50375 -29.99867)
		(end 93.50375 -41.989502)
		(width 0.127)
		(layer "In2.Cu")
		(net "I2C_IOC_SCL")
	)
	(segment
		(start 149.464268 -97.086928)
		(end 148.849588 -96.472248)
		(width 0.127)
		(layer "In2.Cu")
		(net "I2C_IOC_SCL")
	)
	(segment
		(start 50.05959 -120.795542)
		(end 50.05959 -116.814346)
		(width 0.127)
		(layer "In2.Cu")
		(net "I2C_IOC_SCL")
	)
	(segment
		(start 98.065844 -117.016784)
		(end 95.524828 -119.5578)
		(width 0.127)
		(layer "In5.Cu")
		(net "I2C_IOC_SCL")
	)
	(segment
		(start 86.5378 -117.27688)
		(end 86.5378 -116.0526)
		(width 0.127)
		(layer "In5.Cu")
		(net "I2C_IOC_SCL")
	)
	(segment
		(start 99.934776 -115.546378)
		(end 98.46437 -117.016784)
		(width 0.127)
		(layer "In5.Cu")
		(net "I2C_IOC_SCL")
	)
	(segment
		(start 88.81872 -119.5578)
		(end 86.5378 -117.27688)
		(width 0.127)
		(layer "In5.Cu")
		(net "I2C_IOC_SCL")
	)
	(segment
		(start 55.011066 -116.814346)
		(end 50.05959 -116.814346)
		(width 0.127)
		(layer "In5.Cu")
		(net "I2C_IOC_SCL")
	)
	(segment
		(start 83.1342 -112.649)
		(end 77.3684 -112.649)
		(width 0.127)
		(layer "In5.Cu")
		(net "I2C_IOC_SCL")
	)
	(segment
		(start 98.46437 -117.016784)
		(end 98.065844 -117.016784)
		(width 0.127)
		(layer "In5.Cu")
		(net "I2C_IOC_SCL")
	)
	(segment
		(start 97.847912 -88.660478)
		(end 97.847912 -91.023186)
		(width 0.127)
		(layer "In5.Cu")
		(net "I2C_IOC_SCL")
	)
	(segment
		(start 72.1106 -115.189)
		(end 71.374 -115.9256)
		(width 0.127)
		(layer "In5.Cu")
		(net "I2C_IOC_SCL")
	)
	(segment
		(start 71.374 -115.9256)
		(end 68.064634 -115.9256)
		(width 0.127)
		(layer "In5.Cu")
		(net "I2C_IOC_SCL")
	)
	(segment
		(start 74.8284 -115.189)
		(end 72.1106 -115.189)
		(width 0.127)
		(layer "In5.Cu")
		(net "I2C_IOC_SCL")
	)
	(segment
		(start 97.847912 -91.023186)
		(end 99.934776 -93.11005)
		(width 0.127)
		(layer "In5.Cu")
		(net "I2C_IOC_SCL")
	)
	(segment
		(start 97.35439 -88.166956)
		(end 97.847912 -88.660478)
		(width 0.127)
		(layer "In5.Cu")
		(net "I2C_IOC_SCL")
	)
	(segment
		(start 68.064634 -115.9256)
		(end 66.845434 -117.1448)
		(width 0.127)
		(layer "In5.Cu")
		(net "I2C_IOC_SCL")
	)
	(segment
		(start 77.3684 -112.649)
		(end 74.8284 -115.189)
		(width 0.127)
		(layer "In5.Cu")
		(net "I2C_IOC_SCL")
	)
	(segment
		(start 95.524828 -119.5578)
		(end 88.81872 -119.5578)
		(width 0.127)
		(layer "In5.Cu")
		(net "I2C_IOC_SCL")
	)
	(segment
		(start 55.34152 -117.1448)
		(end 55.011066 -116.814346)
		(width 0.127)
		(layer "In5.Cu")
		(net "I2C_IOC_SCL")
	)
	(segment
		(start 86.5378 -116.0526)
		(end 83.1342 -112.649)
		(width 0.127)
		(layer "In5.Cu")
		(net "I2C_IOC_SCL")
	)
	(segment
		(start 66.845434 -117.1448)
		(end 55.34152 -117.1448)
		(width 0.127)
		(layer "In5.Cu")
		(net "I2C_IOC_SCL")
	)
	(segment
		(start 99.934776 -93.11005)
		(end 99.934776 -115.546378)
		(width 0.127)
		(layer "In5.Cu")
		(net "I2C_IOC_SCL")
	)
	(segment
		(start 122.385074 -4.498594)
		(end 120.799606 -4.498594)
		(width 0.127)
		(layer "F.Cu")
		(net "HSW_SDA")
	)
	(segment
		(start 123.54814 -4.498594)
		(end 124.3965 -5.346954)
		(width 0.127)
		(layer "F.Cu")
		(net "HSW_SDA")
	)
	(segment
		(start 124.3965 -5.346954)
		(end 124.3965 -5.588)
		(width 0.127)
		(layer "F.Cu")
		(net "HSW_SDA")
	)
	(segment
		(start 120.121934 -5.176266)
		(end 120.121934 -6.5151)
		(width 0.127)
		(layer "F.Cu")
		(net "HSW_SDA")
	)
	(segment
		(start 120.799606 -4.498594)
		(end 120.121934 -5.176266)
		(width 0.127)
		(layer "F.Cu")
		(net "HSW_SDA")
	)
	(segment
		(start 122.385074 -4.498594)
		(end 123.54814 -4.498594)
		(width 0.127)
		(layer "F.Cu")
		(net "HSW_SDA")
	)
	(via
		(at 122.385074 -4.498594)
		(size 0.6604)
		(drill 0.3302)
		(layers "F.Cu" "B.Cu")
		(net "HSW_SDA")
	)
	(segment
		(start 123.216416 -5.458714)
		(end 123.251214 -5.458714)
		(width 0.127)
		(layer "F.Cu")
		(net "HSW_SCL")
	)
	(segment
		(start 122.227086 -5.458714)
		(end 123.216416 -5.458714)
		(width 0.127)
		(layer "F.Cu")
		(net "HSW_SCL")
	)
	(segment
		(start 120.62206 -6.4389)
		(end 120.62206 -5.91058)
		(width 0.127)
		(layer "F.Cu")
		(net "HSW_SCL")
	)
	(segment
		(start 120.982994 -5.549646)
		(end 122.136154 -5.549646)
		(width 0.127)
		(layer "F.Cu")
		(net "HSW_SCL")
	)
	(segment
		(start 120.62206 -5.91058)
		(end 120.982994 -5.549646)
		(width 0.127)
		(layer "F.Cu")
		(net "HSW_SCL")
	)
	(segment
		(start 123.251214 -5.458714)
		(end 124.3965 -6.604)
		(width 0.127)
		(layer "F.Cu")
		(net "HSW_SCL")
	)
	(segment
		(start 122.136154 -5.549646)
		(end 122.227086 -5.458714)
		(width 0.127)
		(layer "F.Cu")
		(net "HSW_SCL")
	)
	(via
		(at 123.216416 -5.458714)
		(size 0.6604)
		(drill 0.3302)
		(layers "F.Cu" "B.Cu")
		(net "HSW_SCL")
	)
	(segment
		(start 67.9831 -140.2334)
		(end 67.8688 -140.1191)
		(width 0.127)
		(layer "F.Cu")
		(net "FP_RETBTN")
	)
	(segment
		(start 67.8688 -140.1191)
		(end 67.8688 -139.2428)
		(width 0.127)
		(layer "F.Cu")
		(net "FP_RETBTN")
	)
	(segment
		(start 68.020184 -140.196316)
		(end 67.9831 -140.2334)
		(width 0.127)
		(layer "F.Cu")
		(net "FP_RETBTN")
	)
	(segment
		(start 67.8688 -138.1379)
		(end 67.891914 -138.114786)
		(width 0.127)
		(layer "F.Cu")
		(net "FP_RETBTN")
	)
	(segment
		(start 67.8688 -139.2428)
		(end 67.8688 -138.1379)
		(width 0.127)
		(layer "F.Cu")
		(net "FP_RETBTN")
	)
	(segment
		(start 69.65823 -140.196316)
		(end 68.020184 -140.196316)
		(width 0.127)
		(layer "F.Cu")
		(net "FP_RETBTN")
	)
	(via
		(at 67.8688 -139.2428)
		(size 0.6604)
		(drill 0.3302)
		(layers "F.Cu" "B.Cu")
		(net "FP_RETBTN")
	)
	(segment
		(start 73.6346 -140.0302)
		(end 74.0283 -140.0302)
		(width 0.127)
		(layer "F.Cu")
		(net "FP_RESET_RC_N")
	)
	(segment
		(start 72.8218 -140.5382)
		(end 72.9488 -140.5382)
		(width 0.127)
		(layer "F.Cu")
		(net "FP_RESET_RC_N")
	)
	(segment
		(start 72.9488 -140.5382)
		(end 73.1266 -140.5382)
		(width 0.127)
		(layer "F.Cu")
		(net "FP_RESET_RC_N")
	)
	(segment
		(start 71.53783 -140.196316)
		(end 72.479916 -140.196316)
		(width 0.127)
		(layer "F.Cu")
		(net "FP_RESET_RC_N")
	)
	(segment
		(start 73.1266 -140.5382)
		(end 73.6346 -140.0302)
		(width 0.127)
		(layer "F.Cu")
		(net "FP_RESET_RC_N")
	)
	(segment
		(start 72.479916 -140.196316)
		(end 72.8218 -140.5382)
		(width 0.127)
		(layer "F.Cu")
		(net "FP_RESET_RC_N")
	)
	(via
		(at 72.9488 -140.5382)
		(size 0.6604)
		(drill 0.3302)
		(layers "F.Cu" "B.Cu")
		(net "FP_RESET_RC_N")
	)
	(segment
		(start 68.1609 -125.452886)
		(end 67.076828 -126.536958)
		(width 0.127)
		(layer "F.Cu")
		(net "FLA_CS_1_R")
	)
	(segment
		(start 65.06718 -126.536958)
		(end 64.643 -126.961138)
		(width 0.127)
		(layer "F.Cu")
		(net "FLA_CS_1_R")
	)
	(segment
		(start 65.806066 -124.5362)
		(end 68.1609 -124.5362)
		(width 0.127)
		(layer "F.Cu")
		(net "FLA_CS_1_R")
	)
	(segment
		(start 64.643 -126.961138)
		(end 64.643 -129.4384)
		(width 0.127)
		(layer "F.Cu")
		(net "FLA_CS_1_R")
	)
	(segment
		(start 68.1609 -124.5362)
		(end 68.1609 -125.452886)
		(width 0.127)
		(layer "F.Cu")
		(net "FLA_CS_1_R")
	)
	(segment
		(start 67.076828 -126.536958)
		(end 65.06718 -126.536958)
		(width 0.127)
		(layer "F.Cu")
		(net "FLA_CS_1_R")
	)
	(via
		(at 36.9316 -133.107684)
		(size 0.508)
		(drill 0.254)
		(layers "F.Cu" "B.Cu")
		(net "FLA_CS_1_R")
	)
	(via
		(at 64.643 -129.4384)
		(size 0.508)
		(drill 0.254)
		(layers "F.Cu" "B.Cu")
		(net "FLA_CS_1_R")
	)
	(segment
		(start 36.9316 -133.107684)
		(end 36.9316 -135.2677)
		(width 0.127)
		(layer "B.Cu")
		(net "FLA_CS_1_R")
	)
	(segment
		(start 59.9948 -130.3401)
		(end 59.068208 -129.413508)
		(width 0.127)
		(layer "In5.Cu")
		(net "FLA_CS_1_R")
	)
	(segment
		(start 39.712392 -132.448808)
		(end 37.590476 -132.448808)
		(width 0.127)
		(layer "In5.Cu")
		(net "FLA_CS_1_R")
	)
	(segment
		(start 37.590476 -132.448808)
		(end 36.9316 -133.107684)
		(width 0.127)
		(layer "In5.Cu")
		(net "FLA_CS_1_R")
	)
	(segment
		(start 61.087 -130.3401)
		(end 59.9948 -130.3401)
		(width 0.127)
		(layer "In5.Cu")
		(net "FLA_CS_1_R")
	)
	(segment
		(start 40.299894 -131.861306)
		(end 39.712392 -132.448808)
		(width 0.127)
		(layer "In5.Cu")
		(net "FLA_CS_1_R")
	)
	(segment
		(start 59.068208 -129.413508)
		(end 56.170576 -129.413508)
		(width 0.127)
		(layer "In5.Cu")
		(net "FLA_CS_1_R")
	)
	(segment
		(start 61.9887 -129.4384)
		(end 61.087 -130.3401)
		(width 0.127)
		(layer "In5.Cu")
		(net "FLA_CS_1_R")
	)
	(segment
		(start 56.170576 -129.413508)
		(end 53.722778 -131.861306)
		(width 0.127)
		(layer "In5.Cu")
		(net "FLA_CS_1_R")
	)
	(segment
		(start 64.643 -129.4384)
		(end 61.9887 -129.4384)
		(width 0.127)
		(layer "In5.Cu")
		(net "FLA_CS_1_R")
	)
	(segment
		(start 53.722778 -131.861306)
		(end 40.299894 -131.861306)
		(width 0.127)
		(layer "In5.Cu")
		(net "FLA_CS_1_R")
	)
	(segment
		(start 39.699946 -138.600434)
		(end 39.700454 -138.600434)
		(width 0.127)
		(layer "F.Cu")
		(net "FLA_CS_1")
	)
	(segment
		(start 39.700454 -138.600434)
		(end 40.099996 -138.999976)
		(width 0.127)
		(layer "F.Cu")
		(net "FLA_CS_1")
	)
	(via
		(at 39.699946 -138.600434)
		(size 0.4572)
		(drill 0.2032)
		(layers "F.Cu" "B.Cu")
		(net "FLA_CS_1")
	)
	(via
		(at 36.8681 -137.2235)
		(size 0.6096)
		(drill 0.3048)
		(layers "F.Cu" "B.Cu")
		(net "FLA_CS_1")
	)
	(segment
		(start 38.0746 -138.6713)
		(end 39.62908 -138.6713)
		(width 0.127)
		(layer "B.Cu")
		(net "FLA_CS_1")
	)
	(segment
		(start 39.62908 -138.6713)
		(end 39.699946 -138.600434)
		(width 0.127)
		(layer "B.Cu")
		(net "FLA_CS_1")
	)
	(segment
		(start 36.8681 -136.2202)
		(end 36.9316 -136.1567)
		(width 0.127)
		(layer "B.Cu")
		(net "FLA_CS_1")
	)
	(segment
		(start 36.8681 -137.2235)
		(end 36.8681 -137.4648)
		(width 0.127)
		(layer "B.Cu")
		(net "FLA_CS_1")
	)
	(segment
		(start 36.8681 -137.2235)
		(end 36.8681 -136.2202)
		(width 0.127)
		(layer "B.Cu")
		(net "FLA_CS_1")
	)
	(segment
		(start 36.8681 -137.4648)
		(end 38.0746 -138.6713)
		(width 0.127)
		(layer "B.Cu")
		(net "FLA_CS_1")
	)
	(segment
		(start 41.498012 -124.546868)
		(end 41.48709 -124.535946)
		(width 0.127)
		(layer "F.Cu")
		(net "FLA_CS_0_R")
	)
	(segment
		(start 46.552358 -124.238512)
		(end 46.552358 -125.241558)
		(width 0.127)
		(layer "F.Cu")
		(net "FLA_CS_0_R")
	)
	(segment
		(start 43.12666 -124.238512)
		(end 42.818304 -124.546868)
		(width 0.127)
		(layer "F.Cu")
		(net "FLA_CS_0_R")
	)
	(segment
		(start 34.29 -134.5438)
		(end 33.9852 -134.239)
		(width 0.127)
		(layer "F.Cu")
		(net "FLA_CS_0_R")
	)
	(segment
		(start 45.44568 -124.238512)
		(end 43.12666 -124.238512)
		(width 0.127)
		(layer "F.Cu")
		(net "FLA_CS_0_R")
	)
	(segment
		(start 42.818304 -124.546868)
		(end 41.498012 -124.546868)
		(width 0.127)
		(layer "F.Cu")
		(net "FLA_CS_0_R")
	)
	(segment
		(start 46.552358 -125.241558)
		(end 46.5582 -125.2474)
		(width 0.127)
		(layer "F.Cu")
		(net "FLA_CS_0_R")
	)
	(segment
		(start 45.44568 -124.238512)
		(end 46.552358 -124.238512)
		(width 0.127)
		(layer "F.Cu")
		(net "FLA_CS_0_R")
	)
	(segment
		(start 34.7599 -134.5438)
		(end 34.29 -134.5438)
		(width 0.127)
		(layer "F.Cu")
		(net "FLA_CS_0_R")
	)
	(via
		(at 35.052 -123.4186)
		(size 0.508)
		(drill 0.254)
		(layers "F.Cu" "B.Cu")
		(net "FLA_CS_0_R")
	)
	(via
		(at 33.9852 -134.239)
		(size 0.508)
		(drill 0.254)
		(layers "F.Cu" "B.Cu")
		(net "FLA_CS_0_R")
	)
	(via
		(at 46.5582 -125.2474)
		(size 0.508)
		(drill 0.254)
		(layers "F.Cu" "B.Cu")
		(net "FLA_CS_0_R")
	)
	(segment
		(start 36.08451 -133.79069)
		(end 35.5092 -134.366)
		(width 0.127)
		(layer "In2.Cu")
		(net "FLA_CS_0_R")
	)
	(segment
		(start 34.1122 -134.366)
		(end 33.9852 -134.239)
		(width 0.127)
		(layer "In2.Cu")
		(net "FLA_CS_0_R")
	)
	(segment
		(start 35.311588 -123.982988)
		(end 35.311588 -129.164588)
		(width 0.127)
		(layer "In2.Cu")
		(net "FLA_CS_0_R")
	)
	(segment
		(start 35.052 -123.7234)
		(end 35.311588 -123.982988)
		(width 0.127)
		(layer "In2.Cu")
		(net "FLA_CS_0_R")
	)
	(segment
		(start 35.5092 -134.366)
		(end 34.1122 -134.366)
		(width 0.127)
		(layer "In2.Cu")
		(net "FLA_CS_0_R")
	)
	(segment
		(start 36.08451 -129.93751)
		(end 36.08451 -133.79069)
		(width 0.127)
		(layer "In2.Cu")
		(net "FLA_CS_0_R")
	)
	(segment
		(start 35.052 -123.4186)
		(end 35.052 -123.7234)
		(width 0.127)
		(layer "In2.Cu")
		(net "FLA_CS_0_R")
	)
	(segment
		(start 35.311588 -129.164588)
		(end 36.08451 -129.93751)
		(width 0.127)
		(layer "In2.Cu")
		(net "FLA_CS_0_R")
	)
	(segment
		(start 41.531032 -125.557534)
		(end 46.248066 -125.557534)
		(width 0.127)
		(layer "In5.Cu")
		(net "FLA_CS_0_R")
	)
	(segment
		(start 35.052 -123.7234)
		(end 37.5666 -126.238)
		(width 0.127)
		(layer "In5.Cu")
		(net "FLA_CS_0_R")
	)
	(segment
		(start 40.850566 -126.238)
		(end 41.531032 -125.557534)
		(width 0.127)
		(layer "In5.Cu")
		(net "FLA_CS_0_R")
	)
	(segment
		(start 35.052 -123.4186)
		(end 35.052 -123.7234)
		(width 0.127)
		(layer "In5.Cu")
		(net "FLA_CS_0_R")
	)
	(segment
		(start 37.5666 -126.238)
		(end 40.850566 -126.238)
		(width 0.127)
		(layer "In5.Cu")
		(net "FLA_CS_0_R")
	)
	(segment
		(start 46.248066 -125.557534)
		(end 46.5582 -125.2474)
		(width 0.127)
		(layer "In5.Cu")
		(net "FLA_CS_0_R")
	)
	(segment
		(start 36.685728 -136.939528)
		(end 36.8554 -137.1092)
		(width 0.127)
		(layer "F.Cu")
		(net "FLA_CS_0")
	)
	(segment
		(start 38.3032 -138.557)
		(end 36.8554 -137.1092)
		(width 0.127)
		(layer "F.Cu")
		(net "FLA_CS_0")
	)
	(segment
		(start 35.6489 -134.667244)
		(end 36.685728 -135.704072)
		(width 0.127)
		(layer "F.Cu")
		(net "FLA_CS_0")
	)
	(segment
		(start 38.85692 -138.557)
		(end 38.3032 -138.557)
		(width 0.127)
		(layer "F.Cu")
		(net "FLA_CS_0")
	)
	(segment
		(start 39.299896 -138.999976)
		(end 38.85692 -138.557)
		(width 0.127)
		(layer "F.Cu")
		(net "FLA_CS_0")
	)
	(segment
		(start 35.6489 -134.5438)
		(end 35.6489 -134.667244)
		(width 0.127)
		(layer "F.Cu")
		(net "FLA_CS_0")
	)
	(segment
		(start 36.685728 -135.704072)
		(end 36.685728 -136.939528)
		(width 0.127)
		(layer "F.Cu")
		(net "FLA_CS_0")
	)
	(via
		(at 36.8554 -137.1092)
		(size 0.6604)
		(drill 0.3302)
		(layers "F.Cu" "B.Cu")
		(net "FLA_CS_0")
	)
	(segment
		(start 53.699918 -138.199622)
		(end 53.699918 -138.199876)
		(width 0.127)
		(layer "F.Cu")
		(net "COMP_PWR_BTN_R_N")
	)
	(segment
		(start 54.099714 -137.799826)
		(end 53.699918 -138.199622)
		(width 0.127)
		(layer "F.Cu")
		(net "COMP_PWR_BTN_R_N")
	)
	(via
		(at 57.28462 -136.446768)
		(size 0.6096)
		(drill 0.3048)
		(layers "F.Cu" "B.Cu")
		(net "COMP_PWR_BTN_R_N")
	)
	(via
		(at 54.099714 -137.799826)
		(size 0.4572)
		(drill 0.2032)
		(layers "F.Cu" "B.Cu")
		(net "COMP_PWR_BTN_R_N")
	)
	(segment
		(start 54.70652 -136.9314)
		(end 54.099714 -137.538206)
		(width 0.127)
		(layer "B.Cu")
		(net "COMP_PWR_BTN_R_N")
	)
	(segment
		(start 56.799988 -136.9314)
		(end 54.70652 -136.9314)
		(width 0.127)
		(layer "B.Cu")
		(net "COMP_PWR_BTN_R_N")
	)
	(segment
		(start 54.099714 -137.538206)
		(end 54.099714 -137.799826)
		(width 0.127)
		(layer "B.Cu")
		(net "COMP_PWR_BTN_R_N")
	)
	(segment
		(start 57.937908 -135.354568)
		(end 57.937908 -135.79348)
		(width 0.127)
		(layer "B.Cu")
		(net "COMP_PWR_BTN_R_N")
	)
	(segment
		(start 57.937908 -135.79348)
		(end 57.28462 -136.446768)
		(width 0.127)
		(layer "B.Cu")
		(net "COMP_PWR_BTN_R_N")
	)
	(segment
		(start 57.28462 -136.446768)
		(end 56.799988 -136.9314)
		(width 0.127)
		(layer "B.Cu")
		(net "COMP_PWR_BTN_R_N")
	)
	(segment
		(start 101.62032 -126.88189)
		(end 101.62032 -127.216916)
		(width 0.127)
		(layer "F.Cu")
		(net "COMP_PWR_BTN_N")
	)
	(segment
		(start 100.565712 -121.750582)
		(end 101.263958 -121.052336)
		(width 0.127)
		(layer "F.Cu")
		(net "COMP_PWR_BTN_N")
	)
	(segment
		(start 100.103686 -123.941078)
		(end 100.103686 -125.365256)
		(width 0.127)
		(layer "F.Cu")
		(net "COMP_PWR_BTN_N")
	)
	(segment
		(start 100.565712 -122.66295)
		(end 100.565712 -123.479052)
		(width 0.127)
		(layer "F.Cu")
		(net "COMP_PWR_BTN_N")
	)
	(segment
		(start 108.177076 -26.3144)
		(end 111.271558 -29.408882)
		(width 0.127)
		(layer "F.Cu")
		(net "COMP_PWR_BTN_N")
	)
	(segment
		(start 111.271558 -39.82847)
		(end 110.700058 -40.39997)
		(width 0.127)
		(layer "F.Cu")
		(net "COMP_PWR_BTN_N")
	)
	(segment
		(start 103.539544 -44.5643)
		(end 103.539544 -27.817318)
		(width 0.127)
		(layer "F.Cu")
		(net "COMP_PWR_BTN_N")
	)
	(segment
		(start 100.103686 -125.365256)
		(end 101.62032 -126.88189)
		(width 0.127)
		(layer "F.Cu")
		(net "COMP_PWR_BTN_N")
	)
	(segment
		(start 111.271558 -29.408882)
		(end 111.271558 -39.82847)
		(width 0.127)
		(layer "F.Cu")
		(net "COMP_PWR_BTN_N")
	)
	(segment
		(start 100.565712 -122.66295)
		(end 100.565712 -121.750582)
		(width 0.127)
		(layer "F.Cu")
		(net "COMP_PWR_BTN_N")
	)
	(segment
		(start 100.565712 -123.479052)
		(end 100.103686 -123.941078)
		(width 0.127)
		(layer "F.Cu")
		(net "COMP_PWR_BTN_N")
	)
	(segment
		(start 101.263958 -46.839886)
		(end 103.539544 -44.5643)
		(width 0.127)
		(layer "F.Cu")
		(net "COMP_PWR_BTN_N")
	)
	(segment
		(start 101.263958 -121.052336)
		(end 101.263958 -46.839886)
		(width 0.127)
		(layer "F.Cu")
		(net "COMP_PWR_BTN_N")
	)
	(segment
		(start 103.539544 -27.817318)
		(end 105.042462 -26.3144)
		(width 0.127)
		(layer "F.Cu")
		(net "COMP_PWR_BTN_N")
	)
	(segment
		(start 105.042462 -26.3144)
		(end 108.177076 -26.3144)
		(width 0.127)
		(layer "F.Cu")
		(net "COMP_PWR_BTN_N")
	)
	(via
		(at 101.62032 -127.216916)
		(size 0.508)
		(drill 0.254)
		(layers "F.Cu" "B.Cu")
		(net "COMP_PWR_BTN_N")
	)
	(via
		(at 100.565712 -122.66295)
		(size 0.6604)
		(drill 0.3302)
		(layers "F.Cu" "B.Cu")
		(net "COMP_PWR_BTN_N")
	)
	(via
		(at 61.595 -132.969)
		(size 0.508)
		(drill 0.254)
		(layers "F.Cu" "B.Cu")
		(net "COMP_PWR_BTN_N")
	)
	(segment
		(start 59.827414 -133.542786)
		(end 59.827414 -134.05612)
		(width 0.127)
		(layer "B.Cu")
		(net "COMP_PWR_BTN_N")
	)
	(segment
		(start 59.018932 -134.465568)
		(end 57.937908 -134.465568)
		(width 0.127)
		(layer "B.Cu")
		(net "COMP_PWR_BTN_N")
	)
	(segment
		(start 59.827414 -134.05612)
		(end 59.454034 -134.4295)
		(width 0.127)
		(layer "B.Cu")
		(net "COMP_PWR_BTN_N")
	)
	(segment
		(start 61.595 -132.969)
		(end 60.4012 -132.969)
		(width 0.127)
		(layer "B.Cu")
		(net "COMP_PWR_BTN_N")
	)
	(segment
		(start 59.055 -134.4295)
		(end 59.018932 -134.465568)
		(width 0.127)
		(layer "B.Cu")
		(net "COMP_PWR_BTN_N")
	)
	(segment
		(start 59.454034 -134.4295)
		(end 59.055 -134.4295)
		(width 0.127)
		(layer "B.Cu")
		(net "COMP_PWR_BTN_N")
	)
	(segment
		(start 60.4012 -132.969)
		(end 59.827414 -133.542786)
		(width 0.127)
		(layer "B.Cu")
		(net "COMP_PWR_BTN_N")
	)
	(segment
		(start 65.910206 -132.0165)
		(end 65.3923 -132.0165)
		(width 0.127)
		(layer "In5.Cu")
		(net "COMP_PWR_BTN_N")
	)
	(segment
		(start 93.161104 -128.41224)
		(end 90.483944 -131.0894)
		(width 0.127)
		(layer "In5.Cu")
		(net "COMP_PWR_BTN_N")
	)
	(segment
		(start 90.483944 -131.0894)
		(end 86.755224 -131.0894)
		(width 0.127)
		(layer "In5.Cu")
		(net "COMP_PWR_BTN_N")
	)
	(segment
		(start 79.52867 -132.98932)
		(end 74.316844 -132.98932)
		(width 0.127)
		(layer "In5.Cu")
		(net "COMP_PWR_BTN_N")
	)
	(segment
		(start 85.972904 -131.166108)
		(end 84.738718 -132.400294)
		(width 0.127)
		(layer "In5.Cu")
		(net "COMP_PWR_BTN_N")
	)
	(segment
		(start 74.316844 -132.98932)
		(end 73.275698 -131.948174)
		(width 0.127)
		(layer "In5.Cu")
		(net "COMP_PWR_BTN_N")
	)
	(segment
		(start 67.162172 -131.948174)
		(end 65.978532 -131.948174)
		(width 0.127)
		(layer "In5.Cu")
		(net "COMP_PWR_BTN_N")
	)
	(segment
		(start 67.162426 -131.94792)
		(end 67.162172 -131.948174)
		(width 0.127)
		(layer "In5.Cu")
		(net "COMP_PWR_BTN_N")
	)
	(segment
		(start 100.424996 -128.41224)
		(end 93.161104 -128.41224)
		(width 0.127)
		(layer "In5.Cu")
		(net "COMP_PWR_BTN_N")
	)
	(segment
		(start 67.477894 -131.94792)
		(end 67.162426 -131.94792)
		(width 0.127)
		(layer "In5.Cu")
		(net "COMP_PWR_BTN_N")
	)
	(segment
		(start 101.62032 -127.216916)
		(end 100.424996 -128.41224)
		(width 0.127)
		(layer "In5.Cu")
		(net "COMP_PWR_BTN_N")
	)
	(segment
		(start 64.4398 -132.969)
		(end 61.595 -132.969)
		(width 0.127)
		(layer "In5.Cu")
		(net "COMP_PWR_BTN_N")
	)
	(segment
		(start 80.117696 -132.400294)
		(end 79.52867 -132.98932)
		(width 0.127)
		(layer "In5.Cu")
		(net "COMP_PWR_BTN_N")
	)
	(segment
		(start 67.478148 -131.948174)
		(end 67.477894 -131.94792)
		(width 0.127)
		(layer "In5.Cu")
		(net "COMP_PWR_BTN_N")
	)
	(segment
		(start 73.275698 -131.948174)
		(end 67.478148 -131.948174)
		(width 0.127)
		(layer "In5.Cu")
		(net "COMP_PWR_BTN_N")
	)
	(segment
		(start 65.3923 -132.0165)
		(end 64.4398 -132.969)
		(width 0.127)
		(layer "In5.Cu")
		(net "COMP_PWR_BTN_N")
	)
	(segment
		(start 86.755224 -131.0894)
		(end 86.678516 -131.166108)
		(width 0.127)
		(layer "In5.Cu")
		(net "COMP_PWR_BTN_N")
	)
	(segment
		(start 84.738718 -132.400294)
		(end 80.117696 -132.400294)
		(width 0.127)
		(layer "In5.Cu")
		(net "COMP_PWR_BTN_N")
	)
	(segment
		(start 86.678516 -131.166108)
		(end 85.972904 -131.166108)
		(width 0.127)
		(layer "In5.Cu")
		(net "COMP_PWR_BTN_N")
	)
	(segment
		(start 65.978532 -131.948174)
		(end 65.910206 -132.0165)
		(width 0.127)
		(layer "In5.Cu")
		(net "COMP_PWR_BTN_N")
	)
	(segment
		(start 34.595562 -154.883358)
		(end 34.595562 -154.88031)
		(width 0.127)
		(layer "F.Cu")
		(net "COMP_POWER_FAIL_R_N")
	)
	(segment
		(start 37.493194 -153.0858)
		(end 39.147242 -151.431752)
		(width 0.127)
		(layer "F.Cu")
		(net "COMP_POWER_FAIL_R_N")
	)
	(segment
		(start 39.668196 -151.431752)
		(end 40.099996 -150.999952)
		(width 0.127)
		(layer "F.Cu")
		(net "COMP_POWER_FAIL_R_N")
	)
	(segment
		(start 35.549586 -153.926286)
		(end 36.390072 -153.0858)
		(width 0.127)
		(layer "F.Cu")
		(net "COMP_POWER_FAIL_R_N")
	)
	(segment
		(start 39.147242 -151.431752)
		(end 39.668196 -151.431752)
		(width 0.127)
		(layer "F.Cu")
		(net "COMP_POWER_FAIL_R_N")
	)
	(segment
		(start 36.390072 -153.0858)
		(end 37.493194 -153.0858)
		(width 0.127)
		(layer "F.Cu")
		(net "COMP_POWER_FAIL_R_N")
	)
	(segment
		(start 34.595562 -154.88031)
		(end 35.549586 -153.926286)
		(width 0.127)
		(layer "F.Cu")
		(net "COMP_POWER_FAIL_R_N")
	)
	(via
		(at 35.549586 -153.926286)
		(size 0.6604)
		(drill 0.3302)
		(layers "F.Cu" "B.Cu")
		(net "COMP_POWER_FAIL_R_N")
	)
	(segment
		(start 31.367476 -154.883358)
		(end 31.357062 -154.893772)
		(width 0.127)
		(layer "F.Cu")
		(net "COMP_POWER_FAIL_N")
	)
	(segment
		(start 33.706562 -154.883358)
		(end 31.367476 -154.883358)
		(width 0.127)
		(layer "F.Cu")
		(net "COMP_POWER_FAIL_N")
	)
	(segment
		(start 31.357062 -155.715462)
		(end 31.369 -155.7274)
		(width 0.127)
		(layer "F.Cu")
		(net "COMP_POWER_FAIL_N")
	)
	(segment
		(start 31.357062 -154.893772)
		(end 31.357062 -155.715462)
		(width 0.127)
		(layer "F.Cu")
		(net "COMP_POWER_FAIL_N")
	)
	(via
		(at 31.369 -155.7274)
		(size 0.508)
		(drill 0.254)
		(layers "F.Cu" "B.Cu")
		(net "COMP_POWER_FAIL_N")
	)
	(via
		(at 100.626164 -175.92802)
		(size 0.508)
		(drill 0.254)
		(layers "F.Cu" "B.Cu")
		(net "COMP_POWER_FAIL_N")
	)
	(segment
		(start 100.185474 -113.210594)
		(end 100.185474 -123.322842)
		(width 0.127)
		(layer "In2.Cu")
		(net "COMP_POWER_FAIL_N")
	)
	(segment
		(start 109.894878 -29.947616)
		(end 106.827066 -29.947616)
		(width 0.127)
		(layer "In2.Cu")
		(net "COMP_POWER_FAIL_N")
	)
	(segment
		(start 112.499902 -40.600122)
		(end 111.805212 -39.905432)
		(width 0.127)
		(layer "In2.Cu")
		(net "COMP_POWER_FAIL_N")
	)
	(segment
		(start 100.207318 -164.176964)
		(end 99.702366 -164.681916)
		(width 0.127)
		(layer "In2.Cu")
		(net "COMP_POWER_FAIL_N")
	)
	(segment
		(start 99.626166 -128.083056)
		(end 100.007166 -128.464056)
		(width 0.127)
		(layer "In2.Cu")
		(net "COMP_POWER_FAIL_N")
	)
	(segment
		(start 100.207318 -155.462478)
		(end 100.207318 -164.176964)
		(width 0.127)
		(layer "In2.Cu")
		(net "COMP_POWER_FAIL_N")
	)
	(segment
		(start 99.626166 -123.88215)
		(end 99.626166 -128.083056)
		(width 0.127)
		(layer "In2.Cu")
		(net "COMP_POWER_FAIL_N")
	)
	(segment
		(start 99.198938 -146.835114)
		(end 100.116894 -147.75307)
		(width 0.127)
		(layer "In2.Cu")
		(net "COMP_POWER_FAIL_N")
	)
	(segment
		(start 100.007166 -128.464056)
		(end 100.007166 -140.319506)
		(width 0.127)
		(layer "In2.Cu")
		(net "COMP_POWER_FAIL_N")
	)
	(segment
		(start 99.3013 -173.422564)
		(end 100.202746 -174.32401)
		(width 0.127)
		(layer "In2.Cu")
		(net "COMP_POWER_FAIL_N")
	)
	(segment
		(start 99.702366 -166.985696)
		(end 100.202746 -167.486076)
		(width 0.127)
		(layer "In2.Cu")
		(net "COMP_POWER_FAIL_N")
	)
	(segment
		(start 104.9528 -31.821882)
		(end 104.9528 -41.007792)
		(width 0.127)
		(layer "In2.Cu")
		(net "COMP_POWER_FAIL_N")
	)
	(segment
		(start 100.116894 -147.75307)
		(end 100.116894 -155.372054)
		(width 0.127)
		(layer "In2.Cu")
		(net "COMP_POWER_FAIL_N")
	)
	(segment
		(start 99.393502 -112.418622)
		(end 100.185474 -113.210594)
		(width 0.127)
		(layer "In2.Cu")
		(net "COMP_POWER_FAIL_N")
	)
	(segment
		(start 111.805212 -39.905432)
		(end 111.805212 -31.85795)
		(width 0.127)
		(layer "In2.Cu")
		(net "COMP_POWER_FAIL_N")
	)
	(segment
		(start 100.202746 -175.504602)
		(end 100.626164 -175.92802)
		(width 0.127)
		(layer "In2.Cu")
		(net "COMP_POWER_FAIL_N")
	)
	(segment
		(start 100.185474 -123.322842)
		(end 99.626166 -123.88215)
		(width 0.127)
		(layer "In2.Cu")
		(net "COMP_POWER_FAIL_N")
	)
	(segment
		(start 100.202746 -171.403772)
		(end 99.966018 -171.6405)
		(width 0.127)
		(layer "In2.Cu")
		(net "COMP_POWER_FAIL_N")
	)
	(segment
		(start 100.202746 -174.32401)
		(end 100.202746 -175.504602)
		(width 0.127)
		(layer "In2.Cu")
		(net "COMP_POWER_FAIL_N")
	)
	(segment
		(start 99.198938 -143.585184)
		(end 99.198938 -146.835114)
		(width 0.127)
		(layer "In2.Cu")
		(net "COMP_POWER_FAIL_N")
	)
	(segment
		(start 104.9528 -41.007792)
		(end 99.739958 -46.220634)
		(width 0.127)
		(layer "In2.Cu")
		(net "COMP_POWER_FAIL_N")
	)
	(segment
		(start 100.116894 -155.372054)
		(end 100.207318 -155.462478)
		(width 0.127)
		(layer "In2.Cu")
		(net "COMP_POWER_FAIL_N")
	)
	(segment
		(start 99.576382 -171.6405)
		(end 99.3013 -171.915582)
		(width 0.127)
		(layer "In2.Cu")
		(net "COMP_POWER_FAIL_N")
	)
	(segment
		(start 99.393502 -84.366608)
		(end 99.393502 -112.418622)
		(width 0.127)
		(layer "In2.Cu")
		(net "COMP_POWER_FAIL_N")
	)
	(segment
		(start 100.007166 -140.319506)
		(end 99.676458 -140.650214)
		(width 0.127)
		(layer "In2.Cu")
		(net "COMP_POWER_FAIL_N")
	)
	(segment
		(start 99.676458 -143.107664)
		(end 99.198938 -143.585184)
		(width 0.127)
		(layer "In2.Cu")
		(net "COMP_POWER_FAIL_N")
	)
	(segment
		(start 99.966018 -171.6405)
		(end 99.576382 -171.6405)
		(width 0.127)
		(layer "In2.Cu")
		(net "COMP_POWER_FAIL_N")
	)
	(segment
		(start 99.739958 -46.220634)
		(end 99.739958 -84.020152)
		(width 0.127)
		(layer "In2.Cu")
		(net "COMP_POWER_FAIL_N")
	)
	(segment
		(start 99.676458 -140.650214)
		(end 99.676458 -143.107664)
		(width 0.127)
		(layer "In2.Cu")
		(net "COMP_POWER_FAIL_N")
	)
	(segment
		(start 100.202746 -167.486076)
		(end 100.202746 -171.403772)
		(width 0.127)
		(layer "In2.Cu")
		(net "COMP_POWER_FAIL_N")
	)
	(segment
		(start 106.827066 -29.947616)
		(end 104.9528 -31.821882)
		(width 0.127)
		(layer "In2.Cu")
		(net "COMP_POWER_FAIL_N")
	)
	(segment
		(start 99.702366 -164.681916)
		(end 99.702366 -166.985696)
		(width 0.127)
		(layer "In2.Cu")
		(net "COMP_POWER_FAIL_N")
	)
	(segment
		(start 99.3013 -171.915582)
		(end 99.3013 -173.422564)
		(width 0.127)
		(layer "In2.Cu")
		(net "COMP_POWER_FAIL_N")
	)
	(segment
		(start 99.739958 -84.020152)
		(end 99.393502 -84.366608)
		(width 0.127)
		(layer "In2.Cu")
		(net "COMP_POWER_FAIL_N")
	)
	(segment
		(start 111.805212 -31.85795)
		(end 109.894878 -29.947616)
		(width 0.127)
		(layer "In2.Cu")
		(net "COMP_POWER_FAIL_N")
	)
	(segment
		(start 37.867082 -161.9758)
		(end 37.359082 -161.4678)
		(width 0.127)
		(layer "In5.Cu")
		(net "COMP_POWER_FAIL_N")
	)
	(segment
		(start 100.123244 -175.4251)
		(end 99.500182 -175.4251)
		(width 0.127)
		(layer "In5.Cu")
		(net "COMP_POWER_FAIL_N")
	)
	(segment
		(start 87.185754 -174.6123)
		(end 84.764118 -174.6123)
		(width 0.127)
		(layer "In5.Cu")
		(net "COMP_POWER_FAIL_N")
	)
	(segment
		(start 59.363864 -174.1932)
		(end 52.569364 -167.3987)
		(width 0.127)
		(layer "In5.Cu")
		(net "COMP_POWER_FAIL_N")
	)
	(segment
		(start 95.447866 -176.20742)
		(end 94.881446 -175.641)
		(width 0.127)
		(layer "In5.Cu")
		(net "COMP_POWER_FAIL_N")
	)
	(segment
		(start 99.500182 -175.4251)
		(end 99.093782 -175.8315)
		(width 0.127)
		(layer "In5.Cu")
		(net "COMP_POWER_FAIL_N")
	)
	(segment
		(start 100.626164 -175.92802)
		(end 100.123244 -175.4251)
		(width 0.127)
		(layer "In5.Cu")
		(net "COMP_POWER_FAIL_N")
	)
	(segment
		(start 94.881446 -175.641)
		(end 91.757754 -175.641)
		(width 0.127)
		(layer "In5.Cu")
		(net "COMP_POWER_FAIL_N")
	)
	(segment
		(start 41.148508 -164.089842)
		(end 39.034466 -161.9758)
		(width 0.127)
		(layer "In5.Cu")
		(net "COMP_POWER_FAIL_N")
	)
	(segment
		(start 32.5755 -156.9339)
		(end 31.369 -155.7274)
		(width 0.127)
		(layer "In5.Cu")
		(net "COMP_POWER_FAIL_N")
	)
	(segment
		(start 32.5755 -157.7975)
		(end 32.5755 -156.9339)
		(width 0.127)
		(layer "In5.Cu")
		(net "COMP_POWER_FAIL_N")
	)
	(segment
		(start 39.034466 -161.9758)
		(end 37.867082 -161.9758)
		(width 0.127)
		(layer "In5.Cu")
		(net "COMP_POWER_FAIL_N")
	)
	(segment
		(start 91.5035 -175.895254)
		(end 88.468708 -175.895254)
		(width 0.127)
		(layer "In5.Cu")
		(net "COMP_POWER_FAIL_N")
	)
	(segment
		(start 99.093782 -175.8315)
		(end 98.239834 -175.8315)
		(width 0.127)
		(layer "In5.Cu")
		(net "COMP_POWER_FAIL_N")
	)
	(segment
		(start 52.569364 -167.3987)
		(end 48.9839 -167.3987)
		(width 0.127)
		(layer "In5.Cu")
		(net "COMP_POWER_FAIL_N")
	)
	(segment
		(start 44.108878 -164.089842)
		(end 41.148508 -164.089842)
		(width 0.127)
		(layer "In5.Cu")
		(net "COMP_POWER_FAIL_N")
	)
	(segment
		(start 98.239834 -175.8315)
		(end 97.863914 -176.20742)
		(width 0.127)
		(layer "In5.Cu")
		(net "COMP_POWER_FAIL_N")
	)
	(segment
		(start 46.575218 -166.556182)
		(end 44.108878 -164.089842)
		(width 0.127)
		(layer "In5.Cu")
		(net "COMP_POWER_FAIL_N")
	)
	(segment
		(start 48.141382 -166.556182)
		(end 46.575218 -166.556182)
		(width 0.127)
		(layer "In5.Cu")
		(net "COMP_POWER_FAIL_N")
	)
	(segment
		(start 84.738718 -174.6377)
		(end 73.516998 -174.6377)
		(width 0.127)
		(layer "In5.Cu")
		(net "COMP_POWER_FAIL_N")
	)
	(segment
		(start 69.830188 -174.1932)
		(end 59.363864 -174.1932)
		(width 0.127)
		(layer "In5.Cu")
		(net "COMP_POWER_FAIL_N")
	)
	(segment
		(start 84.764118 -174.6123)
		(end 84.738718 -174.6377)
		(width 0.127)
		(layer "In5.Cu")
		(net "COMP_POWER_FAIL_N")
	)
	(segment
		(start 97.863914 -176.20742)
		(end 95.447866 -176.20742)
		(width 0.127)
		(layer "In5.Cu")
		(net "COMP_POWER_FAIL_N")
	)
	(segment
		(start 73.516998 -174.6377)
		(end 72.754998 -173.8757)
		(width 0.127)
		(layer "In5.Cu")
		(net "COMP_POWER_FAIL_N")
	)
	(segment
		(start 48.9839 -167.3987)
		(end 48.141382 -166.556182)
		(width 0.127)
		(layer "In5.Cu")
		(net "COMP_POWER_FAIL_N")
	)
	(segment
		(start 91.757754 -175.641)
		(end 91.5035 -175.895254)
		(width 0.127)
		(layer "In5.Cu")
		(net "COMP_POWER_FAIL_N")
	)
	(segment
		(start 88.468708 -175.895254)
		(end 87.185754 -174.6123)
		(width 0.127)
		(layer "In5.Cu")
		(net "COMP_POWER_FAIL_N")
	)
	(segment
		(start 36.2458 -161.4678)
		(end 32.5755 -157.7975)
		(width 0.127)
		(layer "In5.Cu")
		(net "COMP_POWER_FAIL_N")
	)
	(segment
		(start 37.359082 -161.4678)
		(end 36.2458 -161.4678)
		(width 0.127)
		(layer "In5.Cu")
		(net "COMP_POWER_FAIL_N")
	)
	(segment
		(start 72.754998 -173.8757)
		(end 70.147688 -173.8757)
		(width 0.127)
		(layer "In5.Cu")
		(net "COMP_POWER_FAIL_N")
	)
	(segment
		(start 70.147688 -173.8757)
		(end 69.830188 -174.1932)
		(width 0.127)
		(layer "In5.Cu")
		(net "COMP_POWER_FAIL_N")
	)
	(segment
		(start 111.4044 -26.035)
		(end 113.071402 -27.702002)
		(width 0.127)
		(layer "F.Cu")
		(net "COMP_FAST_THROTTLE_N")
	)
	(segment
		(start 32.117538 -152.007316)
		(end 32.22498 -151.899874)
		(width 0.127)
		(layer "F.Cu")
		(net "COMP_FAST_THROTTLE_N")
	)
	(segment
		(start 112.818926 -39.200074)
		(end 112.499902 -39.200074)
		(width 0.127)
		(layer "F.Cu")
		(net "COMP_FAST_THROTTLE_N")
	)
	(segment
		(start 113.071402 -27.702002)
		(end 113.071402 -38.947598)
		(width 0.127)
		(layer "F.Cu")
		(net "COMP_FAST_THROTTLE_N")
	)
	(segment
		(start 33.3248 -152.2095)
		(end 32.890714 -151.775414)
		(width 0.127)
		(layer "F.Cu")
		(net "COMP_FAST_THROTTLE_N")
	)
	(segment
		(start 32.117538 -152.888442)
		(end 32.117538 -153.917904)
		(width 0.127)
		(layer "F.Cu")
		(net "COMP_FAST_THROTTLE_N")
	)
	(segment
		(start 111.4044 -23.122382)
		(end 111.4044 -26.035)
		(width 0.127)
		(layer "F.Cu")
		(net "COMP_FAST_THROTTLE_N")
	)
	(segment
		(start 32.117538 -153.917904)
		(end 32.359854 -154.16022)
		(width 0.127)
		(layer "F.Cu")
		(net "COMP_FAST_THROTTLE_N")
	)
	(segment
		(start 113.071402 -38.947598)
		(end 112.818926 -39.200074)
		(width 0.127)
		(layer "F.Cu")
		(net "COMP_FAST_THROTTLE_N")
	)
	(segment
		(start 32.890714 -151.775414)
		(end 32.34944 -151.775414)
		(width 0.127)
		(layer "F.Cu")
		(net "COMP_FAST_THROTTLE_N")
	)
	(segment
		(start 32.34944 -151.775414)
		(end 32.22498 -151.899874)
		(width 0.127)
		(layer "F.Cu")
		(net "COMP_FAST_THROTTLE_N")
	)
	(segment
		(start 32.117538 -152.888442)
		(end 32.117538 -152.007316)
		(width 0.127)
		(layer "F.Cu")
		(net "COMP_FAST_THROTTLE_N")
	)
	(via
		(at 32.22498 -151.899874)
		(size 0.6604)
		(drill 0.3302)
		(layers "F.Cu" "B.Cu")
		(net "COMP_FAST_THROTTLE_N")
	)
	(via
		(at 78.829662 -15.788386)
		(size 0.508)
		(drill 0.254)
		(layers "F.Cu" "B.Cu")
		(net "COMP_FAST_THROTTLE_N")
	)
	(via
		(at 32.359854 -154.16022)
		(size 0.508)
		(drill 0.254)
		(layers "F.Cu" "B.Cu")
		(net "COMP_FAST_THROTTLE_N")
	)
	(via
		(at 111.4044 -23.122382)
		(size 0.508)
		(drill 0.254)
		(layers "F.Cu" "B.Cu")
		(net "COMP_FAST_THROTTLE_N")
	)
	(via
		(at 82.6262 -164.7698)
		(size 0.508)
		(drill 0.254)
		(layers "F.Cu" "B.Cu")
		(net "COMP_FAST_THROTTLE_N")
	)
	(segment
		(start 32.359854 -156.019754)
		(end 32.4612 -156.1211)
		(width 0.127)
		(layer "B.Cu")
		(net "COMP_FAST_THROTTLE_N")
	)
	(segment
		(start 32.359854 -154.16022)
		(end 32.359854 -156.019754)
		(width 0.127)
		(layer "B.Cu")
		(net "COMP_FAST_THROTTLE_N")
	)
	(segment
		(start 82.5754 -164.719)
		(end 82.292444 -164.719)
		(width 0.127)
		(layer "In2.Cu")
		(net "COMP_FAST_THROTTLE_N")
	)
	(segment
		(start 78.5749 -147.26285)
		(end 78.3209 -147.00885)
		(width 0.127)
		(layer "In2.Cu")
		(net "COMP_FAST_THROTTLE_N")
	)
	(segment
		(start 78.818232 -112.1918)
		(end 82.646012 -112.1918)
		(width 0.127)
		(layer "In2.Cu")
		(net "COMP_FAST_THROTTLE_N")
	)
	(segment
		(start 83.2866 -43.649646)
		(end 84.5947 -42.341546)
		(width 0.127)
		(layer "In2.Cu")
		(net "COMP_FAST_THROTTLE_N")
	)
	(segment
		(start 82.862928 -99.741482)
		(end 82.862928 -68.961)
		(width 0.127)
		(layer "In2.Cu")
		(net "COMP_FAST_THROTTLE_N")
	)
	(segment
		(start 83.2866 -45.474128)
		(end 83.2866 -43.649646)
		(width 0.127)
		(layer "In2.Cu")
		(net "COMP_FAST_THROTTLE_N")
	)
	(segment
		(start 77.9018 -129.4892)
		(end 77.293978 -128.881378)
		(width 0.127)
		(layer "In2.Cu")
		(net "COMP_FAST_THROTTLE_N")
	)
	(segment
		(start 82.292444 -164.719)
		(end 81.1149 -163.541456)
		(width 0.127)
		(layer "In2.Cu")
		(net "COMP_FAST_THROTTLE_N")
	)
	(segment
		(start 82.583528 -46.1772)
		(end 83.2866 -45.474128)
		(width 0.127)
		(layer "In2.Cu")
		(net "COMP_FAST_THROTTLE_N")
	)
	(segment
		(start 73.600056 -117.409976)
		(end 78.818232 -112.1918)
		(width 0.127)
		(layer "In2.Cu")
		(net "COMP_FAST_THROTTLE_N")
	)
	(segment
		(start 82.862928 -68.961)
		(end 82.583528 -68.6816)
		(width 0.127)
		(layer "In2.Cu")
		(net "COMP_FAST_THROTTLE_N")
	)
	(segment
		(start 78.169008 -141.252448)
		(end 78.169008 -138.19505)
		(width 0.127)
		(layer "In2.Cu")
		(net "COMP_FAST_THROTTLE_N")
	)
	(segment
		(start 82.6262 -164.7698)
		(end 82.5754 -164.719)
		(width 0.127)
		(layer "In2.Cu")
		(net "COMP_FAST_THROTTLE_N")
	)
	(segment
		(start 81.1149 -160.006792)
		(end 79.8195 -158.711392)
		(width 0.127)
		(layer "In2.Cu")
		(net "COMP_FAST_THROTTLE_N")
	)
	(segment
		(start 77.9018 -131.36499)
		(end 77.9018 -129.4892)
		(width 0.127)
		(layer "In2.Cu")
		(net "COMP_FAST_THROTTLE_N")
	)
	(segment
		(start 77.635862 -134.272782)
		(end 77.77099 -134.137654)
		(width 0.127)
		(layer "In2.Cu")
		(net "COMP_FAST_THROTTLE_N")
	)
	(segment
		(start 79.8195 -158.711392)
		(end 79.8195 -150.39086)
		(width 0.127)
		(layer "In2.Cu")
		(net "COMP_FAST_THROTTLE_N")
	)
	(segment
		(start 78.5749 -149.14626)
		(end 78.5749 -147.26285)
		(width 0.127)
		(layer "In2.Cu")
		(net "COMP_FAST_THROTTLE_N")
	)
	(segment
		(start 81.1149 -163.541456)
		(end 81.1149 -160.006792)
		(width 0.127)
		(layer "In2.Cu")
		(net "COMP_FAST_THROTTLE_N")
	)
	(segment
		(start 84.5947 -42.341546)
		(end 84.5947 -36.995608)
		(width 0.127)
		(layer "In2.Cu")
		(net "COMP_FAST_THROTTLE_N")
	)
	(segment
		(start 78.3209 -147.00885)
		(end 78.3209 -141.40434)
		(width 0.127)
		(layer "In2.Cu")
		(net "COMP_FAST_THROTTLE_N")
	)
	(segment
		(start 77.77099 -131.4958)
		(end 77.9018 -131.36499)
		(width 0.127)
		(layer "In2.Cu")
		(net "COMP_FAST_THROTTLE_N")
	)
	(segment
		(start 78.3209 -141.40434)
		(end 78.169008 -141.252448)
		(width 0.127)
		(layer "In2.Cu")
		(net "COMP_FAST_THROTTLE_N")
	)
	(segment
		(start 77.293978 -128.881378)
		(end 77.293978 -127.337566)
		(width 0.127)
		(layer "In2.Cu")
		(net "COMP_FAST_THROTTLE_N")
	)
	(segment
		(start 77.635862 -137.661904)
		(end 77.635862 -134.272782)
		(width 0.127)
		(layer "In2.Cu")
		(net "COMP_FAST_THROTTLE_N")
	)
	(segment
		(start 83.6676 -111.170212)
		(end 83.6676 -109.509052)
		(width 0.127)
		(layer "In2.Cu")
		(net "COMP_FAST_THROTTLE_N")
	)
	(segment
		(start 77.293978 -127.337566)
		(end 73.600056 -123.643644)
		(width 0.127)
		(layer "In2.Cu")
		(net "COMP_FAST_THROTTLE_N")
	)
	(segment
		(start 85.661246 -107.515406)
		(end 85.661246 -102.5398)
		(width 0.127)
		(layer "In2.Cu")
		(net "COMP_FAST_THROTTLE_N")
	)
	(segment
		(start 79.8195 -150.39086)
		(end 78.5749 -149.14626)
		(width 0.127)
		(layer "In2.Cu")
		(net "COMP_FAST_THROTTLE_N")
	)
	(segment
		(start 82.583528 -68.6816)
		(end 82.583528 -46.1772)
		(width 0.127)
		(layer "In2.Cu")
		(net "COMP_FAST_THROTTLE_N")
	)
	(segment
		(start 73.600056 -123.643644)
		(end 73.600056 -117.409976)
		(width 0.127)
		(layer "In2.Cu")
		(net "COMP_FAST_THROTTLE_N")
	)
	(segment
		(start 84.5947 -36.995608)
		(end 78.829662 -31.23057)
		(width 0.127)
		(layer "In2.Cu")
		(net "COMP_FAST_THROTTLE_N")
	)
	(segment
		(start 77.77099 -134.137654)
		(end 77.77099 -131.4958)
		(width 0.127)
		(layer "In2.Cu")
		(net "COMP_FAST_THROTTLE_N")
	)
	(segment
		(start 78.169008 -138.19505)
		(end 77.635862 -137.661904)
		(width 0.127)
		(layer "In2.Cu")
		(net "COMP_FAST_THROTTLE_N")
	)
	(segment
		(start 85.661246 -102.5398)
		(end 82.862928 -99.741482)
		(width 0.127)
		(layer "In2.Cu")
		(net "COMP_FAST_THROTTLE_N")
	)
	(segment
		(start 82.646012 -112.1918)
		(end 83.6676 -111.170212)
		(width 0.127)
		(layer "In2.Cu")
		(net "COMP_FAST_THROTTLE_N")
	)
	(segment
		(start 83.6676 -109.509052)
		(end 85.661246 -107.515406)
		(width 0.127)
		(layer "In2.Cu")
		(net "COMP_FAST_THROTTLE_N")
	)
	(segment
		(start 78.829662 -31.23057)
		(end 78.829662 -15.788386)
		(width 0.127)
		(layer "In2.Cu")
		(net "COMP_FAST_THROTTLE_N")
	)
	(segment
		(start 56.857646 -163.530788)
		(end 55.463948 -163.530788)
		(width 0.127)
		(layer "In5.Cu")
		(net "COMP_FAST_THROTTLE_N")
	)
	(segment
		(start 82.6262 -164.9222)
		(end 82.447384 -165.101016)
		(width 0.127)
		(layer "In5.Cu")
		(net "COMP_FAST_THROTTLE_N")
	)
	(segment
		(start 50.477674 -160.311084)
		(end 50.110644 -160.678114)
		(width 0.127)
		(layer "In5.Cu")
		(net "COMP_FAST_THROTTLE_N")
	)
	(segment
		(start 60.10275 -165.36035)
		(end 58.7502 -164.0078)
		(width 0.127)
		(layer "In5.Cu")
		(net "COMP_FAST_THROTTLE_N")
	)
	(segment
		(start 72.517762 -166.168578)
		(end 64.29375 -166.168578)
		(width 0.127)
		(layer "In5.Cu")
		(net "COMP_FAST_THROTTLE_N")
	)
	(segment
		(start 57.334912 -164.0078)
		(end 57.261252 -163.93414)
		(width 0.127)
		(layer "In5.Cu")
		(net "COMP_FAST_THROTTLE_N")
	)
	(segment
		(start 55.463948 -163.530788)
		(end 52.244244 -160.311084)
		(width 0.127)
		(layer "In5.Cu")
		(net "COMP_FAST_THROTTLE_N")
	)
	(segment
		(start 32.943292 -153.4922)
		(end 32.359854 -154.075638)
		(width 0.127)
		(layer "In5.Cu")
		(net "COMP_FAST_THROTTLE_N")
	)
	(segment
		(start 84.6709 -9.0297)
		(end 78.829662 -14.870938)
		(width 0.127)
		(layer "In5.Cu")
		(net "COMP_FAST_THROTTLE_N")
	)
	(segment
		(start 49.376838 -160.678114)
		(end 48.48352 -159.784796)
		(width 0.127)
		(layer "In5.Cu")
		(net "COMP_FAST_THROTTLE_N")
	)
	(segment
		(start 52.244244 -160.311084)
		(end 50.477674 -160.311084)
		(width 0.127)
		(layer "In5.Cu")
		(net "COMP_FAST_THROTTLE_N")
	)
	(segment
		(start 82.447384 -165.101016)
		(end 73.585324 -165.101016)
		(width 0.127)
		(layer "In5.Cu")
		(net "COMP_FAST_THROTTLE_N")
	)
	(segment
		(start 57.260998 -163.93414)
		(end 56.857646 -163.530788)
		(width 0.127)
		(layer "In5.Cu")
		(net "COMP_FAST_THROTTLE_N")
	)
	(segment
		(start 64.29375 -166.168578)
		(end 63.485522 -165.36035)
		(width 0.127)
		(layer "In5.Cu")
		(net "COMP_FAST_THROTTLE_N")
	)
	(segment
		(start 111.4044 -16.3576)
		(end 110.2614 -15.2146)
		(width 0.127)
		(layer "In5.Cu")
		(net "COMP_FAST_THROTTLE_N")
	)
	(segment
		(start 111.4044 -23.122382)
		(end 111.4044 -16.3576)
		(width 0.127)
		(layer "In5.Cu")
		(net "COMP_FAST_THROTTLE_N")
	)
	(segment
		(start 37.90696 -157.983936)
		(end 33.415224 -153.4922)
		(width 0.127)
		(layer "In5.Cu")
		(net "COMP_FAST_THROTTLE_N")
	)
	(segment
		(start 48.48352 -159.35452)
		(end 47.112936 -157.983936)
		(width 0.127)
		(layer "In5.Cu")
		(net "COMP_FAST_THROTTLE_N")
	)
	(segment
		(start 94.1959 -9.0297)
		(end 84.6709 -9.0297)
		(width 0.127)
		(layer "In5.Cu")
		(net "COMP_FAST_THROTTLE_N")
	)
	(segment
		(start 78.829662 -14.870938)
		(end 78.829662 -15.788386)
		(width 0.127)
		(layer "In5.Cu")
		(net "COMP_FAST_THROTTLE_N")
	)
	(segment
		(start 73.585324 -165.101016)
		(end 72.517762 -166.168578)
		(width 0.127)
		(layer "In5.Cu")
		(net "COMP_FAST_THROTTLE_N")
	)
	(segment
		(start 48.48352 -159.784796)
		(end 48.48352 -159.35452)
		(width 0.127)
		(layer "In5.Cu")
		(net "COMP_FAST_THROTTLE_N")
	)
	(segment
		(start 100.3808 -15.2146)
		(end 94.1959 -9.0297)
		(width 0.127)
		(layer "In5.Cu")
		(net "COMP_FAST_THROTTLE_N")
	)
	(segment
		(start 58.7502 -164.0078)
		(end 57.334912 -164.0078)
		(width 0.127)
		(layer "In5.Cu")
		(net "COMP_FAST_THROTTLE_N")
	)
	(segment
		(start 32.359854 -154.075638)
		(end 32.359854 -154.16022)
		(width 0.127)
		(layer "In5.Cu")
		(net "COMP_FAST_THROTTLE_N")
	)
	(segment
		(start 57.261252 -163.93414)
		(end 57.260998 -163.93414)
		(width 0.127)
		(layer "In5.Cu")
		(net "COMP_FAST_THROTTLE_N")
	)
	(segment
		(start 50.110644 -160.678114)
		(end 49.376838 -160.678114)
		(width 0.127)
		(layer "In5.Cu")
		(net "COMP_FAST_THROTTLE_N")
	)
	(segment
		(start 63.485522 -165.36035)
		(end 60.10275 -165.36035)
		(width 0.127)
		(layer "In5.Cu")
		(net "COMP_FAST_THROTTLE_N")
	)
	(segment
		(start 110.2614 -15.2146)
		(end 100.3808 -15.2146)
		(width 0.127)
		(layer "In5.Cu")
		(net "COMP_FAST_THROTTLE_N")
	)
	(segment
		(start 47.112936 -157.983936)
		(end 37.90696 -157.983936)
		(width 0.127)
		(layer "In5.Cu")
		(net "COMP_FAST_THROTTLE_N")
	)
	(segment
		(start 33.415224 -153.4922)
		(end 32.943292 -153.4922)
		(width 0.127)
		(layer "In5.Cu")
		(net "COMP_FAST_THROTTLE_N")
	)
	(segment
		(start 82.6262 -164.7698)
		(end 82.6262 -164.9222)
		(width 0.127)
		(layer "In5.Cu")
		(net "COMP_FAST_THROTTLE_N")
	)
	(segment
		(start 69.9262 -169.862246)
		(end 70.343776 -170.279822)
		(width 0.127)
		(layer "F.Cu")
		(net "BMC_SELF_HW_RST")
	)
	(segment
		(start 71.9328 -169.7482)
		(end 71.4502 -170.2308)
		(width 0.127)
		(layer "F.Cu")
		(net "BMC_SELF_HW_RST")
	)
	(segment
		(start 70.343776 -170.279822)
		(end 71.401178 -170.279822)
		(width 0.127)
		(layer "F.Cu")
		(net "BMC_SELF_HW_RST")
	)
	(segment
		(start 71.401178 -170.279822)
		(end 71.4502 -170.2308)
		(width 0.127)
		(layer "F.Cu")
		(net "BMC_SELF_HW_RST")
	)
	(segment
		(start 44.099988 -136.191498)
		(end 44.099988 -136.59993)
		(width 0.127)
		(layer "F.Cu")
		(net "BMC_SELF_HW_RST")
	)
	(segment
		(start 71.9328 -168.5544)
		(end 71.9328 -169.7482)
		(width 0.127)
		(layer "F.Cu")
		(net "BMC_SELF_HW_RST")
	)
	(segment
		(start 43.05173 -135.14324)
		(end 44.099988 -136.191498)
		(width 0.127)
		(layer "F.Cu")
		(net "BMC_SELF_HW_RST")
	)
	(segment
		(start 42.77106 -135.14324)
		(end 43.05173 -135.14324)
		(width 0.127)
		(layer "F.Cu")
		(net "BMC_SELF_HW_RST")
	)
	(via
		(at 69.9262 -169.862246)
		(size 0.508)
		(drill 0.254)
		(layers "F.Cu" "B.Cu")
		(net "BMC_SELF_HW_RST")
	)
	(via
		(at 66.3448 -133.4516)
		(size 0.508)
		(drill 0.254)
		(layers "F.Cu" "B.Cu")
		(net "BMC_SELF_HW_RST")
	)
	(via
		(at 71.4502 -170.2308)
		(size 0.6604)
		(drill 0.3302)
		(layers "F.Cu" "B.Cu")
		(net "BMC_SELF_HW_RST")
	)
	(via
		(at 42.77106 -135.14324)
		(size 0.508)
		(drill 0.254)
		(layers "F.Cu" "B.Cu")
		(net "BMC_SELF_HW_RST")
	)
	(segment
		(start 65.9003 -136.694418)
		(end 65.9003 -135.287766)
		(width 0.127)
		(layer "In2.Cu")
		(net "BMC_SELF_HW_RST")
	)
	(segment
		(start 66.2178 -134.970266)
		(end 66.2178 -133.5786)
		(width 0.127)
		(layer "In2.Cu")
		(net "BMC_SELF_HW_RST")
	)
	(segment
		(start 66.5226 -164.8333)
		(end 66.5226 -152.051766)
		(width 0.127)
		(layer "In2.Cu")
		(net "BMC_SELF_HW_RST")
	)
	(segment
		(start 70.1802 -168.4909)
		(end 66.5226 -164.8333)
		(width 0.127)
		(layer "In2.Cu")
		(net "BMC_SELF_HW_RST")
	)
	(segment
		(start 66.8147 -145.021046)
		(end 66.8147 -141.648688)
		(width 0.127)
		(layer "In2.Cu")
		(net "BMC_SELF_HW_RST")
	)
	(segment
		(start 67.5894 -145.796)
		(end 67.1576 -145.3642)
		(width 0.127)
		(layer "In2.Cu")
		(net "BMC_SELF_HW_RST")
	)
	(segment
		(start 66.386964 -141.220952)
		(end 66.386964 -140.891006)
		(width 0.127)
		(layer "In2.Cu")
		(net "BMC_SELF_HW_RST")
	)
	(segment
		(start 66.2178 -133.5786)
		(end 66.3448 -133.4516)
		(width 0.127)
		(layer "In2.Cu")
		(net "BMC_SELF_HW_RST")
	)
	(segment
		(start 65.758314 -136.836404)
		(end 65.9003 -136.694418)
		(width 0.127)
		(layer "In2.Cu")
		(net "BMC_SELF_HW_RST")
	)
	(segment
		(start 67.5894 -150.984966)
		(end 67.5894 -145.796)
		(width 0.127)
		(layer "In2.Cu")
		(net "BMC_SELF_HW_RST")
	)
	(segment
		(start 66.386964 -140.891006)
		(end 65.758314 -140.262356)
		(width 0.127)
		(layer "In2.Cu")
		(net "BMC_SELF_HW_RST")
	)
	(segment
		(start 65.9003 -135.287766)
		(end 66.2178 -134.970266)
		(width 0.127)
		(layer "In2.Cu")
		(net "BMC_SELF_HW_RST")
	)
	(segment
		(start 67.1576 -145.3642)
		(end 66.8147 -145.021046)
		(width 0.127)
		(layer "In2.Cu")
		(net "BMC_SELF_HW_RST")
	)
	(segment
		(start 65.758314 -140.262356)
		(end 65.758314 -136.836404)
		(width 0.127)
		(layer "In2.Cu")
		(net "BMC_SELF_HW_RST")
	)
	(segment
		(start 69.9262 -169.862246)
		(end 70.1802 -169.608246)
		(width 0.127)
		(layer "In2.Cu")
		(net "BMC_SELF_HW_RST")
	)
	(segment
		(start 70.1802 -169.608246)
		(end 70.1802 -168.4909)
		(width 0.127)
		(layer "In2.Cu")
		(net "BMC_SELF_HW_RST")
	)
	(segment
		(start 66.8147 -141.648688)
		(end 66.386964 -141.220952)
		(width 0.127)
		(layer "In2.Cu")
		(net "BMC_SELF_HW_RST")
	)
	(segment
		(start 66.5226 -152.051766)
		(end 67.5894 -150.984966)
		(width 0.127)
		(layer "In2.Cu")
		(net "BMC_SELF_HW_RST")
	)
	(segment
		(start 61.84646 -134.5184)
		(end 61.38418 -134.05612)
		(width 0.127)
		(layer "In5.Cu")
		(net "BMC_SELF_HW_RST")
	)
	(segment
		(start 57.01538 -135.3439)
		(end 44.74972 -135.3439)
		(width 0.127)
		(layer "In5.Cu")
		(net "BMC_SELF_HW_RST")
	)
	(segment
		(start 57.806844 -135.433816)
		(end 57.105296 -135.433816)
		(width 0.127)
		(layer "In5.Cu")
		(net "BMC_SELF_HW_RST")
	)
	(segment
		(start 44.74972 -135.3439)
		(end 44.54906 -135.14324)
		(width 0.127)
		(layer "In5.Cu")
		(net "BMC_SELF_HW_RST")
	)
	(segment
		(start 61.38418 -134.05612)
		(end 59.18454 -134.05612)
		(width 0.127)
		(layer "In5.Cu")
		(net "BMC_SELF_HW_RST")
	)
	(segment
		(start 66.3448 -133.4516)
		(end 66.0146 -133.4516)
		(width 0.127)
		(layer "In5.Cu")
		(net "BMC_SELF_HW_RST")
	)
	(segment
		(start 66.0146 -133.4516)
		(end 64.9478 -134.5184)
		(width 0.127)
		(layer "In5.Cu")
		(net "BMC_SELF_HW_RST")
	)
	(segment
		(start 44.54906 -135.14324)
		(end 42.77106 -135.14324)
		(width 0.127)
		(layer "In5.Cu")
		(net "BMC_SELF_HW_RST")
	)
	(segment
		(start 57.105296 -135.433816)
		(end 57.01538 -135.3439)
		(width 0.127)
		(layer "In5.Cu")
		(net "BMC_SELF_HW_RST")
	)
	(segment
		(start 64.9478 -134.5184)
		(end 61.84646 -134.5184)
		(width 0.127)
		(layer "In5.Cu")
		(net "BMC_SELF_HW_RST")
	)
	(segment
		(start 59.18454 -134.05612)
		(end 57.806844 -135.433816)
		(width 0.127)
		(layer "In5.Cu")
		(net "BMC_SELF_HW_RST")
	)
	(segment
		(start 46.56328 -122.313192)
		(end 46.552358 -122.324114)
		(width 0.127)
		(layer "F.Cu")
		(net "BMC_CPU_EN")
	)
	(segment
		(start 46.552358 -122.324114)
		(end 46.552358 -123.349512)
		(width 0.127)
		(layer "F.Cu")
		(net "BMC_CPU_EN")
	)
	(segment
		(start 45.44568 -122.313192)
		(end 45.44568 -123.349512)
		(width 0.127)
		(layer "F.Cu")
		(net "BMC_CPU_DIS")
	)
	(segment
		(start 91.869006 -144.929606)
		(end 90.357706 -144.929606)
		(width 0.127)
		(layer "F.Cu")
		(net "TCA9555_A2")
	)
	(segment
		(start 91.9226 -144.9832)
		(end 91.869006 -144.929606)
		(width 0.127)
		(layer "F.Cu")
		(net "TCA9555_A2")
	)
	(via
		(at 90.9574 -145.3388)
		(size 0.6096)
		(drill 0.3048)
		(layers "F.Cu" "B.Cu")
		(net "TCA9555_A2")
	)
	(via
		(at 91.9226 -144.9832)
		(size 0.508)
		(drill 0.254)
		(layers "F.Cu" "B.Cu")
		(net "TCA9555_A2")
	)
	(segment
		(start 91.0844 -144.8562)
		(end 90.9574 -144.9832)
		(width 0.127)
		(layer "B.Cu")
		(net "TCA9555_A2")
	)
	(segment
		(start 91.7956 -144.8562)
		(end 91.0844 -144.8562)
		(width 0.127)
		(layer "B.Cu")
		(net "TCA9555_A2")
	)
	(segment
		(start 90.9574 -144.9832)
		(end 90.9574 -145.3388)
		(width 0.127)
		(layer "B.Cu")
		(net "TCA9555_A2")
	)
	(segment
		(start 92.8116 -145.4531)
		(end 91.0717 -145.4531)
		(width 0.127)
		(layer "B.Cu")
		(net "TCA9555_A2")
	)
	(segment
		(start 92.8116 -145.4531)
		(end 93.853 -145.4531)
		(width 0.127)
		(layer "B.Cu")
		(net "TCA9555_A2")
	)
	(segment
		(start 91.9226 -144.9832)
		(end 91.7956 -144.8562)
		(width 0.127)
		(layer "B.Cu")
		(net "TCA9555_A2")
	)
	(segment
		(start 91.0717 -145.4531)
		(end 90.9574 -145.3388)
		(width 0.127)
		(layer "B.Cu")
		(net "TCA9555_A2")
	)
	(segment
		(start 87.386414 -144.822926)
		(end 89.107264 -144.822926)
		(width 0.127)
		(layer "F.Cu")
		(net "TCA9555_A1")
	)
	(segment
		(start 89.107264 -144.822926)
		(end 89.405206 -145.120868)
		(width 0.127)
		(layer "F.Cu")
		(net "TCA9555_A1")
	)
	(segment
		(start 89.405206 -145.1864)
		(end 89.798652 -145.579846)
		(width 0.127)
		(layer "F.Cu")
		(net "TCA9555_A1")
	)
	(segment
		(start 86.97976 -145.22958)
		(end 87.386414 -144.822926)
		(width 0.127)
		(layer "F.Cu")
		(net "TCA9555_A1")
	)
	(segment
		(start 89.798652 -145.579846)
		(end 90.357706 -145.579846)
		(width 0.127)
		(layer "F.Cu")
		(net "TCA9555_A1")
	)
	(segment
		(start 89.405206 -145.120868)
		(end 89.405206 -145.1864)
		(width 0.127)
		(layer "F.Cu")
		(net "TCA9555_A1")
	)
	(via
		(at 87.392764 -147.2438)
		(size 0.6096)
		(drill 0.3048)
		(layers "F.Cu" "B.Cu")
		(net "TCA9555_A1")
	)
	(via
		(at 86.97976 -145.22958)
		(size 0.508)
		(drill 0.254)
		(layers "F.Cu" "B.Cu")
		(net "TCA9555_A1")
	)
	(segment
		(start 87.393018 -146.263614)
		(end 87.25408 -146.124676)
		(width 0.127)
		(layer "B.Cu")
		(net "TCA9555_A1")
	)
	(segment
		(start 87.392764 -147.988528)
		(end 87.392764 -147.2438)
		(width 0.127)
		(layer "B.Cu")
		(net "TCA9555_A1")
	)
	(segment
		(start 87.25408 -145.5039)
		(end 86.97976 -145.22958)
		(width 0.127)
		(layer "B.Cu")
		(net "TCA9555_A1")
	)
	(segment
		(start 87.691976 -148.28774)
		(end 87.392764 -147.988528)
		(width 0.127)
		(layer "B.Cu")
		(net "TCA9555_A1")
	)
	(segment
		(start 87.25408 -146.124676)
		(end 87.25408 -145.5039)
		(width 0.127)
		(layer "B.Cu")
		(net "TCA9555_A1")
	)
	(segment
		(start 87.392764 -146.263868)
		(end 87.393018 -146.263614)
		(width 0.127)
		(layer "B.Cu")
		(net "TCA9555_A1")
	)
	(segment
		(start 87.392764 -147.2438)
		(end 87.392764 -146.263868)
		(width 0.127)
		(layer "B.Cu")
		(net "TCA9555_A1")
	)
	(segment
		(start 95.996506 -144.279366)
		(end 97.513648 -144.279366)
		(width 0.127)
		(layer "F.Cu")
		(net "TCA9555_A0")
	)
	(segment
		(start 97.633282 -144.399)
		(end 98.1075 -144.399)
		(width 0.127)
		(layer "F.Cu")
		(net "TCA9555_A0")
	)
	(segment
		(start 98.1075 -144.399)
		(end 98.1075 -143.401542)
		(width 0.127)
		(layer "F.Cu")
		(net "TCA9555_A0")
	)
	(segment
		(start 97.513648 -144.279366)
		(end 97.633282 -144.399)
		(width 0.127)
		(layer "F.Cu")
		(net "TCA9555_A0")
	)
	(segment
		(start 98.25609 -143.252952)
		(end 98.341942 -143.1671)
		(width 0.127)
		(layer "F.Cu")
		(net "TCA9555_A0")
	)
	(segment
		(start 98.341942 -143.1671)
		(end 99.453446 -143.1671)
		(width 0.127)
		(layer "F.Cu")
		(net "TCA9555_A0")
	)
	(segment
		(start 98.1075 -143.401542)
		(end 98.25609 -143.252952)
		(width 0.127)
		(layer "F.Cu")
		(net "TCA9555_A0")
	)
	(via
		(at 98.25609 -143.252952)
		(size 0.6604)
		(drill 0.3302)
		(layers "F.Cu" "B.Cu")
		(net "TCA9555_A0")
	)
	(segment
		(start 167.4368 -139.4968)
		(end 166.497 -139.4968)
		(width 0.508)
		(layer "F.Cu")
		(net "P12V_STBY")
	)
	(segment
		(start 91.410028 -51.678332)
		(end 91.410028 -51.503834)
		(width 0.508)
		(layer "F.Cu")
		(net "P12V_STBY")
	)
	(segment
		(start 183.632602 -152.254966)
		(end 183.735726 -152.35809)
		(width 0.508)
		(layer "F.Cu")
		(net "P12V_STBY")
	)
	(segment
		(start 166.497 -139.4968)
		(end 165.4556 -138.4554)
		(width 0.508)
		(layer "F.Cu")
		(net "P12V_STBY")
	)
	(segment
		(start 183.064404 -152.254966)
		(end 183.632602 -152.254966)
		(width 0.508)
		(layer "F.Cu")
		(net "P12V_STBY")
	)
	(segment
		(start 91.410028 -51.503834)
		(end 92.070936 -50.842926)
		(width 0.508)
		(layer "F.Cu")
		(net "P12V_STBY")
	)
	(segment
		(start 40.210486 -176.69891)
		(end 39.585646 -176.69891)
		(width 0.508)
		(layer "F.Cu")
		(net "P12V_STBY")
	)
	(segment
		(start 182.785004 -151.975566)
		(end 183.064404 -152.254966)
		(width 0.508)
		(layer "F.Cu")
		(net "P12V_STBY")
	)
	(segment
		(start 170.4594 -119.553736)
		(end 169.218864 -119.553736)
		(width 0.508)
		(layer "F.Cu")
		(net "P12V_STBY")
	)
	(segment
		(start 40.517826 -176.39157)
		(end 40.210486 -176.69891)
		(width 0.508)
		(layer "F.Cu")
		(net "P12V_STBY")
	)
	(via
		(at 177.4698 -107.4674)
		(size 0.7112)
		(drill 0.4064)
		(layers "F.Cu" "B.Cu")
		(net "P12V_STBY")
	)
	(via
		(at 75.255628 -48.062896)
		(size 0.7112)
		(drill 0.4064)
		(layers "F.Cu" "B.Cu")
		(net "P12V_STBY")
	)
	(via
		(at 131.275836 -11.100054)
		(size 0.7112)
		(drill 0.4064)
		(layers "F.Cu" "B.Cu")
		(net "P12V_STBY")
	)
	(via
		(at 169.218864 -119.553736)
		(size 0.508)
		(drill 0.254)
		(layers "F.Cu" "B.Cu")
		(net "P12V_STBY")
	)
	(via
		(at 166.849298 -142.24254)
		(size 0.7112)
		(drill 0.4064)
		(layers "F.Cu" "B.Cu")
		(net "P12V_STBY")
	)
	(via
		(at 40.517826 -176.39157)
		(size 0.508)
		(drill 0.254)
		(layers "F.Cu" "B.Cu")
		(net "P12V_STBY")
	)
	(via
		(at 177.4698 -106.0704)
		(size 0.7112)
		(drill 0.4064)
		(layers "F.Cu" "B.Cu")
		(net "P12V_STBY")
	)
	(via
		(at 183.735726 -152.35809)
		(size 0.508)
		(drill 0.254)
		(layers "F.Cu" "B.Cu")
		(net "P12V_STBY")
	)
	(via
		(at 176.463452 -133.08076)
		(size 0.7112)
		(drill 0.4064)
		(layers "F.Cu" "B.Cu")
		(net "P12V_STBY")
	)
	(via
		(at 76.474828 -46.843696)
		(size 0.7112)
		(drill 0.4064)
		(layers "F.Cu" "B.Cu")
		(net "P12V_STBY")
	)
	(via
		(at 76.474828 -48.062896)
		(size 0.7112)
		(drill 0.4064)
		(layers "F.Cu" "B.Cu")
		(net "P12V_STBY")
	)
	(via
		(at 180.3908 -106.0196)
		(size 0.7112)
		(drill 0.4064)
		(layers "F.Cu" "B.Cu")
		(net "P12V_STBY")
	)
	(via
		(at 175.133 -131.699)
		(size 0.7112)
		(drill 0.4064)
		(layers "F.Cu" "B.Cu")
		(net "P12V_STBY")
	)
	(via
		(at 131.275836 -8.661654)
		(size 0.7112)
		(drill 0.4064)
		(layers "F.Cu" "B.Cu")
		(net "P12V_STBY")
	)
	(via
		(at 54.42458 -176.55413)
		(size 0.508)
		(drill 0.254)
		(layers "F.Cu" "B.Cu")
		(net "P12V_STBY")
	)
	(via
		(at 179.5018 -105.1306)
		(size 0.7112)
		(drill 0.4064)
		(layers "F.Cu" "B.Cu")
		(net "P12V_STBY")
	)
	(via
		(at 177.4698 -108.7374)
		(size 0.7112)
		(drill 0.4064)
		(layers "F.Cu" "B.Cu")
		(net "P12V_STBY")
	)
	(via
		(at 178.718718 -109.586522)
		(size 0.6604)
		(drill 0.3302)
		(layers "F.Cu" "B.Cu")
		(net "P12V_STBY")
	)
	(via
		(at 176.45126 -131.834636)
		(size 0.7112)
		(drill 0.4064)
		(layers "F.Cu" "B.Cu")
		(net "P12V_STBY")
	)
	(via
		(at 168.148 -140.97)
		(size 0.7112)
		(drill 0.4064)
		(layers "F.Cu" "B.Cu")
		(net "P12V_STBY")
	)
	(via
		(at 132.495036 -9.880854)
		(size 0.7112)
		(drill 0.4064)
		(layers "F.Cu" "B.Cu")
		(net "P12V_STBY")
	)
	(via
		(at 132.495036 -11.100054)
		(size 0.7112)
		(drill 0.4064)
		(layers "F.Cu" "B.Cu")
		(net "P12V_STBY")
	)
	(via
		(at 133.714236 -11.100054)
		(size 0.7112)
		(drill 0.4064)
		(layers "F.Cu" "B.Cu")
		(net "P12V_STBY")
	)
	(via
		(at 54.763924 -164.034724)
		(size 0.508)
		(drill 0.254)
		(layers "F.Cu" "B.Cu")
		(net "P12V_STBY")
	)
	(via
		(at 21.12518 -182.753)
		(size 0.7112)
		(drill 0.4064)
		(layers "F.Cu" "B.Cu")
		(net "P12V_STBY")
	)
	(via
		(at 91.410028 -51.678332)
		(size 0.508)
		(drill 0.254)
		(layers "F.Cu" "B.Cu")
		(net "P12V_STBY")
	)
	(via
		(at 19.90598 -182.753)
		(size 0.7112)
		(drill 0.4064)
		(layers "F.Cu" "B.Cu")
		(net "P12V_STBY")
	)
	(via
		(at 22.271482 -177.526696)
		(size 0.508)
		(drill 0.254)
		(layers "F.Cu" "B.Cu")
		(net "P12V_STBY")
	)
	(via
		(at 132.495036 -8.661654)
		(size 0.7112)
		(drill 0.4064)
		(layers "F.Cu" "B.Cu")
		(net "P12V_STBY")
	)
	(via
		(at 166.878 -140.97)
		(size 0.7112)
		(drill 0.4064)
		(layers "F.Cu" "B.Cu")
		(net "P12V_STBY")
	)
	(via
		(at 19.90598 -183.9722)
		(size 0.7112)
		(drill 0.4064)
		(layers "F.Cu" "B.Cu")
		(net "P12V_STBY")
	)
	(via
		(at 175.133 -133.096)
		(size 0.7112)
		(drill 0.4064)
		(layers "F.Cu" "B.Cu")
		(net "P12V_STBY")
	)
	(via
		(at 180.3908 -107.4166)
		(size 0.7112)
		(drill 0.4064)
		(layers "F.Cu" "B.Cu")
		(net "P12V_STBY")
	)
	(via
		(at 177.0888 -134.4168)
		(size 0.508)
		(drill 0.254)
		(layers "F.Cu" "B.Cu")
		(net "P12V_STBY")
	)
	(via
		(at 131.275836 -9.880854)
		(size 0.7112)
		(drill 0.4064)
		(layers "F.Cu" "B.Cu")
		(net "P12V_STBY")
	)
	(via
		(at 168.119298 -142.24254)
		(size 0.7112)
		(drill 0.4064)
		(layers "F.Cu" "B.Cu")
		(net "P12V_STBY")
	)
	(via
		(at 75.255628 -46.843696)
		(size 0.7112)
		(drill 0.4064)
		(layers "F.Cu" "B.Cu")
		(net "P12V_STBY")
	)
	(via
		(at 180.3908 -108.6866)
		(size 0.7112)
		(drill 0.4064)
		(layers "F.Cu" "B.Cu")
		(net "P12V_STBY")
	)
	(via
		(at 21.12518 -183.9722)
		(size 0.7112)
		(drill 0.4064)
		(layers "F.Cu" "B.Cu")
		(net "P12V_STBY")
	)
	(segment
		(start 179.3621 -134.2644)
		(end 177.2412 -134.2644)
		(width 0.508)
		(layer "B.Cu")
		(net "P12V_STBY")
	)
	(segment
		(start 183.813704 -152.280112)
		(end 183.813704 -148.956014)
		(width 0.508)
		(layer "B.Cu")
		(net "P12V_STBY")
	)
	(segment
		(start 177.2412 -134.2644)
		(end 177.0888 -134.4168)
		(width 0.508)
		(layer "B.Cu")
		(net "P12V_STBY")
	)
	(segment
		(start 54.6481 -163.1188)
		(end 54.6481 -163.9189)
		(width 0.508)
		(layer "B.Cu")
		(net "P12V_STBY")
	)
	(segment
		(start 183.735726 -152.35809)
		(end 183.813704 -152.280112)
		(width 0.508)
		(layer "B.Cu")
		(net "P12V_STBY")
	)
	(segment
		(start 22.7076 -182.753)
		(end 24.5618 -180.8988)
		(width 0.508)
		(layer "B.Cu")
		(net "P12V_STBY")
	)
	(segment
		(start 185.16727 -147.602448)
		(end 185.16727 -140.06957)
		(width 0.508)
		(layer "B.Cu")
		(net "P12V_STBY")
	)
	(segment
		(start 54.6481 -163.9189)
		(end 54.763924 -164.034724)
		(width 0.508)
		(layer "B.Cu")
		(net "P12V_STBY")
	)
	(segment
		(start 177.0888 -137.6934)
		(end 177.0888 -134.4168)
		(width 0.762)
		(layer "B.Cu")
		(net "P12V_STBY")
	)
	(segment
		(start 183.813704 -148.956014)
		(end 185.16727 -147.602448)
		(width 0.508)
		(layer "B.Cu")
		(net "P12V_STBY")
	)
	(segment
		(start 21.12518 -182.753)
		(end 22.7076 -182.753)
		(width 0.508)
		(layer "B.Cu")
		(net "P12V_STBY")
	)
	(segment
		(start 185.16727 -140.06957)
		(end 179.3621 -134.2644)
		(width 0.508)
		(layer "B.Cu")
		(net "P12V_STBY")
	)
	(segment
		(start 54.1528 -175.372268)
		(end 54.4322 -175.651668)
		(width 0.508)
		(layer "In2.Cu")
		(net "P12V_STBY")
	)
	(segment
		(start 54.4322 -176.54651)
		(end 54.42458 -176.55413)
		(width 0.508)
		(layer "In2.Cu")
		(net "P12V_STBY")
	)
	(segment
		(start 54.1528 -164.86886)
		(end 54.1528 -175.372268)
		(width 0.508)
		(layer "In2.Cu")
		(net "P12V_STBY")
	)
	(segment
		(start 54.763924 -164.034724)
		(end 54.763924 -164.257736)
		(width 0.508)
		(layer "In2.Cu")
		(net "P12V_STBY")
	)
	(segment
		(start 54.4322 -175.651668)
		(end 54.4322 -176.54651)
		(width 0.508)
		(layer "In2.Cu")
		(net "P12V_STBY")
	)
	(segment
		(start 54.763924 -164.257736)
		(end 54.1528 -164.86886)
		(width 0.508)
		(layer "In2.Cu")
		(net "P12V_STBY")
	)
	(segment
		(start 39.524686 -177.38471)
		(end 40.517826 -176.39157)
		(width 0.508)
		(layer "In5.Cu")
		(net "P12V_STBY")
	)
	(segment
		(start 22.271482 -177.526696)
		(end 22.825964 -176.972214)
		(width 0.508)
		(layer "In5.Cu")
		(net "P12V_STBY")
	)
	(segment
		(start 37.381434 -177.38471)
		(end 39.524686 -177.38471)
		(width 0.508)
		(layer "In5.Cu")
		(net "P12V_STBY")
	)
	(segment
		(start 53.63083 -175.76038)
		(end 54.42458 -176.55413)
		(width 0.508)
		(layer "In5.Cu")
		(net "P12V_STBY")
	)
	(segment
		(start 22.825964 -176.972214)
		(end 36.968938 -176.972214)
		(width 0.508)
		(layer "In5.Cu")
		(net "P12V_STBY")
	)
	(segment
		(start 40.517826 -176.39157)
		(end 40.849296 -176.0601)
		(width 0.508)
		(layer "In5.Cu")
		(net "P12V_STBY")
	)
	(segment
		(start 36.968938 -176.972214)
		(end 37.381434 -177.38471)
		(width 0.508)
		(layer "In5.Cu")
		(net "P12V_STBY")
	)
	(segment
		(start 40.849296 -176.0601)
		(end 48.266858 -176.0601)
		(width 0.508)
		(layer "In5.Cu")
		(net "P12V_STBY")
	)
	(segment
		(start 48.566578 -175.76038)
		(end 53.63083 -175.76038)
		(width 0.508)
		(layer "In5.Cu")
		(net "P12V_STBY")
	)
	(segment
		(start 48.266858 -176.0601)
		(end 48.566578 -175.76038)
		(width 0.508)
		(layer "In5.Cu")
		(net "P12V_STBY")
	)
	(segment
		(start 91.8464 -117.7036)
		(end 91.8464 -119.1768)
		(width 0.127)
		(layer "F.Cu")
		(net "UART_IOM_TX")
	)
	(segment
		(start 93.9546 -116.5098)
		(end 93.853 -116.6114)
		(width 0.127)
		(layer "F.Cu")
		(net "UART_IOM_TX")
	)
	(segment
		(start 93.853 -116.6114)
		(end 92.9386 -116.6114)
		(width 0.127)
		(layer "F.Cu")
		(net "UART_IOM_TX")
	)
	(segment
		(start 89.3318 -124.93752)
		(end 90.8558 -126.46152)
		(width 0.127)
		(layer "F.Cu")
		(net "UART_IOM_TX")
	)
	(segment
		(start 90.25255 -20.432522)
		(end 94.232984 -20.432522)
		(width 0.127)
		(layer "F.Cu")
		(net "UART_IOM_TX")
	)
	(segment
		(start 89.799922 -19.979894)
		(end 90.25255 -20.432522)
		(width 0.127)
		(layer "F.Cu")
		(net "UART_IOM_TX")
	)
	(segment
		(start 91.098878 -119.4816)
		(end 89.3318 -121.248678)
		(width 0.127)
		(layer "F.Cu")
		(net "UART_IOM_TX")
	)
	(segment
		(start 94.18955 -19.587972)
		(end 93.290898 -19.587972)
		(width 0.127)
		(layer "F.Cu")
		(net "UART_IOM_TX")
	)
	(segment
		(start 89.3318 -121.248678)
		(end 89.3318 -124.93752)
		(width 0.127)
		(layer "F.Cu")
		(net "UART_IOM_TX")
	)
	(segment
		(start 90.8558 -126.46152)
		(end 90.8558 -126.746)
		(width 0.127)
		(layer "F.Cu")
		(net "UART_IOM_TX")
	)
	(segment
		(start 92.9386 -116.6114)
		(end 91.8464 -117.7036)
		(width 0.127)
		(layer "F.Cu")
		(net "UART_IOM_TX")
	)
	(segment
		(start 94.321376 -19.719798)
		(end 94.18955 -19.587972)
		(width 0.127)
		(layer "F.Cu")
		(net "UART_IOM_TX")
	)
	(segment
		(start 94.232984 -20.432522)
		(end 94.321376 -20.34413)
		(width 0.127)
		(layer "F.Cu")
		(net "UART_IOM_TX")
	)
	(segment
		(start 91.5416 -119.4816)
		(end 91.098878 -119.4816)
		(width 0.127)
		(layer "F.Cu")
		(net "UART_IOM_TX")
	)
	(segment
		(start 94.321376 -20.34413)
		(end 94.321376 -19.719798)
		(width 0.127)
		(layer "F.Cu")
		(net "UART_IOM_TX")
	)
	(segment
		(start 91.8464 -119.1768)
		(end 91.5416 -119.4816)
		(width 0.127)
		(layer "F.Cu")
		(net "UART_IOM_TX")
	)
	(via
		(at 90.8558 -126.746)
		(size 0.508)
		(drill 0.254)
		(layers "F.Cu" "B.Cu")
		(net "UART_IOM_TX")
	)
	(via
		(at 93.290898 -19.587972)
		(size 0.508)
		(drill 0.254)
		(layers "F.Cu" "B.Cu")
		(net "UART_IOM_TX")
	)
	(via
		(at 91.5416 -119.4816)
		(size 0.6604)
		(drill 0.3302)
		(layers "F.Cu" "B.Cu")
		(net "UART_IOM_TX")
	)
	(via
		(at 93.9546 -116.5098)
		(size 0.508)
		(drill 0.254)
		(layers "F.Cu" "B.Cu")
		(net "UART_IOM_TX")
	)
	(segment
		(start 91.53779 -129.1082)
		(end 91.698572 -128.947418)
		(width 0.127)
		(layer "B.Cu")
		(net "UART_IOM_TX")
	)
	(segment
		(start 91.53779 -131.16179)
		(end 91.53779 -129.1082)
		(width 0.127)
		(layer "B.Cu")
		(net "UART_IOM_TX")
	)
	(segment
		(start 91.78036 -131.40436)
		(end 91.53779 -131.16179)
		(width 0.127)
		(layer "B.Cu")
		(net "UART_IOM_TX")
	)
	(segment
		(start 92.1639 -131.40436)
		(end 91.78036 -131.40436)
		(width 0.127)
		(layer "B.Cu")
		(net "UART_IOM_TX")
	)
	(segment
		(start 91.698572 -128.947418)
		(end 91.698572 -127.588772)
		(width 0.127)
		(layer "B.Cu")
		(net "UART_IOM_TX")
	)
	(segment
		(start 91.698572 -127.588772)
		(end 90.8558 -126.746)
		(width 0.127)
		(layer "B.Cu")
		(net "UART_IOM_TX")
	)
	(segment
		(start 82.081878 -96.696022)
		(end 82.081878 -93.96349)
		(width 0.127)
		(layer "In5.Cu")
		(net "UART_IOM_TX")
	)
	(segment
		(start 82.2706 -93.774768)
		(end 82.2706 -89.712038)
		(width 0.127)
		(layer "In5.Cu")
		(net "UART_IOM_TX")
	)
	(segment
		(start 93.9546 -116.5098)
		(end 93.867478 -116.422678)
		(width 0.127)
		(layer "In5.Cu")
		(net "UART_IOM_TX")
	)
	(segment
		(start 92.905072 -24.515826)
		(end 92.905072 -19.973798)
		(width 0.127)
		(layer "In5.Cu")
		(net "UART_IOM_TX")
	)
	(segment
		(start 80.778858 -43.604942)
		(end 83.93684 -40.44696)
		(width 0.127)
		(layer "In5.Cu")
		(net "UART_IOM_TX")
	)
	(segment
		(start 82.2706 -74.587608)
		(end 82.2706 -69.17817)
		(width 0.127)
		(layer "In5.Cu")
		(net "UART_IOM_TX")
	)
	(segment
		(start 81.9658 -83.0326)
		(end 81.9658 -81.292446)
		(width 0.127)
		(layer "In5.Cu")
		(net "UART_IOM_TX")
	)
	(segment
		(start 92.185744 -25.235154)
		(end 92.905072 -24.515826)
		(width 0.127)
		(layer "In5.Cu")
		(net "UART_IOM_TX")
	)
	(segment
		(start 82.914236 -61.517784)
		(end 80.778858 -59.382406)
		(width 0.127)
		(layer "In5.Cu")
		(net "UART_IOM_TX")
	)
	(segment
		(start 83.93684 -40.44696)
		(end 83.93684 -28.779216)
		(width 0.127)
		(layer "In5.Cu")
		(net "UART_IOM_TX")
	)
	(segment
		(start 82.081624 -87.57666)
		(end 82.2452 -87.413084)
		(width 0.127)
		(layer "In5.Cu")
		(net "UART_IOM_TX")
	)
	(segment
		(start 93.867478 -116.422678)
		(end 93.867478 -108.812584)
		(width 0.127)
		(layer "In5.Cu")
		(net "UART_IOM_TX")
	)
	(segment
		(start 93.867478 -108.812584)
		(end 84.201 -99.146106)
		(width 0.127)
		(layer "In5.Cu")
		(net "UART_IOM_TX")
	)
	(segment
		(start 87.480902 -25.235154)
		(end 92.185744 -25.235154)
		(width 0.127)
		(layer "In5.Cu")
		(net "UART_IOM_TX")
	)
	(segment
		(start 82.081624 -74.776584)
		(end 82.2706 -74.587608)
		(width 0.127)
		(layer "In5.Cu")
		(net "UART_IOM_TX")
	)
	(segment
		(start 82.914236 -68.534534)
		(end 82.914236 -61.517784)
		(width 0.127)
		(layer "In5.Cu")
		(net "UART_IOM_TX")
	)
	(segment
		(start 82.2452 -83.312)
		(end 81.9658 -83.0326)
		(width 0.127)
		(layer "In5.Cu")
		(net "UART_IOM_TX")
	)
	(segment
		(start 82.2452 -81.013046)
		(end 82.2452 -77.13345)
		(width 0.127)
		(layer "In5.Cu")
		(net "UART_IOM_TX")
	)
	(segment
		(start 82.081624 -76.969874)
		(end 82.081624 -74.776584)
		(width 0.127)
		(layer "In5.Cu")
		(net "UART_IOM_TX")
	)
	(segment
		(start 82.2452 -87.413084)
		(end 82.2452 -83.312)
		(width 0.127)
		(layer "In5.Cu")
		(net "UART_IOM_TX")
	)
	(segment
		(start 82.2706 -89.712038)
		(end 82.081624 -89.523062)
		(width 0.127)
		(layer "In5.Cu")
		(net "UART_IOM_TX")
	)
	(segment
		(start 82.2452 -77.13345)
		(end 82.081624 -76.969874)
		(width 0.127)
		(layer "In5.Cu")
		(net "UART_IOM_TX")
	)
	(segment
		(start 82.2706 -69.17817)
		(end 82.914236 -68.534534)
		(width 0.127)
		(layer "In5.Cu")
		(net "UART_IOM_TX")
	)
	(segment
		(start 81.9658 -81.292446)
		(end 82.2452 -81.013046)
		(width 0.127)
		(layer "In5.Cu")
		(net "UART_IOM_TX")
	)
	(segment
		(start 82.081878 -93.96349)
		(end 82.2706 -93.774768)
		(width 0.127)
		(layer "In5.Cu")
		(net "UART_IOM_TX")
	)
	(segment
		(start 92.905072 -19.973798)
		(end 93.290898 -19.587972)
		(width 0.127)
		(layer "In5.Cu")
		(net "UART_IOM_TX")
	)
	(segment
		(start 82.081624 -89.523062)
		(end 82.081624 -87.57666)
		(width 0.127)
		(layer "In5.Cu")
		(net "UART_IOM_TX")
	)
	(segment
		(start 83.93684 -28.779216)
		(end 87.480902 -25.235154)
		(width 0.127)
		(layer "In5.Cu")
		(net "UART_IOM_TX")
	)
	(segment
		(start 84.201 -99.146106)
		(end 84.201 -98.815144)
		(width 0.127)
		(layer "In5.Cu")
		(net "UART_IOM_TX")
	)
	(segment
		(start 84.201 -98.815144)
		(end 82.081878 -96.696022)
		(width 0.127)
		(layer "In5.Cu")
		(net "UART_IOM_TX")
	)
	(segment
		(start 80.778858 -59.382406)
		(end 80.778858 -43.604942)
		(width 0.127)
		(layer "In5.Cu")
		(net "UART_IOM_TX")
	)
	(segment
		(start 89.799922 -21.97989)
		(end 89.872312 -21.97989)
		(width 0.127)
		(layer "F.Cu")
		(net "UART_IOM_RX")
	)
	(segment
		(start 89.5858 -126.5936)
		(end 88.6968 -125.7046)
		(width 0.127)
		(layer "F.Cu")
		(net "UART_IOM_RX")
	)
	(segment
		(start 94.234508 -21.425662)
		(end 94.321376 -21.51253)
		(width 0.127)
		(layer "F.Cu")
		(net "UART_IOM_RX")
	)
	(segment
		(start 94.321376 -22.007068)
		(end 93.790262 -22.538182)
		(width 0.127)
		(layer "F.Cu")
		(net "UART_IOM_RX")
	)
	(segment
		(start 90.2462 -127.254)
		(end 90.2462 -127.6858)
		(width 0.127)
		(layer "F.Cu")
		(net "UART_IOM_RX")
	)
	(segment
		(start 90.42654 -21.425662)
		(end 94.234508 -21.425662)
		(width 0.127)
		(layer "F.Cu")
		(net "UART_IOM_RX")
	)
	(segment
		(start 89.872312 -21.97989)
		(end 90.42654 -21.425662)
		(width 0.127)
		(layer "F.Cu")
		(net "UART_IOM_RX")
	)
	(segment
		(start 93.2815 -115.2779)
		(end 94.0435 -115.2779)
		(width 0.127)
		(layer "F.Cu")
		(net "UART_IOM_RX")
	)
	(segment
		(start 94.321376 -21.51253)
		(end 94.321376 -22.007068)
		(width 0.127)
		(layer "F.Cu")
		(net "UART_IOM_RX")
	)
	(segment
		(start 88.6968 -120.7008)
		(end 91.2114 -118.1862)
		(width 0.127)
		(layer "F.Cu")
		(net "UART_IOM_RX")
	)
	(segment
		(start 91.2114 -117.348)
		(end 93.2815 -115.2779)
		(width 0.127)
		(layer "F.Cu")
		(net "UART_IOM_RX")
	)
	(segment
		(start 91.2114 -118.1862)
		(end 91.2114 -117.348)
		(width 0.127)
		(layer "F.Cu")
		(net "UART_IOM_RX")
	)
	(segment
		(start 94.0435 -115.2779)
		(end 94.488 -114.8334)
		(width 0.127)
		(layer "F.Cu")
		(net "UART_IOM_RX")
	)
	(segment
		(start 89.5858 -126.5936)
		(end 90.2462 -127.254)
		(width 0.127)
		(layer "F.Cu")
		(net "UART_IOM_RX")
	)
	(segment
		(start 88.6968 -125.7046)
		(end 88.6968 -120.7008)
		(width 0.127)
		(layer "F.Cu")
		(net "UART_IOM_RX")
	)
	(via
		(at 93.790262 -22.538182)
		(size 0.508)
		(drill 0.254)
		(layers "F.Cu" "B.Cu")
		(net "UART_IOM_RX")
	)
	(via
		(at 90.2462 -127.6858)
		(size 0.508)
		(drill 0.254)
		(layers "F.Cu" "B.Cu")
		(net "UART_IOM_RX")
	)
	(via
		(at 94.488 -114.8334)
		(size 0.508)
		(drill 0.254)
		(layers "F.Cu" "B.Cu")
		(net "UART_IOM_RX")
	)
	(via
		(at 89.5858 -126.5936)
		(size 0.6604)
		(drill 0.3302)
		(layers "F.Cu" "B.Cu")
		(net "UART_IOM_RX")
	)
	(segment
		(start 91.304364 -135.21436)
		(end 91.13266 -135.386064)
		(width 0.127)
		(layer "B.Cu")
		(net "UART_IOM_RX")
	)
	(segment
		(start 91.13266 -135.386064)
		(end 90.404696 -135.386064)
		(width 0.127)
		(layer "B.Cu")
		(net "UART_IOM_RX")
	)
	(segment
		(start 87.272368 -133.798564)
		(end 88.39073 -132.680202)
		(width 0.127)
		(layer "B.Cu")
		(net "UART_IOM_RX")
	)
	(segment
		(start 89.633552 -128.298448)
		(end 90.2462 -127.6858)
		(width 0.127)
		(layer "B.Cu")
		(net "UART_IOM_RX")
	)
	(segment
		(start 92.67698 -135.21436)
		(end 91.304364 -135.21436)
		(width 0.127)
		(layer "B.Cu")
		(net "UART_IOM_RX")
	)
	(segment
		(start 88.39073 -131.652518)
		(end 89.633552 -130.409696)
		(width 0.127)
		(layer "B.Cu")
		(net "UART_IOM_RX")
	)
	(segment
		(start 88.66251 -135.8519)
		(end 87.272368 -134.461758)
		(width 0.127)
		(layer "B.Cu")
		(net "UART_IOM_RX")
	)
	(segment
		(start 88.39073 -132.680202)
		(end 88.39073 -131.652518)
		(width 0.127)
		(layer "B.Cu")
		(net "UART_IOM_RX")
	)
	(segment
		(start 89.93886 -135.8519)
		(end 88.66251 -135.8519)
		(width 0.127)
		(layer "B.Cu")
		(net "UART_IOM_RX")
	)
	(segment
		(start 89.633552 -130.409696)
		(end 89.633552 -128.298448)
		(width 0.127)
		(layer "B.Cu")
		(net "UART_IOM_RX")
	)
	(segment
		(start 92.69222 -135.2296)
		(end 92.67698 -135.21436)
		(width 0.127)
		(layer "B.Cu")
		(net "UART_IOM_RX")
	)
	(segment
		(start 87.272368 -134.461758)
		(end 87.272368 -133.798564)
		(width 0.127)
		(layer "B.Cu")
		(net "UART_IOM_RX")
	)
	(segment
		(start 90.404696 -135.386064)
		(end 89.93886 -135.8519)
		(width 0.127)
		(layer "B.Cu")
		(net "UART_IOM_RX")
	)
	(segment
		(start 82.716624 -89.259664)
		(end 82.9056 -89.44864)
		(width 0.127)
		(layer "In5.Cu")
		(net "UART_IOM_RX")
	)
	(segment
		(start 93.790262 -22.538182)
		(end 94.395036 -23.142956)
		(width 0.127)
		(layer "In5.Cu")
		(net "UART_IOM_RX")
	)
	(segment
		(start 82.8802 -96.5962)
		(end 84.5566 -98.2726)
		(width 0.127)
		(layer "In5.Cu")
		(net "UART_IOM_RX")
	)
	(segment
		(start 82.716878 -94.226634)
		(end 82.716878 -95.64751)
		(width 0.127)
		(layer "In5.Cu")
		(net "UART_IOM_RX")
	)
	(segment
		(start 86.088728 -99.169728)
		(end 86.088728 -100.13569)
		(width 0.127)
		(layer "In5.Cu")
		(net "UART_IOM_RX")
	)
	(segment
		(start 82.8802 -87.676228)
		(end 82.716624 -87.839804)
		(width 0.127)
		(layer "In5.Cu")
		(net "UART_IOM_RX")
	)
	(segment
		(start 82.716624 -75.039728)
		(end 82.716624 -76.70673)
		(width 0.127)
		(layer "In5.Cu")
		(net "UART_IOM_RX")
	)
	(segment
		(start 94.4626 -108.5342)
		(end 94.5388 -108.6104)
		(width 0.127)
		(layer "In5.Cu")
		(net "UART_IOM_RX")
	)
	(segment
		(start 83.549236 -61.25464)
		(end 83.549236 -68.797678)
		(width 0.127)
		(layer "In5.Cu")
		(net "UART_IOM_RX")
	)
	(segment
		(start 82.716624 -82.859626)
		(end 82.8802 -83.023202)
		(width 0.127)
		(layer "In5.Cu")
		(net "UART_IOM_RX")
	)
	(segment
		(start 84.57184 -29.04236)
		(end 84.57184 -40.821356)
		(width 0.127)
		(layer "In5.Cu")
		(net "UART_IOM_RX")
	)
	(segment
		(start 82.716878 -95.64751)
		(end 82.8802 -95.810832)
		(width 0.127)
		(layer "In5.Cu")
		(net "UART_IOM_RX")
	)
	(segment
		(start 94.395036 -23.142956)
		(end 94.395036 -24.166322)
		(width 0.127)
		(layer "In5.Cu")
		(net "UART_IOM_RX")
	)
	(segment
		(start 82.9056 -94.037912)
		(end 82.716878 -94.226634)
		(width 0.127)
		(layer "In5.Cu")
		(net "UART_IOM_RX")
	)
	(segment
		(start 84.5566 -98.2726)
		(end 85.1916 -98.2726)
		(width 0.127)
		(layer "In5.Cu")
		(net "UART_IOM_RX")
	)
	(segment
		(start 94.4626 -108.509562)
		(end 94.4626 -108.5342)
		(width 0.127)
		(layer "In5.Cu")
		(net "UART_IOM_RX")
	)
	(segment
		(start 87.744046 -25.870154)
		(end 84.57184 -29.04236)
		(width 0.127)
		(layer "In5.Cu")
		(net "UART_IOM_RX")
	)
	(segment
		(start 85.1916 -98.2726)
		(end 86.088728 -99.169728)
		(width 0.127)
		(layer "In5.Cu")
		(net "UART_IOM_RX")
	)
	(segment
		(start 84.57184 -40.821356)
		(end 82.857594 -42.535602)
		(width 0.127)
		(layer "In5.Cu")
		(net "UART_IOM_RX")
	)
	(segment
		(start 82.908648 -69.438266)
		(end 82.908648 -74.847704)
		(width 0.127)
		(layer "In5.Cu")
		(net "UART_IOM_RX")
	)
	(segment
		(start 86.088728 -100.13569)
		(end 94.4626 -108.509562)
		(width 0.127)
		(layer "In5.Cu")
		(net "UART_IOM_RX")
	)
	(segment
		(start 82.908648 -74.847704)
		(end 82.716624 -75.039728)
		(width 0.127)
		(layer "In5.Cu")
		(net "UART_IOM_RX")
	)
	(segment
		(start 94.395036 -24.166322)
		(end 92.691204 -25.870154)
		(width 0.127)
		(layer "In5.Cu")
		(net "UART_IOM_RX")
	)
	(segment
		(start 82.716624 -81.44002)
		(end 82.716624 -82.859626)
		(width 0.127)
		(layer "In5.Cu")
		(net "UART_IOM_RX")
	)
	(segment
		(start 83.549236 -68.797678)
		(end 82.908648 -69.438266)
		(width 0.127)
		(layer "In5.Cu")
		(net "UART_IOM_RX")
	)
	(segment
		(start 82.8802 -76.870306)
		(end 82.8802 -81.276444)
		(width 0.127)
		(layer "In5.Cu")
		(net "UART_IOM_RX")
	)
	(segment
		(start 82.8802 -83.023202)
		(end 82.8802 -87.676228)
		(width 0.127)
		(layer "In5.Cu")
		(net "UART_IOM_RX")
	)
	(segment
		(start 94.5388 -108.6104)
		(end 94.5388 -114.7826)
		(width 0.127)
		(layer "In5.Cu")
		(net "UART_IOM_RX")
	)
	(segment
		(start 82.9056 -89.44864)
		(end 82.9056 -94.037912)
		(width 0.127)
		(layer "In5.Cu")
		(net "UART_IOM_RX")
	)
	(segment
		(start 92.691204 -25.870154)
		(end 87.744046 -25.870154)
		(width 0.127)
		(layer "In5.Cu")
		(net "UART_IOM_RX")
	)
	(segment
		(start 94.5388 -114.7826)
		(end 94.488 -114.8334)
		(width 0.127)
		(layer "In5.Cu")
		(net "UART_IOM_RX")
	)
	(segment
		(start 82.716624 -76.70673)
		(end 82.8802 -76.870306)
		(width 0.127)
		(layer "In5.Cu")
		(net "UART_IOM_RX")
	)
	(segment
		(start 82.8802 -81.276444)
		(end 82.716624 -81.44002)
		(width 0.127)
		(layer "In5.Cu")
		(net "UART_IOM_RX")
	)
	(segment
		(start 82.8802 -95.810832)
		(end 82.8802 -96.5962)
		(width 0.127)
		(layer "In5.Cu")
		(net "UART_IOM_RX")
	)
	(segment
		(start 82.857594 -42.535602)
		(end 82.857594 -60.562998)
		(width 0.127)
		(layer "In5.Cu")
		(net "UART_IOM_RX")
	)
	(segment
		(start 82.716624 -87.839804)
		(end 82.716624 -89.259664)
		(width 0.127)
		(layer "In5.Cu")
		(net "UART_IOM_RX")
	)
	(segment
		(start 82.857594 -60.562998)
		(end 83.549236 -61.25464)
		(width 0.127)
		(layer "In5.Cu")
		(net "UART_IOM_RX")
	)
	(segment
		(start 115.2652 -14.1478)
		(end 115.868196 -13.544804)
		(width 0.254)
		(layer "F.Cu")
		(net "MB0_VCC")
	)
	(segment
		(start 115.868196 -13.544804)
		(end 116.500148 -13.544804)
		(width 0.254)
		(layer "F.Cu")
		(net "MB0_VCC")
	)
	(segment
		(start 117.8814 -14.1351)
		(end 117.6528 -14.1351)
		(width 0.254)
		(layer "F.Cu")
		(net "MB0_VCC")
	)
	(segment
		(start 117.090444 -14.1351)
		(end 117.6528 -14.1351)
		(width 0.254)
		(layer "F.Cu")
		(net "MB0_VCC")
	)
	(segment
		(start 118.121938 -13.894562)
		(end 117.8814 -14.1351)
		(width 0.254)
		(layer "F.Cu")
		(net "MB0_VCC")
	)
	(segment
		(start 118.121938 -11.4681)
		(end 118.121938 -13.894562)
		(width 0.254)
		(layer "F.Cu")
		(net "MB0_VCC")
	)
	(segment
		(start 116.500148 -13.544804)
		(end 117.090444 -14.1351)
		(width 0.254)
		(layer "F.Cu")
		(net "MB0_VCC")
	)
	(via
		(at 116.500148 -13.544804)
		(size 0.6604)
		(drill 0.3302)
		(layers "F.Cu" "B.Cu")
		(net "MB0_VCC")
	)
	(segment
		(start 111.8362 -12.079478)
		(end 111.8362 -12.166854)
		(width 0.127)
		(layer "F.Cu")
		(net "MB0_VCAP_R")
	)
	(segment
		(start 112.967516 -11.646154)
		(end 112.269524 -11.646154)
		(width 0.127)
		(layer "F.Cu")
		(net "MB0_VCAP_R")
	)
	(segment
		(start 112.967516 -11.646154)
		(end 113.048542 -11.565128)
		(width 0.127)
		(layer "F.Cu")
		(net "MB0_VCAP_R")
	)
	(segment
		(start 112.269524 -11.646154)
		(end 111.8362 -12.079478)
		(width 0.127)
		(layer "F.Cu")
		(net "MB0_VCAP_R")
	)
	(segment
		(start 114.603784 -11.565128)
		(end 115.927378 -10.241534)
		(width 0.127)
		(layer "F.Cu")
		(net "MB0_VCAP_R")
	)
	(segment
		(start 113.048542 -11.565128)
		(end 114.603784 -11.565128)
		(width 0.127)
		(layer "F.Cu")
		(net "MB0_VCAP_R")
	)
	(segment
		(start 113.920524 -12.69111)
		(end 112.959388 -12.69111)
		(width 0.127)
		(layer "F.Cu")
		(net "MB0_VCAP_R")
	)
	(segment
		(start 113.92408 -12.694666)
		(end 113.920524 -12.69111)
		(width 0.127)
		(layer "F.Cu")
		(net "MB0_VCAP_R")
	)
	(segment
		(start 112.360456 -12.69111)
		(end 112.959388 -12.69111)
		(width 0.127)
		(layer "F.Cu")
		(net "MB0_VCAP_R")
	)
	(segment
		(start 111.8362 -12.166854)
		(end 112.360456 -12.69111)
		(width 0.127)
		(layer "F.Cu")
		(net "MB0_VCAP_R")
	)
	(segment
		(start 115.927378 -10.241534)
		(end 116.3955 -10.241534)
		(width 0.127)
		(layer "F.Cu")
		(net "MB0_VCAP_R")
	)
	(via
		(at 111.579152 -11.917934)
		(size 0.6096)
		(drill 0.3048)
		(layers "F.Cu" "B.Cu")
		(net "MB0_VCAP_R")
	)
	(via
		(at 113.92408 -12.694666)
		(size 0.508)
		(drill 0.254)
		(layers "F.Cu" "B.Cu")
		(net "MB0_VCAP_R")
	)
	(segment
		(start 112.352328 -12.69111)
		(end 111.579152 -11.917934)
		(width 0.127)
		(layer "B.Cu")
		(net "MB0_VCAP_R")
	)
	(segment
		(start 111.2393 -9.6012)
		(end 111.2393 -11.578082)
		(width 0.127)
		(layer "B.Cu")
		(net "MB0_VCAP_R")
	)
	(segment
		(start 111.2393 -11.578082)
		(end 111.579152 -11.917934)
		(width 0.127)
		(layer "B.Cu")
		(net "MB0_VCAP_R")
	)
	(segment
		(start 113.920524 -12.69111)
		(end 112.352328 -12.69111)
		(width 0.127)
		(layer "B.Cu")
		(net "MB0_VCAP_R")
	)
	(segment
		(start 113.92408 -12.694666)
		(end 113.920524 -12.69111)
		(width 0.127)
		(layer "B.Cu")
		(net "MB0_VCAP_R")
	)
	(segment
		(start 113.30559 -8.726678)
		(end 114.260122 -8.726678)
		(width 0.127)
		(layer "F.Cu")
		(net "MB0_TIME_R")
	)
	(segment
		(start 114.260122 -8.726678)
		(end 114.5286 -8.4582)
		(width 0.127)
		(layer "F.Cu")
		(net "MB0_TIME_R")
	)
	(segment
		(start 116.3955 -8.741664)
		(end 115.751864 -8.741664)
		(width 0.127)
		(layer "F.Cu")
		(net "MB0_TIME_R")
	)
	(segment
		(start 115.4684 -8.4582)
		(end 114.5286 -8.4582)
		(width 0.127)
		(layer "F.Cu")
		(net "MB0_TIME_R")
	)
	(segment
		(start 115.751864 -8.741664)
		(end 115.4684 -8.4582)
		(width 0.127)
		(layer "F.Cu")
		(net "MB0_TIME_R")
	)
	(via
		(at 114.5286 -8.4582)
		(size 0.6604)
		(drill 0.3302)
		(layers "F.Cu" "B.Cu")
		(net "MB0_TIME_R")
	)
	(segment
		(start 123.4059 -17.265142)
		(end 123.4059 -17.843754)
		(width 0.127)
		(layer "F.Cu")
		(net "MB0_TEMP_E")
	)
	(segment
		(start 126.80696 -17.15643)
		(end 126.80696 -17.865344)
		(width 0.127)
		(layer "F.Cu")
		(net "MB0_TEMP_E")
	)
	(segment
		(start 125.994922 -18.677382)
		(end 125.519434 -18.677382)
		(width 0.127)
		(layer "F.Cu")
		(net "MB0_TEMP_E")
	)
	(segment
		(start 123.4059 -17.843754)
		(end 124.239528 -18.677382)
		(width 0.127)
		(layer "F.Cu")
		(net "MB0_TEMP_E")
	)
	(segment
		(start 126.80696 -17.865344)
		(end 125.994922 -18.677382)
		(width 0.127)
		(layer "F.Cu")
		(net "MB0_TEMP_E")
	)
	(segment
		(start 124.239528 -18.677382)
		(end 125.519434 -18.677382)
		(width 0.127)
		(layer "F.Cu")
		(net "MB0_TEMP_E")
	)
	(via
		(at 125.519434 -18.677382)
		(size 0.6604)
		(drill 0.3302)
		(layers "F.Cu" "B.Cu")
		(net "MB0_TEMP_E")
	)
	(segment
		(start 123.43765 -15.315184)
		(end 123.18111 -15.571724)
		(width 0.127)
		(layer "F.Cu")
		(net "MB0_TEMP_C")
	)
	(segment
		(start 123.18111 -16.110712)
		(end 123.242578 -16.17218)
		(width 0.127)
		(layer "F.Cu")
		(net "MB0_TEMP_C")
	)
	(segment
		(start 123.242578 -16.17218)
		(end 124.90196 -16.17218)
		(width 0.127)
		(layer "F.Cu")
		(net "MB0_TEMP_C")
	)
	(segment
		(start 124.90196 -16.17218)
		(end 125.82271 -16.17218)
		(width 0.127)
		(layer "F.Cu")
		(net "MB0_TEMP_C")
	)
	(segment
		(start 123.43765 -14.9479)
		(end 123.43765 -15.315184)
		(width 0.127)
		(layer "F.Cu")
		(net "MB0_TEMP_C")
	)
	(segment
		(start 123.18111 -15.571724)
		(end 123.18111 -16.110712)
		(width 0.127)
		(layer "F.Cu")
		(net "MB0_TEMP_C")
	)
	(segment
		(start 125.82271 -16.17218)
		(end 126.80696 -15.18793)
		(width 0.127)
		(layer "F.Cu")
		(net "MB0_TEMP_C")
	)
	(via
		(at 123.18111 -16.110712)
		(size 0.6604)
		(drill 0.3302)
		(layers "F.Cu" "B.Cu")
		(net "MB0_TEMP_C")
	)
	(segment
		(start 121.107454 -13.306044)
		(end 121.107454 -12.66317)
		(width 0.127)
		(layer "F.Cu")
		(net "MB0_TEMP")
	)
	(segment
		(start 120.98401 -13.64361)
		(end 120.98401 -13.429488)
		(width 0.127)
		(layer "F.Cu")
		(net "MB0_TEMP")
	)
	(segment
		(start 120.98147 -13.70711)
		(end 120.98147 -13.64615)
		(width 0.127)
		(layer "F.Cu")
		(net "MB0_TEMP")
	)
	(segment
		(start 120.98147 -13.70711)
		(end 120.98147 -15.30477)
		(width 0.127)
		(layer "F.Cu")
		(net "MB0_TEMP")
	)
	(segment
		(start 120.98401 -13.429488)
		(end 121.107454 -13.306044)
		(width 0.127)
		(layer "F.Cu")
		(net "MB0_TEMP")
	)
	(segment
		(start 121.93905 -15.5575)
		(end 122.54865 -14.9479)
		(width 0.127)
		(layer "F.Cu")
		(net "MB0_TEMP")
	)
	(segment
		(start 120.98147 -13.64615)
		(end 120.98401 -13.64361)
		(width 0.127)
		(layer "F.Cu")
		(net "MB0_TEMP")
	)
	(segment
		(start 120.98147 -15.30477)
		(end 121.2342 -15.5575)
		(width 0.127)
		(layer "F.Cu")
		(net "MB0_TEMP")
	)
	(segment
		(start 121.2342 -15.5575)
		(end 121.93905 -15.5575)
		(width 0.127)
		(layer "F.Cu")
		(net "MB0_TEMP")
	)
	(segment
		(start 121.107454 -12.66317)
		(end 120.62206 -12.177776)
		(width 0.127)
		(layer "F.Cu")
		(net "MB0_TEMP")
	)
	(segment
		(start 120.62206 -12.177776)
		(end 120.62206 -11.5443)
		(width 0.127)
		(layer "F.Cu")
		(net "MB0_TEMP")
	)
	(via
		(at 120.98147 -13.70711)
		(size 0.6604)
		(drill 0.3302)
		(layers "F.Cu" "B.Cu")
		(net "MB0_TEMP")
	)
	(segment
		(start 116.846096 -4.775454)
		(end 117.12194 -5.051298)
		(width 0.127)
		(layer "F.Cu")
		(net "MB0_SPISS_PD")
	)
	(segment
		(start 114.094514 -4.775454)
		(end 116.846096 -4.775454)
		(width 0.127)
		(layer "F.Cu")
		(net "MB0_SPISS_PD")
	)
	(segment
		(start 113.29289 -5.577078)
		(end 114.094514 -4.775454)
		(width 0.127)
		(layer "F.Cu")
		(net "MB0_SPISS_PD")
	)
	(segment
		(start 117.12194 -5.051298)
		(end 117.12194 -6.4389)
		(width 0.127)
		(layer "F.Cu")
		(net "MB0_SPISS_PD")
	)
	(via
		(at 116.846096 -4.775454)
		(size 0.6604)
		(drill 0.3302)
		(layers "F.Cu" "B.Cu")
		(net "MB0_SPISS_PD")
	)
	(segment
		(start 123.542298 -6.765798)
		(end 123.041156 -6.765798)
		(width 0.127)
		(layer "F.Cu")
		(net "MB0_RETRY_R")
	)
	(segment
		(start 124.3965 -7.62)
		(end 123.542298 -6.765798)
		(width 0.127)
		(layer "F.Cu")
		(net "MB0_RETRY_R")
	)
	(segment
		(start 122.565414 -7.24154)
		(end 121.4247 -7.24154)
		(width 0.127)
		(layer "F.Cu")
		(net "MB0_RETRY_R")
	)
	(segment
		(start 123.041156 -6.765798)
		(end 122.565414 -7.24154)
		(width 0.127)
		(layer "F.Cu")
		(net "MB0_RETRY_R")
	)
	(via
		(at 123.041156 -6.765798)
		(size 0.6604)
		(drill 0.3302)
		(layers "F.Cu" "B.Cu")
		(net "MB0_RETRY_R")
	)
	(segment
		(start 112.959388 -13.58011)
		(end 112.07496 -14.464538)
		(width 0.127)
		(layer "F.Cu")
		(net "MB0_PSET_R")
	)
	(segment
		(start 111.8362 -14.405864)
		(end 111.894874 -14.464538)
		(width 0.127)
		(layer "F.Cu")
		(net "MB0_PSET_R")
	)
	(segment
		(start 114.882422 -12.93876)
		(end 116.3193 -11.501882)
		(width 0.127)
		(layer "F.Cu")
		(net "MB0_PSET_R")
	)
	(segment
		(start 116.3193 -11.501882)
		(end 116.3193 -10.74166)
		(width 0.127)
		(layer "F.Cu")
		(net "MB0_PSET_R")
	)
	(segment
		(start 112.07496 -14.464538)
		(end 111.894874 -14.464538)
		(width 0.127)
		(layer "F.Cu")
		(net "MB0_PSET_R")
	)
	(segment
		(start 112.959388 -13.58011)
		(end 114.241072 -13.58011)
		(width 0.127)
		(layer "F.Cu")
		(net "MB0_PSET_R")
	)
	(segment
		(start 114.241072 -13.58011)
		(end 114.882422 -12.93876)
		(width 0.127)
		(layer "F.Cu")
		(net "MB0_PSET_R")
	)
	(segment
		(start 111.8362 -13.324078)
		(end 111.8362 -14.405864)
		(width 0.127)
		(layer "F.Cu")
		(net "MB0_PSET_R")
	)
	(via
		(at 114.882422 -12.93876)
		(size 0.6604)
		(drill 0.3302)
		(layers "F.Cu" "B.Cu")
		(net "MB0_PSET_R")
	)
	(segment
		(start 121.3485 -9.241536)
		(end 121.857008 -9.241536)
		(width 0.127)
		(layer "F.Cu")
		(net "MB0_P12V_PWGIN_R")
	)
	(segment
		(start 121.857008 -9.241536)
		(end 123.207272 -10.5918)
		(width 0.127)
		(layer "F.Cu")
		(net "MB0_P12V_PWGIN_R")
	)
	(segment
		(start 123.5837 -10.702544)
		(end 123.472956 -10.5918)
		(width 0.127)
		(layer "F.Cu")
		(net "MB0_P12V_PWGIN_R")
	)
	(segment
		(start 123.5837 -12.4714)
		(end 123.5837 -10.702544)
		(width 0.127)
		(layer "F.Cu")
		(net "MB0_P12V_PWGIN_R")
	)
	(segment
		(start 123.207272 -10.5918)
		(end 123.472956 -10.5918)
		(width 0.127)
		(layer "F.Cu")
		(net "MB0_P12V_PWGIN_R")
	)
	(via
		(at 124.381514 -10.748518)
		(size 0.6096)
		(drill 0.3048)
		(layers "F.Cu" "B.Cu")
		(net "MB0_P12V_PWGIN_R")
	)
	(via
		(at 123.472956 -10.5918)
		(size 0.508)
		(drill 0.254)
		(layers "F.Cu" "B.Cu")
		(net "MB0_P12V_PWGIN_R")
	)
	(segment
		(start 124.381514 -10.748518)
		(end 124.3965 -10.733532)
		(width 0.127)
		(layer "B.Cu")
		(net "MB0_P12V_PWGIN_R")
	)
	(segment
		(start 124.381514 -10.748518)
		(end 123.629674 -10.748518)
		(width 0.127)
		(layer "B.Cu")
		(net "MB0_P12V_PWGIN_R")
	)
	(segment
		(start 123.629674 -10.748518)
		(end 123.472956 -10.5918)
		(width 0.127)
		(layer "B.Cu")
		(net "MB0_P12V_PWGIN_R")
	)
	(segment
		(start 124.3965 -10.733532)
		(end 124.3965 -9.779)
		(width 0.127)
		(layer "B.Cu")
		(net "MB0_P12V_PWGIN_R")
	)
	(via
		(at 140.0048 -12.0142)
		(size 0.6604)
		(drill 0.3302)
		(layers "F.Cu" "B.Cu")
		(net "MB0_P12V_MAIN_R")
	)
	(segment
		(start 113.300764 -9.689338)
		(end 114.415316 -9.689338)
		(width 0.127)
		(layer "F.Cu")
		(net "MB0_ISTART_R")
	)
	(segment
		(start 114.415316 -9.689338)
		(end 114.863118 -9.241536)
		(width 0.127)
		(layer "F.Cu")
		(net "MB0_ISTART_R")
	)
	(segment
		(start 114.863118 -9.241536)
		(end 116.3955 -9.241536)
		(width 0.127)
		(layer "F.Cu")
		(net "MB0_ISTART_R")
	)
	(via
		(at 112.649 -10.668)
		(size 0.6096)
		(drill 0.3048)
		(layers "F.Cu" "B.Cu")
		(net "MB0_ISTART_R")
	)
	(via
		(at 114.415316 -9.689338)
		(size 0.508)
		(drill 0.254)
		(layers "F.Cu" "B.Cu")
		(net "MB0_ISTART_R")
	)
	(segment
		(start 112.649 -10.668)
		(end 112.483646 -10.668)
		(width 0.127)
		(layer "B.Cu")
		(net "MB0_ISTART_R")
	)
	(segment
		(start 112.1283 -10.312654)
		(end 112.1283 -9.6012)
		(width 0.127)
		(layer "B.Cu")
		(net "MB0_ISTART_R")
	)
	(segment
		(start 114.415316 -9.689338)
		(end 114.301778 -9.5758)
		(width 0.127)
		(layer "B.Cu")
		(net "MB0_ISTART_R")
	)
	(segment
		(start 113.2586 -10.198354)
		(end 112.788954 -10.668)
		(width 0.127)
		(layer "B.Cu")
		(net "MB0_ISTART_R")
	)
	(segment
		(start 113.2586 -9.5758)
		(end 113.2586 -10.198354)
		(width 0.127)
		(layer "B.Cu")
		(net "MB0_ISTART_R")
	)
	(segment
		(start 112.788954 -10.668)
		(end 112.649 -10.668)
		(width 0.127)
		(layer "B.Cu")
		(net "MB0_ISTART_R")
	)
	(segment
		(start 114.301778 -9.5758)
		(end 113.2586 -9.5758)
		(width 0.127)
		(layer "B.Cu")
		(net "MB0_ISTART_R")
	)
	(segment
		(start 112.483646 -10.668)
		(end 112.1283 -10.312654)
		(width 0.127)
		(layer "B.Cu")
		(net "MB0_ISTART_R")
	)
	(segment
		(start 115.320572 -9.741662)
		(end 114.30508 -10.757154)
		(width 0.127)
		(layer "F.Cu")
		(net "MB0_ISET_R")
	)
	(segment
		(start 111.15929 -10.157968)
		(end 111.15929 -9.666478)
		(width 0.127)
		(layer "F.Cu")
		(net "MB0_ISET_R")
	)
	(segment
		(start 111.8362 -10.834878)
		(end 112.889792 -10.834878)
		(width 0.127)
		(layer "F.Cu")
		(net "MB0_ISET_R")
	)
	(segment
		(start 114.30508 -10.757154)
		(end 114.010186 -10.757154)
		(width 0.127)
		(layer "F.Cu")
		(net "MB0_ISET_R")
	)
	(segment
		(start 112.889792 -10.834878)
		(end 112.967516 -10.757154)
		(width 0.127)
		(layer "F.Cu")
		(net "MB0_ISET_R")
	)
	(segment
		(start 116.3955 -9.741662)
		(end 115.320572 -9.741662)
		(width 0.127)
		(layer "F.Cu")
		(net "MB0_ISET_R")
	)
	(segment
		(start 114.010186 -10.757154)
		(end 112.967516 -10.757154)
		(width 0.127)
		(layer "F.Cu")
		(net "MB0_ISET_R")
	)
	(segment
		(start 111.8362 -10.834878)
		(end 111.15929 -10.157968)
		(width 0.127)
		(layer "F.Cu")
		(net "MB0_ISET_R")
	)
	(via
		(at 114.010186 -10.757154)
		(size 0.6604)
		(drill 0.3302)
		(layers "F.Cu" "B.Cu")
		(net "MB0_ISET_R")
	)
	(segment
		(start 118.6942 -5.5499)
		(end 118.622064 -5.622036)
		(width 0.127)
		(layer "F.Cu")
		(net "MB0_HS_ENABLE")
	)
	(segment
		(start 118.6942 -5.08)
		(end 118.6942 -5.5499)
		(width 0.127)
		(layer "F.Cu")
		(net "MB0_HS_ENABLE")
	)
	(segment
		(start 118.622064 -5.622036)
		(end 118.622064 -6.5151)
		(width 0.127)
		(layer "F.Cu")
		(net "MB0_HS_ENABLE")
	)
	(via
		(at 116.459 -6.858)
		(size 0.6096)
		(drill 0.3048)
		(layers "F.Cu" "B.Cu")
		(net "MB0_HS_ENABLE")
	)
	(via
		(at 118.6942 -5.08)
		(size 0.508)
		(drill 0.254)
		(layers "F.Cu" "B.Cu")
		(net "MB0_HS_ENABLE")
	)
	(segment
		(start 116.1923 -7.1247)
		(end 116.1923 -8.5344)
		(width 0.127)
		(layer "B.Cu")
		(net "MB0_HS_ENABLE")
	)
	(segment
		(start 118.6942 -5.376418)
		(end 118.6942 -5.08)
		(width 0.127)
		(layer "B.Cu")
		(net "MB0_HS_ENABLE")
	)
	(segment
		(start 118.745 -5.427218)
		(end 118.6942 -5.376418)
		(width 0.127)
		(layer "B.Cu")
		(net "MB0_HS_ENABLE")
	)
	(segment
		(start 115.9256 -8.8011)
		(end 116.1923 -8.5344)
		(width 0.127)
		(layer "B.Cu")
		(net "MB0_HS_ENABLE")
	)
	(segment
		(start 116.459 -6.858)
		(end 116.1923 -7.1247)
		(width 0.127)
		(layer "B.Cu")
		(net "MB0_HS_ENABLE")
	)
	(segment
		(start 118.745 -6.477)
		(end 116.84 -6.477)
		(width 0.127)
		(layer "B.Cu")
		(net "MB0_HS_ENABLE")
	)
	(segment
		(start 118.745 -6.477)
		(end 118.745 -5.427218)
		(width 0.127)
		(layer "B.Cu")
		(net "MB0_HS_ENABLE")
	)
	(segment
		(start 116.84 -6.477)
		(end 116.459 -6.858)
		(width 0.127)
		(layer "B.Cu")
		(net "MB0_HS_ENABLE")
	)
	(segment
		(start 115.9256 -13.8049)
		(end 115.9256 -8.8011)
		(width 0.127)
		(layer "B.Cu")
		(net "MB0_HS_ENABLE")
	)
	(segment
		(start 122.254264 -8.741664)
		(end 122.74169 -9.22909)
		(width 0.127)
		(layer "F.Cu")
		(net "MB0_CM_VOUT_R")
	)
	(segment
		(start 123.613418 -9.628378)
		(end 123.588272 -9.653524)
		(width 0.127)
		(layer "F.Cu")
		(net "MB0_CM_VOUT_R")
	)
	(segment
		(start 122.74169 -9.22909)
		(end 123.166124 -9.653524)
		(width 0.127)
		(layer "F.Cu")
		(net "MB0_CM_VOUT_R")
	)
	(segment
		(start 123.166124 -9.653524)
		(end 123.588272 -9.653524)
		(width 0.127)
		(layer "F.Cu")
		(net "MB0_CM_VOUT_R")
	)
	(segment
		(start 124.418344 -9.628378)
		(end 123.613418 -9.628378)
		(width 0.127)
		(layer "F.Cu")
		(net "MB0_CM_VOUT_R")
	)
	(segment
		(start 121.3485 -8.741664)
		(end 122.254264 -8.741664)
		(width 0.127)
		(layer "F.Cu")
		(net "MB0_CM_VOUT_R")
	)
	(via
		(at 122.74169 -9.22909)
		(size 0.6604)
		(drill 0.3302)
		(layers "F.Cu" "B.Cu")
		(net "MB0_CM_VOUT_R")
	)
	(via
		(at 123.588272 -9.653524)
		(size 0.508)
		(drill 0.254)
		(layers "F.Cu" "B.Cu")
		(net "MB0_CM_VOUT_R")
	)
	(segment
		(start 123.588272 -9.010142)
		(end 123.846844 -8.75157)
		(width 0.127)
		(layer "B.Cu")
		(net "MB0_CM_VOUT_R")
	)
	(segment
		(start 123.588272 -9.653524)
		(end 123.588272 -9.010142)
		(width 0.127)
		(layer "B.Cu")
		(net "MB0_CM_VOUT_R")
	)
	(segment
		(start 123.846844 -8.75157)
		(end 124.394976 -8.75157)
		(width 0.127)
		(layer "B.Cu")
		(net "MB0_CM_VOUT_R")
	)
	(segment
		(start 117.50675 -12.669774)
		(end 117.622066 -12.554458)
		(width 0.127)
		(layer "F.Cu")
		(net "MB0_CM_UV_R")
	)
	(segment
		(start 117.622066 -12.554458)
		(end 117.622066 -11.4681)
		(width 0.127)
		(layer "F.Cu")
		(net "MB0_CM_UV_R")
	)
	(via
		(at 117.50675 -12.669774)
		(size 0.508)
		(drill 0.254)
		(layers "F.Cu" "B.Cu")
		(net "MB0_CM_UV_R")
	)
	(via
		(at 130.937 -14.7066)
		(size 0.508)
		(drill 0.254)
		(layers "F.Cu" "B.Cu")
		(net "MB0_CM_UV_R")
	)
	(via
		(at 127.74422 -16.29918)
		(size 0.6096)
		(drill 0.3048)
		(layers "F.Cu" "B.Cu")
		(net "MB0_CM_UV_R")
	)
	(segment
		(start 128.8415 -16.51)
		(end 127.95504 -16.51)
		(width 0.127)
		(layer "B.Cu")
		(net "MB0_CM_UV_R")
	)
	(segment
		(start 129.735326 -14.661642)
		(end 129.00533 -15.391638)
		(width 0.127)
		(layer "B.Cu")
		(net "MB0_CM_UV_R")
	)
	(segment
		(start 127.74422 -15.99692)
		(end 127.74422 -16.29918)
		(width 0.127)
		(layer "B.Cu")
		(net "MB0_CM_UV_R")
	)
	(segment
		(start 130.12166 -14.661642)
		(end 130.892042 -14.661642)
		(width 0.127)
		(layer "B.Cu")
		(net "MB0_CM_UV_R")
	)
	(segment
		(start 130.12166 -14.661642)
		(end 129.735326 -14.661642)
		(width 0.127)
		(layer "B.Cu")
		(net "MB0_CM_UV_R")
	)
	(segment
		(start 127.95504 -16.51)
		(end 127.74422 -16.29918)
		(width 0.127)
		(layer "B.Cu")
		(net "MB0_CM_UV_R")
	)
	(segment
		(start 128.349502 -15.391638)
		(end 127.74422 -15.99692)
		(width 0.127)
		(layer "B.Cu")
		(net "MB0_CM_UV_R")
	)
	(segment
		(start 129.00533 -15.391638)
		(end 128.349502 -15.391638)
		(width 0.127)
		(layer "B.Cu")
		(net "MB0_CM_UV_R")
	)
	(segment
		(start 130.892042 -14.661642)
		(end 130.937 -14.7066)
		(width 0.127)
		(layer "B.Cu")
		(net "MB0_CM_UV_R")
	)
	(segment
		(start 118.56339 -13.726414)
		(end 129.677414 -13.726414)
		(width 0.127)
		(layer "In5.Cu")
		(net "MB0_CM_UV_R")
	)
	(segment
		(start 130.5052 -14.5542)
		(end 130.7846 -14.5542)
		(width 0.127)
		(layer "In5.Cu")
		(net "MB0_CM_UV_R")
	)
	(segment
		(start 129.677414 -13.726414)
		(end 130.5052 -14.5542)
		(width 0.127)
		(layer "In5.Cu")
		(net "MB0_CM_UV_R")
	)
	(segment
		(start 130.7846 -14.5542)
		(end 130.937 -14.7066)
		(width 0.127)
		(layer "In5.Cu")
		(net "MB0_CM_UV_R")
	)
	(segment
		(start 117.50675 -12.669774)
		(end 118.56339 -13.726414)
		(width 0.127)
		(layer "In5.Cu")
		(net "MB0_CM_UV_R")
	)
	(segment
		(start 131.038854 -15.24)
		(end 125.946154 -20.3327)
		(width 0.127)
		(layer "F.Cu")
		(net "MB0_CM_SENSE_R1_P")
	)
	(segment
		(start 118.9228 -17.487392)
		(end 119.532146 -18.096738)
		(width 0.127)
		(layer "F.Cu")
		(net "MB0_CM_SENSE_R1_P")
	)
	(segment
		(start 125.946154 -20.3327)
		(end 122.986038 -20.3327)
		(width 0.127)
		(layer "F.Cu")
		(net "MB0_CM_SENSE_R1_P")
	)
	(segment
		(start 135.902192 -13.919962)
		(end 135.176006 -13.919962)
		(width 0.127)
		(layer "F.Cu")
		(net "MB0_CM_SENSE_R1_P")
	)
	(segment
		(start 121.064528 -19.62912)
		(end 119.532146 -18.096738)
		(width 0.127)
		(layer "F.Cu")
		(net "MB0_CM_SENSE_R1_P")
	)
	(segment
		(start 122.986038 -20.3327)
		(end 122.282458 -19.62912)
		(width 0.127)
		(layer "F.Cu")
		(net "MB0_CM_SENSE_R1_P")
	)
	(segment
		(start 134.3533 -13.6144)
		(end 132.7277 -15.24)
		(width 0.127)
		(layer "F.Cu")
		(net "MB0_CM_SENSE_R1_P")
	)
	(segment
		(start 118.9228 -16.7767)
		(end 118.9228 -17.487392)
		(width 0.127)
		(layer "F.Cu")
		(net "MB0_CM_SENSE_R1_P")
	)
	(segment
		(start 134.870444 -13.6144)
		(end 134.3533 -13.6144)
		(width 0.127)
		(layer "F.Cu")
		(net "MB0_CM_SENSE_R1_P")
	)
	(segment
		(start 135.176006 -13.919962)
		(end 134.870444 -13.6144)
		(width 0.127)
		(layer "F.Cu")
		(net "MB0_CM_SENSE_R1_P")
	)
	(segment
		(start 122.282458 -19.62912)
		(end 121.064528 -19.62912)
		(width 0.127)
		(layer "F.Cu")
		(net "MB0_CM_SENSE_R1_P")
	)
	(segment
		(start 132.7277 -15.24)
		(end 131.038854 -15.24)
		(width 0.127)
		(layer "F.Cu")
		(net "MB0_CM_SENSE_R1_P")
	)
	(via
		(at 119.532146 -18.096738)
		(size 0.6604)
		(drill 0.3302)
		(layers "F.Cu" "B.Cu")
		(net "MB0_CM_SENSE_R1_P")
	)
	(segment
		(start 122.493024 -19.12112)
		(end 121.43232 -19.12112)
		(width 0.127)
		(layer "F.Cu")
		(net "MB0_CM_SENSE_R1_N")
	)
	(segment
		(start 121.43232 -19.12112)
		(end 120.015 -17.7038)
		(width 0.127)
		(layer "F.Cu")
		(net "MB0_CM_SENSE_R1_N")
	)
	(segment
		(start 124.39142 -19.741896)
		(end 123.1138 -19.741896)
		(width 0.127)
		(layer "F.Cu")
		(net "MB0_CM_SENSE_R1_N")
	)
	(segment
		(start 129.946146 -11.9634)
		(end 133.7691 -11.9634)
		(width 0.127)
		(layer "F.Cu")
		(net "MB0_CM_SENSE_R1_N")
	)
	(segment
		(start 133.7691 -11.9634)
		(end 134.3533 -12.5476)
		(width 0.127)
		(layer "F.Cu")
		(net "MB0_CM_SENSE_R1_N")
	)
	(segment
		(start 135.19277 -12.292838)
		(end 134.938008 -12.5476)
		(width 0.127)
		(layer "F.Cu")
		(net "MB0_CM_SENSE_R1_N")
	)
	(segment
		(start 129.4765 -12.433046)
		(end 129.946146 -11.9634)
		(width 0.127)
		(layer "F.Cu")
		(net "MB0_CM_SENSE_R1_N")
	)
	(segment
		(start 123.1138 -19.741896)
		(end 122.493024 -19.12112)
		(width 0.127)
		(layer "F.Cu")
		(net "MB0_CM_SENSE_R1_N")
	)
	(segment
		(start 120.015 -17.7038)
		(end 120.015 -16.7513)
		(width 0.127)
		(layer "F.Cu")
		(net "MB0_CM_SENSE_R1_N")
	)
	(segment
		(start 135.902192 -12.292838)
		(end 135.19277 -12.292838)
		(width 0.127)
		(layer "F.Cu")
		(net "MB0_CM_SENSE_R1_N")
	)
	(segment
		(start 125.818392 -19.741896)
		(end 129.4765 -16.083788)
		(width 0.127)
		(layer "F.Cu")
		(net "MB0_CM_SENSE_R1_N")
	)
	(segment
		(start 129.4765 -16.083788)
		(end 129.4765 -12.433046)
		(width 0.127)
		(layer "F.Cu")
		(net "MB0_CM_SENSE_R1_N")
	)
	(segment
		(start 124.39142 -19.741896)
		(end 125.818392 -19.741896)
		(width 0.127)
		(layer "F.Cu")
		(net "MB0_CM_SENSE_R1_N")
	)
	(segment
		(start 134.938008 -12.5476)
		(end 134.3533 -12.5476)
		(width 0.127)
		(layer "F.Cu")
		(net "MB0_CM_SENSE_R1_N")
	)
	(via
		(at 124.39142 -19.741896)
		(size 0.6604)
		(drill 0.3302)
		(layers "F.Cu" "B.Cu")
		(net "MB0_CM_SENSE_R1_N")
	)
	(segment
		(start 118.622064 -12.780264)
		(end 118.622064 -11.4681)
		(width 0.127)
		(layer "F.Cu")
		(net "MB0_CM_SENSE_P")
	)
	(segment
		(start 118.8212 -14.732)
		(end 118.8212 -14.19352)
		(width 0.127)
		(layer "F.Cu")
		(net "MB0_CM_SENSE_P")
	)
	(segment
		(start 118.939564 -13.65123)
		(end 118.939564 -13.097764)
		(width 0.127)
		(layer "F.Cu")
		(net "MB0_CM_SENSE_P")
	)
	(segment
		(start 118.9228 -14.8336)
		(end 118.8212 -14.732)
		(width 0.127)
		(layer "F.Cu")
		(net "MB0_CM_SENSE_P")
	)
	(segment
		(start 118.939564 -13.097764)
		(end 118.622064 -12.780264)
		(width 0.127)
		(layer "F.Cu")
		(net "MB0_CM_SENSE_P")
	)
	(segment
		(start 118.8212 -14.19352)
		(end 118.939564 -14.075156)
		(width 0.127)
		(layer "F.Cu")
		(net "MB0_CM_SENSE_P")
	)
	(segment
		(start 118.9228 -15.8877)
		(end 118.9228 -14.8336)
		(width 0.127)
		(layer "F.Cu")
		(net "MB0_CM_SENSE_P")
	)
	(segment
		(start 118.939564 -14.075156)
		(end 118.939564 -13.65123)
		(width 0.127)
		(layer "F.Cu")
		(net "MB0_CM_SENSE_P")
	)
	(via
		(at 118.8212 -14.732)
		(size 0.6604)
		(drill 0.3302)
		(layers "F.Cu" "B.Cu")
		(net "MB0_CM_SENSE_P")
	)
	(segment
		(start 119.828564 -13.65123)
		(end 120.043702 -13.65123)
		(width 0.127)
		(layer "F.Cu")
		(net "MB0_CM_SENSE_N")
	)
	(segment
		(start 119.828564 -13.65123)
		(end 119.828564 -14.114272)
		(width 0.127)
		(layer "F.Cu")
		(net "MB0_CM_SENSE_N")
	)
	(segment
		(start 120.599454 -12.539472)
		(end 120.121934 -12.061952)
		(width 0.127)
		(layer "F.Cu")
		(net "MB0_CM_SENSE_N")
	)
	(segment
		(start 120.599454 -13.095478)
		(end 120.599454 -12.539472)
		(width 0.127)
		(layer "F.Cu")
		(net "MB0_CM_SENSE_N")
	)
	(segment
		(start 120.015 -14.8844)
		(end 120.015 -15.8623)
		(width 0.127)
		(layer "F.Cu")
		(net "MB0_CM_SENSE_N")
	)
	(segment
		(start 120.121934 -12.061952)
		(end 120.121934 -11.4681)
		(width 0.127)
		(layer "F.Cu")
		(net "MB0_CM_SENSE_N")
	)
	(segment
		(start 119.828564 -14.114272)
		(end 120.1674 -14.453108)
		(width 0.127)
		(layer "F.Cu")
		(net "MB0_CM_SENSE_N")
	)
	(segment
		(start 120.043702 -13.65123)
		(end 120.599454 -13.095478)
		(width 0.127)
		(layer "F.Cu")
		(net "MB0_CM_SENSE_N")
	)
	(segment
		(start 120.1674 -14.732)
		(end 120.015 -14.8844)
		(width 0.127)
		(layer "F.Cu")
		(net "MB0_CM_SENSE_N")
	)
	(segment
		(start 120.1674 -14.453108)
		(end 120.1674 -14.732)
		(width 0.127)
		(layer "F.Cu")
		(net "MB0_CM_SENSE_N")
	)
	(via
		(at 120.1674 -14.732)
		(size 0.6604)
		(drill 0.3302)
		(layers "F.Cu" "B.Cu")
		(net "MB0_CM_SENSE_N")
	)
	(segment
		(start 116.578888 -12.607036)
		(end 116.586 -12.599924)
		(width 0.127)
		(layer "F.Cu")
		(net "MB0_CM_OV_R")
	)
	(segment
		(start 117.12194 -11.91006)
		(end 117.12194 -11.5443)
		(width 0.127)
		(layer "F.Cu")
		(net "MB0_CM_OV_R")
	)
	(segment
		(start 116.586 -12.599924)
		(end 116.586 -12.446)
		(width 0.127)
		(layer "F.Cu")
		(net "MB0_CM_OV_R")
	)
	(segment
		(start 116.586 -12.446)
		(end 117.12194 -11.91006)
		(width 0.127)
		(layer "F.Cu")
		(net "MB0_CM_OV_R")
	)
	(via
		(at 116.578888 -12.607036)
		(size 0.508)
		(drill 0.254)
		(layers "F.Cu" "B.Cu")
		(net "MB0_CM_OV_R")
	)
	(via
		(at 127.968756 -14.395704)
		(size 0.508)
		(drill 0.254)
		(layers "F.Cu" "B.Cu")
		(net "MB0_CM_OV_R")
	)
	(via
		(at 125.857 -15.52321)
		(size 0.6096)
		(drill 0.3048)
		(layers "F.Cu" "B.Cu")
		(net "MB0_CM_OV_R")
	)
	(segment
		(start 126.2634 -14.05001)
		(end 125.984 -14.32941)
		(width 0.127)
		(layer "B.Cu")
		(net "MB0_CM_OV_R")
	)
	(segment
		(start 125.984 -15.3924)
		(end 125.857 -15.5194)
		(width 0.127)
		(layer "B.Cu")
		(net "MB0_CM_OV_R")
	)
	(segment
		(start 127.623062 -14.05001)
		(end 127.968756 -14.395704)
		(width 0.127)
		(layer "B.Cu")
		(net "MB0_CM_OV_R")
	)
	(segment
		(start 125.984 -14.32941)
		(end 125.984 -15.3924)
		(width 0.127)
		(layer "B.Cu")
		(net "MB0_CM_OV_R")
	)
	(segment
		(start 127.104394 -14.05001)
		(end 127.623062 -14.05001)
		(width 0.127)
		(layer "B.Cu")
		(net "MB0_CM_OV_R")
	)
	(segment
		(start 125.857 -15.5194)
		(end 125.857 -15.52321)
		(width 0.127)
		(layer "B.Cu")
		(net "MB0_CM_OV_R")
	)
	(segment
		(start 125.857 -15.52321)
		(end 124.734574 -15.52321)
		(width 0.127)
		(layer "B.Cu")
		(net "MB0_CM_OV_R")
	)
	(segment
		(start 127.104394 -14.05001)
		(end 126.2634 -14.05001)
		(width 0.127)
		(layer "B.Cu")
		(net "MB0_CM_OV_R")
	)
	(segment
		(start 124.734574 -15.52321)
		(end 124.625862 -15.414498)
		(width 0.127)
		(layer "B.Cu")
		(net "MB0_CM_OV_R")
	)
	(segment
		(start 119.737378 -14.234668)
		(end 118.20652 -14.234668)
		(width 0.127)
		(layer "In5.Cu")
		(net "MB0_CM_OV_R")
	)
	(segment
		(start 127.968756 -14.395704)
		(end 127.968502 -14.395958)
		(width 0.127)
		(layer "In5.Cu")
		(net "MB0_CM_OV_R")
	)
	(segment
		(start 119.898668 -14.395958)
		(end 119.737378 -14.234668)
		(width 0.127)
		(layer "In5.Cu")
		(net "MB0_CM_OV_R")
	)
	(segment
		(start 127.968502 -14.395958)
		(end 119.898668 -14.395958)
		(width 0.127)
		(layer "In5.Cu")
		(net "MB0_CM_OV_R")
	)
	(segment
		(start 118.20652 -14.234668)
		(end 116.578888 -12.607036)
		(width 0.127)
		(layer "In5.Cu")
		(net "MB0_CM_OV_R")
	)
	(via
		(at 130.185668 -4.849114)
		(size 0.6604)
		(drill 0.3302)
		(layers "F.Cu" "B.Cu")
		(net "MB0_CM_GATE_R")
	)
	(via
		(at 126.48946 -13.85316)
		(size 0.6604)
		(drill 0.3302)
		(layers "F.Cu" "B.Cu")
		(net "MB0_CM_GATE")
	)
	(segment
		(start 116.3193 -6.5405)
		(end 115.6208 -5.842)
		(width 0.127)
		(layer "F.Cu")
		(net "MB0_CM_ADR2_R")
	)
	(segment
		(start 113.599722 -6.643878)
		(end 114.4016 -5.842)
		(width 0.127)
		(layer "F.Cu")
		(net "MB0_CM_ADR2_R")
	)
	(segment
		(start 115.6208 -5.842)
		(end 114.7572 -5.842)
		(width 0.127)
		(layer "F.Cu")
		(net "MB0_CM_ADR2_R")
	)
	(segment
		(start 114.4016 -5.842)
		(end 114.7572 -5.842)
		(width 0.127)
		(layer "F.Cu")
		(net "MB0_CM_ADR2_R")
	)
	(segment
		(start 113.31829 -6.643878)
		(end 113.599722 -6.643878)
		(width 0.127)
		(layer "F.Cu")
		(net "MB0_CM_ADR2_R")
	)
	(segment
		(start 116.3193 -7.24154)
		(end 116.3193 -6.5405)
		(width 0.127)
		(layer "F.Cu")
		(net "MB0_CM_ADR2_R")
	)
	(via
		(at 114.7572 -5.842)
		(size 0.6604)
		(drill 0.3302)
		(layers "F.Cu" "B.Cu")
		(net "MB0_CM_ADR2_R")
	)
	(segment
		(start 113.31829 -7.736078)
		(end 113.942368 -7.112)
		(width 0.127)
		(layer "F.Cu")
		(net "MB0_CM_ADR1_R")
	)
	(segment
		(start 115.067334 -7.112)
		(end 114.681 -7.112)
		(width 0.127)
		(layer "F.Cu")
		(net "MB0_CM_ADR1_R")
	)
	(segment
		(start 115.697 -7.741666)
		(end 115.067334 -7.112)
		(width 0.127)
		(layer "F.Cu")
		(net "MB0_CM_ADR1_R")
	)
	(segment
		(start 116.3955 -7.741666)
		(end 115.697 -7.741666)
		(width 0.127)
		(layer "F.Cu")
		(net "MB0_CM_ADR1_R")
	)
	(segment
		(start 113.942368 -7.112)
		(end 114.681 -7.112)
		(width 0.127)
		(layer "F.Cu")
		(net "MB0_CM_ADR1_R")
	)
	(via
		(at 114.681 -7.112)
		(size 0.6604)
		(drill 0.3302)
		(layers "F.Cu" "B.Cu")
		(net "MB0_CM_ADR1_R")
	)
	(via
		(at 132.37337 -4.983734)
		(size 0.6604)
		(drill 0.3302)
		(layers "F.Cu" "B.Cu")
		(net "MB0_12V_CTRL_GATE1")
	)
	(segment
		(start 88.6587 -146.8247)
		(end 88.8238 -146.6596)
		(width 0.127)
		(layer "F.Cu")
		(net "IO_EXP0_RESET#_FLT")
	)
	(segment
		(start 89.253314 -146.230086)
		(end 88.8238 -146.6596)
		(width 0.127)
		(layer "F.Cu")
		(net "IO_EXP0_RESET#_FLT")
	)
	(segment
		(start 87.8586 -146.8247)
		(end 88.6587 -146.8247)
		(width 0.127)
		(layer "F.Cu")
		(net "IO_EXP0_RESET#_FLT")
	)
	(segment
		(start 90.357706 -146.230086)
		(end 89.253314 -146.230086)
		(width 0.127)
		(layer "F.Cu")
		(net "IO_EXP0_RESET#_FLT")
	)
	(via
		(at 88.8238 -146.6596)
		(size 0.6604)
		(drill 0.3302)
		(layers "F.Cu" "B.Cu")
		(net "IO_EXP0_RESET#_FLT")
	)
	(segment
		(start 97.240598 -139.077446)
		(end 97.340166 -139.177014)
		(width 0.127)
		(layer "F.Cu")
		(net "DEBUG_RST_BTN_N")
	)
	(segment
		(start 97.340166 -139.177014)
		(end 97.725484 -139.177014)
		(width 0.127)
		(layer "F.Cu")
		(net "DEBUG_RST_BTN_N")
	)
	(segment
		(start 40.899588 -138.199876)
		(end 40.899842 -138.199876)
		(width 0.127)
		(layer "F.Cu")
		(net "DEBUG_RST_BTN_N")
	)
	(segment
		(start 40.500046 -137.800334)
		(end 40.899588 -138.199876)
		(width 0.127)
		(layer "F.Cu")
		(net "DEBUG_RST_BTN_N")
	)
	(segment
		(start 98.227642 -138.674856)
		(end 98.227642 -138.31951)
		(width 0.127)
		(layer "F.Cu")
		(net "DEBUG_RST_BTN_N")
	)
	(segment
		(start 97.725484 -139.177014)
		(end 98.227642 -138.674856)
		(width 0.127)
		(layer "F.Cu")
		(net "DEBUG_RST_BTN_N")
	)
	(segment
		(start 95.996506 -139.077446)
		(end 97.240598 -139.077446)
		(width 0.127)
		(layer "F.Cu")
		(net "DEBUG_RST_BTN_N")
	)
	(via
		(at 37.211 -125.095)
		(size 0.508)
		(drill 0.254)
		(layers "F.Cu" "B.Cu")
		(net "DEBUG_RST_BTN_N")
	)
	(via
		(at 97.725484 -139.177014)
		(size 0.6604)
		(drill 0.3302)
		(layers "F.Cu" "B.Cu")
		(net "DEBUG_RST_BTN_N")
	)
	(via
		(at 54.1274 -120.9802)
		(size 0.508)
		(drill 0.254)
		(layers "F.Cu" "B.Cu")
		(net "DEBUG_RST_BTN_N")
	)
	(via
		(at 94.488 -121.33834)
		(size 0.508)
		(drill 0.254)
		(layers "F.Cu" "B.Cu")
		(net "DEBUG_RST_BTN_N")
	)
	(via
		(at 40.500046 -137.800334)
		(size 0.4572)
		(drill 0.2032)
		(layers "F.Cu" "B.Cu")
		(net "DEBUG_RST_BTN_N")
	)
	(via
		(at 98.227642 -138.31951)
		(size 0.508)
		(drill 0.254)
		(layers "F.Cu" "B.Cu")
		(net "DEBUG_RST_BTN_N")
	)
	(segment
		(start 96.436942 -123.989846)
		(end 98.191828 -125.744732)
		(width 0.127)
		(layer "B.Cu")
		(net "DEBUG_RST_BTN_N")
	)
	(segment
		(start 98.815398 -129.663952)
		(end 98.815398 -137.731754)
		(width 0.127)
		(layer "B.Cu")
		(net "DEBUG_RST_BTN_N")
	)
	(segment
		(start 95.89516 -122.7455)
		(end 95.89516 -123.294394)
		(width 0.127)
		(layer "B.Cu")
		(net "DEBUG_RST_BTN_N")
	)
	(segment
		(start 94.488 -121.33834)
		(end 95.89516 -122.7455)
		(width 0.127)
		(layer "B.Cu")
		(net "DEBUG_RST_BTN_N")
	)
	(segment
		(start 96.436942 -123.836176)
		(end 96.436942 -123.989846)
		(width 0.127)
		(layer "B.Cu")
		(net "DEBUG_RST_BTN_N")
	)
	(segment
		(start 98.191828 -125.744732)
		(end 98.191828 -129.040382)
		(width 0.127)
		(layer "B.Cu")
		(net "DEBUG_RST_BTN_N")
	)
	(segment
		(start 98.191828 -129.040382)
		(end 98.815398 -129.663952)
		(width 0.127)
		(layer "B.Cu")
		(net "DEBUG_RST_BTN_N")
	)
	(segment
		(start 37.1602 -125.9967)
		(end 37.1602 -125.1458)
		(width 0.127)
		(layer "B.Cu")
		(net "DEBUG_RST_BTN_N")
	)
	(segment
		(start 98.815398 -137.731754)
		(end 98.227642 -138.31951)
		(width 0.127)
		(layer "B.Cu")
		(net "DEBUG_RST_BTN_N")
	)
	(segment
		(start 54.777132 -122.804682)
		(end 54.777132 -121.629932)
		(width 0.127)
		(layer "B.Cu")
		(net "DEBUG_RST_BTN_N")
	)
	(segment
		(start 37.1602 -125.1458)
		(end 37.211 -125.095)
		(width 0.127)
		(layer "B.Cu")
		(net "DEBUG_RST_BTN_N")
	)
	(segment
		(start 95.89516 -123.294394)
		(end 96.436942 -123.836176)
		(width 0.127)
		(layer "B.Cu")
		(net "DEBUG_RST_BTN_N")
	)
	(segment
		(start 54.777132 -121.629932)
		(end 54.1274 -120.9802)
		(width 0.127)
		(layer "B.Cu")
		(net "DEBUG_RST_BTN_N")
	)
	(segment
		(start 40.7035 -131.967224)
		(end 40.500046 -132.170678)
		(width 0.127)
		(layer "In2.Cu")
		(net "DEBUG_RST_BTN_N")
	)
	(segment
		(start 39.97706 -129.16662)
		(end 40.7035 -129.89306)
		(width 0.127)
		(layer "In2.Cu")
		(net "DEBUG_RST_BTN_N")
	)
	(segment
		(start 39.97706 -128.040638)
		(end 39.97706 -129.16662)
		(width 0.127)
		(layer "In2.Cu")
		(net "DEBUG_RST_BTN_N")
	)
	(segment
		(start 40.500046 -132.170678)
		(end 40.500046 -137.800334)
		(width 0.127)
		(layer "In2.Cu")
		(net "DEBUG_RST_BTN_N")
	)
	(segment
		(start 40.7035 -129.89306)
		(end 40.7035 -131.967224)
		(width 0.127)
		(layer "In2.Cu")
		(net "DEBUG_RST_BTN_N")
	)
	(segment
		(start 37.211 -125.274578)
		(end 39.97706 -128.040638)
		(width 0.127)
		(layer "In2.Cu")
		(net "DEBUG_RST_BTN_N")
	)
	(segment
		(start 37.211 -125.095)
		(end 37.211 -125.274578)
		(width 0.127)
		(layer "In2.Cu")
		(net "DEBUG_RST_BTN_N")
	)
	(segment
		(start 70.4977 -120.9929)
		(end 71.4502 -120.0404)
		(width 0.127)
		(layer "In5.Cu")
		(net "DEBUG_RST_BTN_N")
	)
	(segment
		(start 55.004462 -120.103138)
		(end 67.972432 -120.103138)
		(width 0.127)
		(layer "In5.Cu")
		(net "DEBUG_RST_BTN_N")
	)
	(segment
		(start 89.2302 -121.9454)
		(end 93.1672 -121.9454)
		(width 0.127)
		(layer "In5.Cu")
		(net "DEBUG_RST_BTN_N")
	)
	(segment
		(start 39.930324 -124.7521)
		(end 37.5539 -124.7521)
		(width 0.127)
		(layer "In5.Cu")
		(net "DEBUG_RST_BTN_N")
	)
	(segment
		(start 67.972432 -120.103138)
		(end 68.862448 -120.9929)
		(width 0.127)
		(layer "In5.Cu")
		(net "DEBUG_RST_BTN_N")
	)
	(segment
		(start 81.9658 -114.681)
		(end 89.2302 -121.9454)
		(width 0.127)
		(layer "In5.Cu")
		(net "DEBUG_RST_BTN_N")
	)
	(segment
		(start 54.1274 -120.9802)
		(end 52.9844 -120.9802)
		(width 0.127)
		(layer "In5.Cu")
		(net "DEBUG_RST_BTN_N")
	)
	(segment
		(start 37.5539 -124.7521)
		(end 37.211 -125.095)
		(width 0.127)
		(layer "In5.Cu")
		(net "DEBUG_RST_BTN_N")
	)
	(segment
		(start 77.94752 -114.681)
		(end 81.9658 -114.681)
		(width 0.127)
		(layer "In5.Cu")
		(net "DEBUG_RST_BTN_N")
	)
	(segment
		(start 50.112422 -124.1679)
		(end 40.515032 -124.1679)
		(width 0.127)
		(layer "In5.Cu")
		(net "DEBUG_RST_BTN_N")
	)
	(segment
		(start 71.4502 -120.0404)
		(end 72.58812 -120.0404)
		(width 0.127)
		(layer "In5.Cu")
		(net "DEBUG_RST_BTN_N")
	)
	(segment
		(start 52.0192 -121.9454)
		(end 52.0192 -122.261122)
		(width 0.127)
		(layer "In5.Cu")
		(net "DEBUG_RST_BTN_N")
	)
	(segment
		(start 72.58812 -120.0404)
		(end 77.94752 -114.681)
		(width 0.127)
		(layer "In5.Cu")
		(net "DEBUG_RST_BTN_N")
	)
	(segment
		(start 52.9844 -120.9802)
		(end 52.0192 -121.9454)
		(width 0.127)
		(layer "In5.Cu")
		(net "DEBUG_RST_BTN_N")
	)
	(segment
		(start 52.0192 -122.261122)
		(end 50.112422 -124.1679)
		(width 0.127)
		(layer "In5.Cu")
		(net "DEBUG_RST_BTN_N")
	)
	(segment
		(start 93.77426 -121.33834)
		(end 94.488 -121.33834)
		(width 0.127)
		(layer "In5.Cu")
		(net "DEBUG_RST_BTN_N")
	)
	(segment
		(start 93.1672 -121.9454)
		(end 93.77426 -121.33834)
		(width 0.127)
		(layer "In5.Cu")
		(net "DEBUG_RST_BTN_N")
	)
	(segment
		(start 68.862448 -120.9929)
		(end 70.4977 -120.9929)
		(width 0.127)
		(layer "In5.Cu")
		(net "DEBUG_RST_BTN_N")
	)
	(segment
		(start 54.1274 -120.9802)
		(end 55.004462 -120.103138)
		(width 0.127)
		(layer "In5.Cu")
		(net "DEBUG_RST_BTN_N")
	)
	(segment
		(start 40.515032 -124.1679)
		(end 39.930324 -124.7521)
		(width 0.127)
		(layer "In5.Cu")
		(net "DEBUG_RST_BTN_N")
	)
	(segment
		(start 125.307344 -9.628378)
		(end 125.307344 -9.996932)
		(width 0.254)
		(layer "F.Cu")
		(net "AGND_CURRENT_MON")
	)
	(segment
		(start 125.307344 -9.996932)
		(end 125.99289 -10.682478)
		(width 0.254)
		(layer "F.Cu")
		(net "AGND_CURRENT_MON")
	)
	(segment
		(start 125.99289 -10.682478)
		(end 125.99289 -11.79449)
		(width 0.254)
		(layer "F.Cu")
		(net "AGND_CURRENT_MON")
	)
	(segment
		(start 119.888 -9.017)
		(end 120.612662 -9.741662)
		(width 0.254)
		(layer "F.Cu")
		(net "AGND_CURRENT_MON")
	)
	(segment
		(start 120.612662 -9.741662)
		(end 121.3485 -9.741662)
		(width 0.254)
		(layer "F.Cu")
		(net "AGND_CURRENT_MON")
	)
	(via
		(at 111.582708 -8.64616)
		(size 0.508)
		(drill 0.254)
		(layers "F.Cu" "B.Cu")
		(net "AGND_CURRENT_MON")
	)
	(via
		(at 118.872 -10.033)
		(size 0.5588)
		(drill 0.3048)
		(layers "F.Cu" "B.Cu")
		(net "AGND_CURRENT_MON")
	)
	(via
		(at 117.856 -9.017)
		(size 0.5588)
		(drill 0.3048)
		(layers "F.Cu" "B.Cu")
		(net "AGND_CURRENT_MON")
	)
	(via
		(at 119.888 -9.017)
		(size 0.5588)
		(drill 0.3048)
		(layers "F.Cu" "B.Cu")
		(net "AGND_CURRENT_MON")
	)
	(via
		(at 129.0574 -12.7254)
		(size 0.6096)
		(drill 0.3048)
		(layers "F.Cu" "B.Cu")
		(net "AGND_CURRENT_MON")
	)
	(via
		(at 125.99289 -11.79449)
		(size 0.508)
		(drill 0.254)
		(layers "F.Cu" "B.Cu")
		(net "AGND_CURRENT_MON")
	)
	(via
		(at 111.5568 -5.6134)
		(size 0.508)
		(drill 0.254)
		(layers "F.Cu" "B.Cu")
		(net "AGND_CURRENT_MON")
	)
	(via
		(at 118.872 -8.9916)
		(size 0.5588)
		(drill 0.3048)
		(layers "F.Cu" "B.Cu")
		(net "AGND_CURRENT_MON")
	)
	(via
		(at 111.646716 -7.728966)
		(size 0.508)
		(drill 0.254)
		(layers "F.Cu" "B.Cu")
		(net "AGND_CURRENT_MON")
	)
	(via
		(at 111.645446 -6.690106)
		(size 0.508)
		(drill 0.254)
		(layers "F.Cu" "B.Cu")
		(net "AGND_CURRENT_MON")
	)
	(via
		(at 118.872 -8.001)
		(size 0.5588)
		(drill 0.3048)
		(layers "F.Cu" "B.Cu")
		(net "AGND_CURRENT_MON")
	)
	(segment
		(start 111.96955 -8.0518)
		(end 111.646716 -7.728966)
		(width 0.508)
		(layer "B.Cu")
		(net "AGND_CURRENT_MON")
	)
	(segment
		(start 113.2586 -8.0518)
		(end 111.96955 -8.0518)
		(width 0.508)
		(layer "B.Cu")
		(net "AGND_CURRENT_MON")
	)
	(segment
		(start 119.121936 -12.466828)
		(end 119.121936 -11.4681)
		(width 0.254)
		(layer "F.Cu")
		(net "ADM1278_HS_P")
	)
	(segment
		(start 131.8514 -14.6304)
		(end 131.52755 -14.30655)
		(width 0.254)
		(layer "F.Cu")
		(net "ADM1278_HS_P")
	)
	(segment
		(start 119.140732 -12.485624)
		(end 119.121936 -12.466828)
		(width 0.254)
		(layer "F.Cu")
		(net "ADM1278_HS_P")
	)
	(segment
		(start 131.52755 -13.968476)
		(end 131.945126 -13.5509)
		(width 0.254)
		(layer "F.Cu")
		(net "ADM1278_HS_P")
	)
	(segment
		(start 132.3848 -14.6304)
		(end 131.8514 -14.6304)
		(width 0.254)
		(layer "F.Cu")
		(net "ADM1278_HS_P")
	)
	(segment
		(start 131.52755 -14.30655)
		(end 131.52755 -13.968476)
		(width 0.254)
		(layer "F.Cu")
		(net "ADM1278_HS_P")
	)
	(segment
		(start 131.945126 -13.5509)
		(end 132.5372 -13.5509)
		(width 0.254)
		(layer "F.Cu")
		(net "ADM1278_HS_P")
	)
	(segment
		(start 133.4643 -13.6144)
		(end 132.6007 -13.6144)
		(width 0.254)
		(layer "F.Cu")
		(net "ADM1278_HS_P")
	)
	(segment
		(start 132.6007 -13.6144)
		(end 132.5372 -13.5509)
		(width 0.254)
		(layer "F.Cu")
		(net "ADM1278_HS_P")
	)
	(via
		(at 119.140732 -12.485624)
		(size 0.508)
		(drill 0.254)
		(layers "F.Cu" "B.Cu")
		(net "ADM1278_HS_P")
	)
	(via
		(at 132.3848 -14.6304)
		(size 0.508)
		(drill 0.254)
		(layers "F.Cu" "B.Cu")
		(net "ADM1278_HS_P")
	)
	(via
		(at 131.52755 -13.968476)
		(size 0.6604)
		(drill 0.3302)
		(layers "F.Cu" "B.Cu")
		(net "ADM1278_HS_P")
	)
	(segment
		(start 122.253502 -11.794998)
		(end 122.794268 -12.335764)
		(width 0.254)
		(layer "In5.Cu")
		(net "ADM1278_HS_P")
	)
	(segment
		(start 129.087118 -12.335764)
		(end 129.43586 -11.987022)
		(width 0.254)
		(layer "In5.Cu")
		(net "ADM1278_HS_P")
	)
	(segment
		(start 119.831358 -11.794998)
		(end 122.253502 -11.794998)
		(width 0.254)
		(layer "In5.Cu")
		(net "ADM1278_HS_P")
	)
	(segment
		(start 129.43586 -11.987022)
		(end 131.044442 -11.987022)
		(width 0.254)
		(layer "In5.Cu")
		(net "ADM1278_HS_P")
	)
	(segment
		(start 119.140732 -12.485624)
		(end 119.831358 -11.794998)
		(width 0.254)
		(layer "In5.Cu")
		(net "ADM1278_HS_P")
	)
	(segment
		(start 132.3848 -13.32738)
		(end 132.3848 -14.6304)
		(width 0.254)
		(layer "In5.Cu")
		(net "ADM1278_HS_P")
	)
	(segment
		(start 131.044442 -11.987022)
		(end 132.3848 -13.32738)
		(width 0.254)
		(layer "In5.Cu")
		(net "ADM1278_HS_P")
	)
	(segment
		(start 122.794268 -12.335764)
		(end 129.087118 -12.335764)
		(width 0.254)
		(layer "In5.Cu")
		(net "ADM1278_HS_P")
	)
	(segment
		(start 133.35 -12.6619)
		(end 133.4643 -12.5476)
		(width 0.254)
		(layer "F.Cu")
		(net "ADM1278_HS_N")
	)
	(segment
		(start 132.5372 -12.6619)
		(end 133.35 -12.6619)
		(width 0.254)
		(layer "F.Cu")
		(net "ADM1278_HS_N")
	)
	(segment
		(start 119.622062 -12.230862)
		(end 119.622062 -11.4681)
		(width 0.254)
		(layer "F.Cu")
		(net "ADM1278_HS_N")
	)
	(segment
		(start 131.2672 -12.6619)
		(end 131.2164 -12.6111)
		(width 0.254)
		(layer "F.Cu")
		(net "ADM1278_HS_N")
	)
	(segment
		(start 130.252724 -12.571476)
		(end 130.292348 -12.6111)
		(width 0.254)
		(layer "F.Cu")
		(net "ADM1278_HS_N")
	)
	(segment
		(start 120.104408 -12.713208)
		(end 119.622062 -12.230862)
		(width 0.254)
		(layer "F.Cu")
		(net "ADM1278_HS_N")
	)
	(segment
		(start 120.180354 -12.713208)
		(end 120.104408 -12.713208)
		(width 0.254)
		(layer "F.Cu")
		(net "ADM1278_HS_N")
	)
	(segment
		(start 132.5372 -12.6619)
		(end 131.2672 -12.6619)
		(width 0.254)
		(layer "F.Cu")
		(net "ADM1278_HS_N")
	)
	(segment
		(start 130.292348 -12.6111)
		(end 131.2164 -12.6111)
		(width 0.254)
		(layer "F.Cu")
		(net "ADM1278_HS_N")
	)
	(via
		(at 131.2164 -12.6111)
		(size 0.6604)
		(drill 0.3302)
		(layers "F.Cu" "B.Cu")
		(net "ADM1278_HS_N")
	)
	(via
		(at 120.180354 -12.713208)
		(size 0.508)
		(drill 0.254)
		(layers "F.Cu" "B.Cu")
		(net "ADM1278_HS_N")
	)
	(via
		(at 130.252724 -12.571476)
		(size 0.508)
		(drill 0.254)
		(layers "F.Cu" "B.Cu")
		(net "ADM1278_HS_N")
	)
	(segment
		(start 129.82702 -12.99718)
		(end 120.464326 -12.99718)
		(width 0.254)
		(layer "In5.Cu")
		(net "ADM1278_HS_N")
	)
	(segment
		(start 130.252724 -12.571476)
		(end 129.82702 -12.99718)
		(width 0.254)
		(layer "In5.Cu")
		(net "ADM1278_HS_N")
	)
	(segment
		(start 120.464326 -12.99718)
		(end 120.180354 -12.713208)
		(width 0.254)
		(layer "In5.Cu")
		(net "ADM1278_HS_N")
	)
	(segment
		(start 97.005648 -159.231076)
		(end 97.00133 -159.226758)
		(width 0.127)
		(layer "F.Cu")
		(net "VBUS_DET")
	)
	(segment
		(start 95.710756 -158.372556)
		(end 95.710756 -157.605476)
		(width 0.127)
		(layer "F.Cu")
		(net "VBUS_DET")
	)
	(segment
		(start 97.00133 -159.226758)
		(end 96.564958 -159.226758)
		(width 0.127)
		(layer "F.Cu")
		(net "VBUS_DET")
	)
	(segment
		(start 96.564958 -159.226758)
		(end 95.710756 -158.372556)
		(width 0.127)
		(layer "F.Cu")
		(net "VBUS_DET")
	)
	(segment
		(start 97.324672 -159.231076)
		(end 97.62617 -159.532574)
		(width 0.127)
		(layer "F.Cu")
		(net "VBUS_DET")
	)
	(segment
		(start 97.62617 -159.532574)
		(end 98.434144 -159.532574)
		(width 0.127)
		(layer "F.Cu")
		(net "VBUS_DET")
	)
	(segment
		(start 97.324672 -159.231076)
		(end 97.005648 -159.231076)
		(width 0.127)
		(layer "F.Cu")
		(net "VBUS_DET")
	)
	(via
		(at 97.324672 -159.231076)
		(size 0.6604)
		(drill 0.3302)
		(layers "F.Cu" "B.Cu")
		(net "VBUS_DET")
	)
	(segment
		(start 96.40697 -159.607758)
		(end 95.363792 -158.56458)
		(width 0.127)
		(layer "F.Cu")
		(net "USB_SUSP_IND")
	)
	(segment
		(start 97.662492 -160.426908)
		(end 96.843342 -159.607758)
		(width 0.127)
		(layer "F.Cu")
		(net "USB_SUSP_IND")
	)
	(segment
		(start 95.363792 -158.56458)
		(end 94.751652 -158.56458)
		(width 0.127)
		(layer "F.Cu")
		(net "USB_SUSP_IND")
	)
	(segment
		(start 98.6282 -161.683192)
		(end 98.425 -161.886392)
		(width 0.127)
		(layer "F.Cu")
		(net "USB_SUSP_IND")
	)
	(segment
		(start 98.6282 -160.7058)
		(end 98.349308 -160.426908)
		(width 0.127)
		(layer "F.Cu")
		(net "USB_SUSP_IND")
	)
	(segment
		(start 96.843342 -159.607758)
		(end 96.40697 -159.607758)
		(width 0.127)
		(layer "F.Cu")
		(net "USB_SUSP_IND")
	)
	(segment
		(start 98.349308 -160.426908)
		(end 97.662492 -160.426908)
		(width 0.127)
		(layer "F.Cu")
		(net "USB_SUSP_IND")
	)
	(segment
		(start 98.6282 -160.7058)
		(end 98.6282 -161.683192)
		(width 0.127)
		(layer "F.Cu")
		(net "USB_SUSP_IND")
	)
	(via
		(at 98.6282 -160.7058)
		(size 0.6604)
		(drill 0.3302)
		(layers "F.Cu" "B.Cu")
		(net "USB_SUSP_IND")
	)
	(segment
		(start 98.483674 -158.441644)
		(end 97.489518 -158.441644)
		(width 0.127)
		(layer "F.Cu")
		(net "USB_RESET_N")
	)
	(segment
		(start 96.430592 -157.105604)
		(end 95.621856 -157.105604)
		(width 0.127)
		(layer "F.Cu")
		(net "USB_RESET_N")
	)
	(segment
		(start 96.687132 -158.078678)
		(end 96.687132 -157.362144)
		(width 0.127)
		(layer "F.Cu")
		(net "USB_RESET_N")
	)
	(segment
		(start 97.332546 -158.284672)
		(end 96.893126 -158.284672)
		(width 0.127)
		(layer "F.Cu")
		(net "USB_RESET_N")
	)
	(segment
		(start 96.687132 -157.362144)
		(end 96.430592 -157.105604)
		(width 0.127)
		(layer "F.Cu")
		(net "USB_RESET_N")
	)
	(segment
		(start 96.893126 -158.284672)
		(end 96.687132 -158.078678)
		(width 0.127)
		(layer "F.Cu")
		(net "USB_RESET_N")
	)
	(segment
		(start 97.489518 -158.441644)
		(end 97.332546 -158.284672)
		(width 0.127)
		(layer "F.Cu")
		(net "USB_RESET_N")
	)
	(via
		(at 96.2152 -158.7119)
		(size 0.6096)
		(drill 0.3048)
		(layers "F.Cu" "B.Cu")
		(net "USB_RESET_N")
	)
	(via
		(at 97.332546 -158.284672)
		(size 0.508)
		(drill 0.254)
		(layers "F.Cu" "B.Cu")
		(net "USB_RESET_N")
	)
	(segment
		(start 95.431864 -158.7119)
		(end 95.131636 -159.012128)
		(width 0.127)
		(layer "B.Cu")
		(net "USB_RESET_N")
	)
	(segment
		(start 97.296478 -158.32074)
		(end 97.296478 -158.759398)
		(width 0.127)
		(layer "B.Cu")
		(net "USB_RESET_N")
	)
	(segment
		(start 97.296478 -158.759398)
		(end 96.269556 -159.78632)
		(width 0.127)
		(layer "B.Cu")
		(net "USB_RESET_N")
	)
	(segment
		(start 96.269556 -159.78632)
		(end 96.218756 -159.78632)
		(width 0.127)
		(layer "B.Cu")
		(net "USB_RESET_N")
	)
	(segment
		(start 96.218756 -158.715456)
		(end 96.218756 -159.78632)
		(width 0.127)
		(layer "B.Cu")
		(net "USB_RESET_N")
	)
	(segment
		(start 96.2152 -158.7119)
		(end 96.218756 -158.715456)
		(width 0.127)
		(layer "B.Cu")
		(net "USB_RESET_N")
	)
	(segment
		(start 97.332546 -158.284672)
		(end 97.296478 -158.32074)
		(width 0.127)
		(layer "B.Cu")
		(net "USB_RESET_N")
	)
	(segment
		(start 96.2152 -158.7119)
		(end 95.431864 -158.7119)
		(width 0.127)
		(layer "B.Cu")
		(net "USB_RESET_N")
	)
	(segment
		(start 97.350834 -153.67)
		(end 96.415352 -154.605482)
		(width 0.127)
		(layer "F.Cu")
		(net "USB_OCS_N4")
	)
	(segment
		(start 98.087434 -152.9334)
		(end 97.350834 -153.67)
		(width 0.127)
		(layer "F.Cu")
		(net "USB_OCS_N4")
	)
	(segment
		(start 98.4631 -152.9334)
		(end 98.087434 -152.9334)
		(width 0.127)
		(layer "F.Cu")
		(net "USB_OCS_N4")
	)
	(segment
		(start 96.415352 -154.605482)
		(end 95.621856 -154.605482)
		(width 0.127)
		(layer "F.Cu")
		(net "USB_OCS_N4")
	)
	(via
		(at 97.350834 -153.67)
		(size 0.6604)
		(drill 0.3302)
		(layers "F.Cu" "B.Cu")
		(net "USB_OCS_N4")
	)
	(segment
		(start 97.660968 -149.733)
		(end 97.439988 -149.95398)
		(width 0.127)
		(layer "F.Cu")
		(net "USB_OCS_N3")
	)
	(segment
		(start 96.481392 -150.912576)
		(end 96.481392 -151.852376)
		(width 0.127)
		(layer "F.Cu")
		(net "USB_OCS_N3")
	)
	(segment
		(start 97.439988 -149.95398)
		(end 96.481392 -150.912576)
		(width 0.127)
		(layer "F.Cu")
		(net "USB_OCS_N3")
	)
	(segment
		(start 95.710756 -152.623012)
		(end 95.710756 -153.605484)
		(width 0.127)
		(layer "F.Cu")
		(net "USB_OCS_N3")
	)
	(segment
		(start 96.481392 -151.852376)
		(end 95.710756 -152.623012)
		(width 0.127)
		(layer "F.Cu")
		(net "USB_OCS_N3")
	)
	(segment
		(start 98.4377 -149.751034)
		(end 97.660968 -149.733)
		(width 0.127)
		(layer "F.Cu")
		(net "USB_OCS_N3")
	)
	(via
		(at 97.439988 -149.95398)
		(size 0.6604)
		(drill 0.3302)
		(layers "F.Cu" "B.Cu")
		(net "USB_OCS_N3")
	)
	(segment
		(start 96.669098 -149.052026)
		(end 96.224852 -149.052026)
		(width 0.127)
		(layer "F.Cu")
		(net "USB_OCS_N2")
	)
	(segment
		(start 94.25178 -151.97582)
		(end 94.25178 -152.73528)
		(width 0.127)
		(layer "F.Cu")
		(net "USB_OCS_N2")
	)
	(segment
		(start 95.445834 -149.831044)
		(end 95.445834 -150.046436)
		(width 0.127)
		(layer "F.Cu")
		(net "USB_OCS_N2")
	)
	(segment
		(start 95.445834 -150.781766)
		(end 94.25178 -151.97582)
		(width 0.127)
		(layer "F.Cu")
		(net "USB_OCS_N2")
	)
	(segment
		(start 96.224852 -149.052026)
		(end 95.445834 -149.831044)
		(width 0.127)
		(layer "F.Cu")
		(net "USB_OCS_N2")
	)
	(segment
		(start 95.445834 -150.046436)
		(end 95.445834 -150.781766)
		(width 0.127)
		(layer "F.Cu")
		(net "USB_OCS_N2")
	)
	(segment
		(start 97.1677 -148.553424)
		(end 96.669098 -149.052026)
		(width 0.127)
		(layer "F.Cu")
		(net "USB_OCS_N2")
	)
	(via
		(at 95.445834 -150.046436)
		(size 0.6604)
		(drill 0.3302)
		(layers "F.Cu" "B.Cu")
		(net "USB_OCS_N2")
	)
	(segment
		(start 93.132656 -162.51428)
		(end 93.132656 -162.978846)
		(width 0.127)
		(layer "F.Cu")
		(net "USB_HUB_XTAL_OUT")
	)
	(segment
		(start 92.865956 -163.245546)
		(end 92.865956 -165.258496)
		(width 0.127)
		(layer "F.Cu")
		(net "USB_HUB_XTAL_OUT")
	)
	(segment
		(start 93.132656 -162.978846)
		(end 92.865956 -163.245546)
		(width 0.127)
		(layer "F.Cu")
		(net "USB_HUB_XTAL_OUT")
	)
	(segment
		(start 93.132148 -162.513772)
		(end 93.132656 -162.51428)
		(width 0.127)
		(layer "F.Cu")
		(net "USB_HUB_XTAL_OUT")
	)
	(segment
		(start 93.132148 -161.662872)
		(end 93.132148 -162.513772)
		(width 0.127)
		(layer "F.Cu")
		(net "USB_HUB_XTAL_OUT")
	)
	(segment
		(start 92.751656 -160.722056)
		(end 92.992956 -160.963356)
		(width 0.127)
		(layer "F.Cu")
		(net "USB_HUB_XTAL_OUT")
	)
	(segment
		(start 92.751656 -158.47568)
		(end 92.751656 -160.722056)
		(width 0.127)
		(layer "F.Cu")
		(net "USB_HUB_XTAL_OUT")
	)
	(segment
		(start 92.992956 -160.963356)
		(end 92.992956 -161.52368)
		(width 0.127)
		(layer "F.Cu")
		(net "USB_HUB_XTAL_OUT")
	)
	(segment
		(start 92.992956 -161.52368)
		(end 93.132148 -161.662872)
		(width 0.127)
		(layer "F.Cu")
		(net "USB_HUB_XTAL_OUT")
	)
	(segment
		(start 92.865956 -165.258496)
		(end 93.171518 -165.564058)
		(width 0.127)
		(layer "F.Cu")
		(net "USB_HUB_XTAL_OUT")
	)
	(segment
		(start 93.171518 -165.564058)
		(end 93.795342 -165.564058)
		(width 0.127)
		(layer "F.Cu")
		(net "USB_HUB_XTAL_OUT")
	)
	(segment
		(start 92.103956 -161.52368)
		(end 92.103956 -162.509708)
		(width 0.127)
		(layer "F.Cu")
		(net "USB_HUB_XTAL_IN")
	)
	(segment
		(start 92.103956 -161.3154)
		(end 92.103956 -161.52368)
		(width 0.127)
		(layer "F.Cu")
		(net "USB_HUB_XTAL_IN")
	)
	(segment
		(start 92.103956 -162.509708)
		(end 92.084144 -162.52952)
		(width 0.127)
		(layer "F.Cu")
		(net "USB_HUB_XTAL_IN")
	)
	(segment
		(start 92.25153 -158.47568)
		(end 92.25153 -161.167826)
		(width 0.127)
		(layer "F.Cu")
		(net "USB_HUB_XTAL_IN")
	)
	(segment
		(start 92.084144 -162.52952)
		(end 92.084144 -163.419536)
		(width 0.127)
		(layer "F.Cu")
		(net "USB_HUB_XTAL_IN")
	)
	(segment
		(start 92.084144 -163.419536)
		(end 91.452446 -164.051234)
		(width 0.127)
		(layer "F.Cu")
		(net "USB_HUB_XTAL_IN")
	)
	(segment
		(start 92.25153 -161.167826)
		(end 92.103956 -161.3154)
		(width 0.127)
		(layer "F.Cu")
		(net "USB_HUB_XTAL_IN")
	)
	(segment
		(start 99.576382 -151.01316)
		(end 99.601782 -150.98776)
		(width 0.127)
		(layer "F.Cu")
		(net "USB_EN_4")
	)
	(segment
		(start 96.184466 -154.105356)
		(end 95.621856 -154.105356)
		(width 0.127)
		(layer "F.Cu")
		(net "USB_EN_4")
	)
	(segment
		(start 96.937576 -151.54402)
		(end 96.937576 -151.998172)
		(width 0.127)
		(layer "F.Cu")
		(net "USB_EN_4")
	)
	(segment
		(start 96.677734 -153.612088)
		(end 96.184466 -154.105356)
		(width 0.127)
		(layer "F.Cu")
		(net "USB_EN_4")
	)
	(segment
		(start 97.468436 -151.01316)
		(end 97.314258 -151.167338)
		(width 0.127)
		(layer "F.Cu")
		(net "USB_EN_4")
	)
	(segment
		(start 97.314258 -151.167338)
		(end 96.937576 -151.54402)
		(width 0.127)
		(layer "F.Cu")
		(net "USB_EN_4")
	)
	(segment
		(start 96.677734 -152.258014)
		(end 96.677734 -153.612088)
		(width 0.127)
		(layer "F.Cu")
		(net "USB_EN_4")
	)
	(segment
		(start 96.937576 -151.998172)
		(end 96.677734 -152.258014)
		(width 0.127)
		(layer "F.Cu")
		(net "USB_EN_4")
	)
	(segment
		(start 98.484182 -151.01316)
		(end 97.468436 -151.01316)
		(width 0.127)
		(layer "F.Cu")
		(net "USB_EN_4")
	)
	(segment
		(start 98.484182 -151.01316)
		(end 99.576382 -151.01316)
		(width 0.127)
		(layer "F.Cu")
		(net "USB_EN_4")
	)
	(via
		(at 97.314258 -151.167338)
		(size 0.6604)
		(drill 0.3302)
		(layers "F.Cu" "B.Cu")
		(net "USB_EN_4")
	)
	(segment
		(start 95.9358 -151.7904)
		(end 95.07982 -152.64638)
		(width 0.127)
		(layer "F.Cu")
		(net "USB_EN_3")
	)
	(segment
		(start 95.07982 -152.64638)
		(end 94.751652 -152.64638)
		(width 0.127)
		(layer "F.Cu")
		(net "USB_EN_3")
	)
	(segment
		(start 95.9358 -151.13)
		(end 95.9358 -151.7904)
		(width 0.127)
		(layer "F.Cu")
		(net "USB_EN_3")
	)
	(segment
		(start 96.4184 -149.630892)
		(end 96.425512 -149.62378)
		(width 0.127)
		(layer "F.Cu")
		(net "USB_EN_3")
	)
	(segment
		(start 97.2058 -149.1488)
		(end 97.757488 -149.1488)
		(width 0.127)
		(layer "F.Cu")
		(net "USB_EN_3")
	)
	(segment
		(start 96.425512 -149.62378)
		(end 96.73082 -149.62378)
		(width 0.127)
		(layer "F.Cu")
		(net "USB_EN_3")
	)
	(segment
		(start 95.9358 -151.13)
		(end 95.9358 -150.62962)
		(width 0.127)
		(layer "F.Cu")
		(net "USB_EN_3")
	)
	(segment
		(start 97.757488 -149.1488)
		(end 98.178366 -148.727922)
		(width 0.127)
		(layer "F.Cu")
		(net "USB_EN_3")
	)
	(segment
		(start 96.73082 -149.62378)
		(end 97.2058 -149.1488)
		(width 0.127)
		(layer "F.Cu")
		(net "USB_EN_3")
	)
	(segment
		(start 95.9358 -150.62962)
		(end 96.4184 -150.14702)
		(width 0.127)
		(layer "F.Cu")
		(net "USB_EN_3")
	)
	(segment
		(start 96.4184 -150.14702)
		(end 96.4184 -149.630892)
		(width 0.127)
		(layer "F.Cu")
		(net "USB_EN_3")
	)
	(via
		(at 96.425512 -149.62378)
		(size 0.6604)
		(drill 0.3302)
		(layers "F.Cu" "B.Cu")
		(net "USB_EN_3")
	)
	(via
		(at 95.9358 -151.13)
		(size 0.508)
		(drill 0.254)
		(layers "F.Cu" "B.Cu")
		(net "USB_EN_3")
	)
	(segment
		(start 96.52 -151.9809)
		(end 96.52 -151.7142)
		(width 0.127)
		(layer "B.Cu")
		(net "USB_EN_3")
	)
	(segment
		(start 96.52 -151.7142)
		(end 95.9358 -151.13)
		(width 0.127)
		(layer "B.Cu")
		(net "USB_EN_3")
	)
	(segment
		(start 95.576644 -148.553424)
		(end 95.070168 -149.0599)
		(width 0.127)
		(layer "F.Cu")
		(net "USB_EN_2")
	)
	(segment
		(start 94.6658 -150.7744)
		(end 94.6912 -150.749)
		(width 0.127)
		(layer "F.Cu")
		(net "USB_EN_2")
	)
	(segment
		(start 94.6912 -149.438868)
		(end 95.070168 -149.0599)
		(width 0.127)
		(layer "F.Cu")
		(net "USB_EN_2")
	)
	(segment
		(start 94.6658 -150.7744)
		(end 93.751654 -151.688546)
		(width 0.127)
		(layer "F.Cu")
		(net "USB_EN_2")
	)
	(segment
		(start 93.751654 -151.688546)
		(end 93.751654 -152.73528)
		(width 0.127)
		(layer "F.Cu")
		(net "USB_EN_2")
	)
	(segment
		(start 94.6912 -150.749)
		(end 94.6912 -149.438868)
		(width 0.127)
		(layer "F.Cu")
		(net "USB_EN_2")
	)
	(segment
		(start 96.1009 -148.553424)
		(end 95.576644 -148.553424)
		(width 0.127)
		(layer "F.Cu")
		(net "USB_EN_2")
	)
	(via
		(at 94.6658 -150.7744)
		(size 0.6604)
		(drill 0.3302)
		(layers "F.Cu" "B.Cu")
		(net "USB_EN_2")
	)
	(segment
		(start 91.751658 -151.371046)
		(end 91.751658 -152.73528)
		(width 0.127)
		(layer "F.Cu")
		(net "USB_EN_1")
	)
	(segment
		(start 90.2716 -150.7236)
		(end 90.6526 -151.1046)
		(width 0.127)
		(layer "F.Cu")
		(net "USB_EN_1")
	)
	(segment
		(start 89.52992 -149.761956)
		(end 89.78519 -149.761956)
		(width 0.127)
		(layer "F.Cu")
		(net "USB_EN_1")
	)
	(segment
		(start 84.840318 -69.2023)
		(end 86.603078 -70.96506)
		(width 0.127)
		(layer "F.Cu")
		(net "USB_EN_1")
	)
	(segment
		(start 87.004906 -30.57398)
		(end 87.022686 -30.59176)
		(width 0.127)
		(layer "F.Cu")
		(net "USB_EN_1")
	)
	(segment
		(start 87.0204 -98.588068)
		(end 87.561928 -99.129596)
		(width 0.127)
		(layer "F.Cu")
		(net "USB_EN_1")
	)
	(segment
		(start 88.553544 -149.761956)
		(end 87.960962 -150.354538)
		(width 0.127)
		(layer "F.Cu")
		(net "USB_EN_1")
	)
	(segment
		(start 86.603078 -70.96506)
		(end 86.603078 -71.254366)
		(width 0.127)
		(layer "F.Cu")
		(net "USB_EN_1")
	)
	(segment
		(start 91.485212 -151.1046)
		(end 91.751658 -151.371046)
		(width 0.127)
		(layer "F.Cu")
		(net "USB_EN_1")
	)
	(segment
		(start 87.0204 -71.671688)
		(end 87.0204 -98.588068)
		(width 0.127)
		(layer "F.Cu")
		(net "USB_EN_1")
	)
	(segment
		(start 84.840318 -69.088)
		(end 84.840318 -69.2023)
		(width 0.127)
		(layer "F.Cu")
		(net "USB_EN_1")
	)
	(segment
		(start 87.022686 -30.59176)
		(end 89.281 -30.59176)
		(width 0.127)
		(layer "F.Cu")
		(net "USB_EN_1")
	)
	(segment
		(start 90.6526 -151.1046)
		(end 91.485212 -151.1046)
		(width 0.127)
		(layer "F.Cu")
		(net "USB_EN_1")
	)
	(segment
		(start 89.78519 -149.761956)
		(end 90.2716 -150.248366)
		(width 0.127)
		(layer "F.Cu")
		(net "USB_EN_1")
	)
	(segment
		(start 89.52992 -149.761956)
		(end 88.553544 -149.761956)
		(width 0.127)
		(layer "F.Cu")
		(net "USB_EN_1")
	)
	(segment
		(start 90.2716 -150.248366)
		(end 90.2716 -150.7236)
		(width 0.127)
		(layer "F.Cu")
		(net "USB_EN_1")
	)
	(segment
		(start 86.603078 -71.254366)
		(end 87.0204 -71.671688)
		(width 0.127)
		(layer "F.Cu")
		(net "USB_EN_1")
	)
	(via
		(at 87.960962 -150.354538)
		(size 0.508)
		(drill 0.254)
		(layers "F.Cu" "B.Cu")
		(net "USB_EN_1")
	)
	(via
		(at 86.0552 -110.5154)
		(size 0.508)
		(drill 0.254)
		(layers "F.Cu" "B.Cu")
		(net "USB_EN_1")
	)
	(via
		(at 90.2716 -150.7236)
		(size 0.6604)
		(drill 0.3302)
		(layers "F.Cu" "B.Cu")
		(net "USB_EN_1")
	)
	(via
		(at 84.840318 -69.088)
		(size 0.508)
		(drill 0.254)
		(layers "F.Cu" "B.Cu")
		(net "USB_EN_1")
	)
	(via
		(at 87.561928 -99.129596)
		(size 0.508)
		(drill 0.254)
		(layers "F.Cu" "B.Cu")
		(net "USB_EN_1")
	)
	(via
		(at 89.024714 -115.267486)
		(size 0.508)
		(drill 0.254)
		(layers "F.Cu" "B.Cu")
		(net "USB_EN_1")
	)
	(via
		(at 87.004906 -30.57398)
		(size 0.508)
		(drill 0.254)
		(layers "F.Cu" "B.Cu")
		(net "USB_EN_1")
	)
	(segment
		(start 87.561928 -99.129596)
		(end 87.0966 -99.594924)
		(width 0.127)
		(layer "B.Cu")
		(net "USB_EN_1")
	)
	(segment
		(start 87.0966 -99.846638)
		(end 87.092028 -99.85121)
		(width 0.127)
		(layer "B.Cu")
		(net "USB_EN_1")
	)
	(segment
		(start 87.092028 -100.240846)
		(end 87.0966 -100.245418)
		(width 0.127)
		(layer "B.Cu")
		(net "USB_EN_1")
	)
	(segment
		(start 87.0966 -99.594924)
		(end 87.0966 -99.846638)
		(width 0.127)
		(layer "B.Cu")
		(net "USB_EN_1")
	)
	(segment
		(start 87.0966 -108.730796)
		(end 86.0552 -109.772196)
		(width 0.127)
		(layer "B.Cu")
		(net "USB_EN_1")
	)
	(segment
		(start 86.0552 -109.772196)
		(end 86.0552 -110.5154)
		(width 0.127)
		(layer "B.Cu")
		(net "USB_EN_1")
	)
	(segment
		(start 87.0966 -100.245418)
		(end 87.0966 -108.730796)
		(width 0.127)
		(layer "B.Cu")
		(net "USB_EN_1")
	)
	(segment
		(start 87.092028 -99.85121)
		(end 87.092028 -100.240846)
		(width 0.127)
		(layer "B.Cu")
		(net "USB_EN_1")
	)
	(segment
		(start 87.960962 -150.354538)
		(end 88.553544 -149.761956)
		(width 0.127)
		(layer "B.Cu")
		(net "USB_EN_1")
	)
	(segment
		(start 88.553544 -149.761956)
		(end 89.52992 -149.761956)
		(width 0.127)
		(layer "B.Cu")
		(net "USB_EN_1")
	)
	(segment
		(start 89.311226 -139.531852)
		(end 89.311226 -137.972292)
		(width 0.127)
		(layer "In2.Cu")
		(net "USB_EN_1")
	)
	(segment
		(start 88.92794 -139.915138)
		(end 89.311226 -139.531852)
		(width 0.127)
		(layer "In2.Cu")
		(net "USB_EN_1")
	)
	(segment
		(start 87.960962 -150.354538)
		(end 87.287354 -149.68093)
		(width 0.127)
		(layer "In2.Cu")
		(net "USB_EN_1")
	)
	(segment
		(start 89.41562 -136.038336)
		(end 89.41562 -132.807456)
		(width 0.127)
		(layer "In2.Cu")
		(net "USB_EN_1")
	)
	(segment
		(start 89.535 -115.777772)
		(end 89.0397 -115.282472)
		(width 0.127)
		(layer "In2.Cu")
		(net "USB_EN_1")
	)
	(segment
		(start 89.41562 -132.807456)
		(end 89.25179 -132.643626)
		(width 0.127)
		(layer "In2.Cu")
		(net "USB_EN_1")
	)
	(segment
		(start 89.535 -123.70435)
		(end 89.535 -115.777772)
		(width 0.127)
		(layer "In2.Cu")
		(net "USB_EN_1")
	)
	(segment
		(start 88.92794 -141.93012)
		(end 88.92794 -139.915138)
		(width 0.127)
		(layer "In2.Cu")
		(net "USB_EN_1")
	)
	(segment
		(start 87.287354 -146.70532)
		(end 86.45652 -145.874486)
		(width 0.127)
		(layer "In2.Cu")
		(net "USB_EN_1")
	)
	(segment
		(start 87.287354 -149.68093)
		(end 87.287354 -146.70532)
		(width 0.127)
		(layer "In2.Cu")
		(net "USB_EN_1")
	)
	(segment
		(start 89.25179 -132.643626)
		(end 89.25179 -123.98756)
		(width 0.127)
		(layer "In2.Cu")
		(net "USB_EN_1")
	)
	(segment
		(start 86.45652 -145.874486)
		(end 86.45652 -144.089882)
		(width 0.127)
		(layer "In2.Cu")
		(net "USB_EN_1")
	)
	(segment
		(start 89.25179 -123.98756)
		(end 89.535 -123.70435)
		(width 0.127)
		(layer "In2.Cu")
		(net "USB_EN_1")
	)
	(segment
		(start 86.45652 -144.089882)
		(end 87.140542 -143.40586)
		(width 0.127)
		(layer "In2.Cu")
		(net "USB_EN_1")
	)
	(segment
		(start 89.311226 -137.972292)
		(end 89.7763 -137.507218)
		(width 0.127)
		(layer "In2.Cu")
		(net "USB_EN_1")
	)
	(segment
		(start 89.7763 -137.507218)
		(end 89.7763 -136.399016)
		(width 0.127)
		(layer "In2.Cu")
		(net "USB_EN_1")
	)
	(segment
		(start 89.0397 -115.267486)
		(end 89.024714 -115.267486)
		(width 0.127)
		(layer "In2.Cu")
		(net "USB_EN_1")
	)
	(segment
		(start 87.140542 -143.40586)
		(end 87.4522 -143.40586)
		(width 0.127)
		(layer "In2.Cu")
		(net "USB_EN_1")
	)
	(segment
		(start 89.7763 -136.399016)
		(end 89.41562 -136.038336)
		(width 0.127)
		(layer "In2.Cu")
		(net "USB_EN_1")
	)
	(segment
		(start 87.4522 -143.40586)
		(end 88.92794 -141.93012)
		(width 0.127)
		(layer "In2.Cu")
		(net "USB_EN_1")
	)
	(segment
		(start 89.0397 -115.282472)
		(end 89.0397 -115.267486)
		(width 0.127)
		(layer "In2.Cu")
		(net "USB_EN_1")
	)
	(segment
		(start 89.024714 -115.2398)
		(end 89.024714 -115.267486)
		(width 0.127)
		(layer "In5.Cu")
		(net "USB_EN_1")
	)
	(segment
		(start 86.0552 -112.270286)
		(end 89.024714 -115.2398)
		(width 0.127)
		(layer "In5.Cu")
		(net "USB_EN_1")
	)
	(segment
		(start 83.873848 -60.141866)
		(end 83.873848 -53.970936)
		(width 0.127)
		(layer "In5.Cu")
		(net "USB_EN_1")
	)
	(segment
		(start 84.840318 -69.088)
		(end 84.836 -69.088)
		(width 0.127)
		(layer "In5.Cu")
		(net "USB_EN_1")
	)
	(segment
		(start 83.874102 -53.655214)
		(end 83.873848 -53.65496)
		(width 0.127)
		(layer "In5.Cu")
		(net "USB_EN_1")
	)
	(segment
		(start 87.004906 -30.949138)
		(end 87.004906 -30.57398)
		(width 0.127)
		(layer "In5.Cu")
		(net "USB_EN_1")
	)
	(segment
		(start 83.874102 -53.970682)
		(end 83.874102 -53.655214)
		(width 0.127)
		(layer "In5.Cu")
		(net "USB_EN_1")
	)
	(segment
		(start 83.873848 -42.95648)
		(end 85.58784 -41.242488)
		(width 0.127)
		(layer "In5.Cu")
		(net "USB_EN_1")
	)
	(segment
		(start 85.58784 -32.366204)
		(end 87.004906 -30.949138)
		(width 0.127)
		(layer "In5.Cu")
		(net "USB_EN_1")
	)
	(segment
		(start 84.565236 -68.817236)
		(end 84.565236 -60.833254)
		(width 0.127)
		(layer "In5.Cu")
		(net "USB_EN_1")
	)
	(segment
		(start 84.565236 -60.833254)
		(end 83.873848 -60.141866)
		(width 0.127)
		(layer "In5.Cu")
		(net "USB_EN_1")
	)
	(segment
		(start 84.836 -69.088)
		(end 84.565236 -68.817236)
		(width 0.127)
		(layer "In5.Cu")
		(net "USB_EN_1")
	)
	(segment
		(start 83.873848 -53.65496)
		(end 83.873848 -42.95648)
		(width 0.127)
		(layer "In5.Cu")
		(net "USB_EN_1")
	)
	(segment
		(start 85.58784 -41.242488)
		(end 85.58784 -32.366204)
		(width 0.127)
		(layer "In5.Cu")
		(net "USB_EN_1")
	)
	(segment
		(start 83.873848 -53.970936)
		(end 83.874102 -53.970682)
		(width 0.127)
		(layer "In5.Cu")
		(net "USB_EN_1")
	)
	(segment
		(start 86.0552 -110.5154)
		(end 86.0552 -112.270286)
		(width 0.127)
		(layer "In5.Cu")
		(net "USB_EN_1")
	)
	(segment
		(start 53.299614 -146.599656)
		(end 52.899818 -146.19986)
		(width 0.127)
		(layer "F.Cu")
		(net "RMII_BMC_MDIO_R")
	)
	(segment
		(start 53.299614 -146.59991)
		(end 53.299614 -146.599656)
		(width 0.127)
		(layer "F.Cu")
		(net "RMII_BMC_MDIO_R")
	)
	(via
		(at 53.299614 -146.59991)
		(size 0.4572)
		(drill 0.2032)
		(layers "F.Cu" "B.Cu")
		(net "RMII_BMC_MDIO_R")
	)
	(segment
		(start 53.299614 -146.403314)
		(end 52.905914 -146.009614)
		(width 0.127)
		(layer "B.Cu")
		(net "RMII_BMC_MDIO_R")
	)
	(segment
		(start 53.299614 -146.59991)
		(end 53.299614 -146.403314)
		(width 0.127)
		(layer "B.Cu")
		(net "RMII_BMC_MDIO_R")
	)
	(segment
		(start 52.905914 -145.118074)
		(end 52.78628 -144.99844)
		(width 0.127)
		(layer "B.Cu")
		(net "RMII_BMC_MDIO_R")
	)
	(segment
		(start 52.905914 -146.009614)
		(end 52.905914 -145.118074)
		(width 0.127)
		(layer "B.Cu")
		(net "RMII_BMC_MDIO_R")
	)
	(segment
		(start 54.099714 -148.20011)
		(end 53.699918 -147.800314)
		(width 0.127)
		(layer "F.Cu")
		(net "RMII_BMC_MDC_R")
	)
	(segment
		(start 53.699918 -147.800314)
		(end 53.699918 -147.80006)
		(width 0.127)
		(layer "F.Cu")
		(net "RMII_BMC_MDC_R")
	)
	(via
		(at 54.099714 -148.20011)
		(size 0.4572)
		(drill 0.2032)
		(layers "F.Cu" "B.Cu")
		(net "RMII_BMC_MDC_R")
	)
	(segment
		(start 53.145436 -147.8026)
		(end 53.136546 -147.79371)
		(width 0.127)
		(layer "B.Cu")
		(net "RMII_BMC_MDC_R")
	)
	(segment
		(start 53.702204 -147.8026)
		(end 53.145436 -147.8026)
		(width 0.127)
		(layer "B.Cu")
		(net "RMII_BMC_MDC_R")
	)
	(segment
		(start 53.136546 -147.79371)
		(end 53.136292 -147.79371)
		(width 0.127)
		(layer "B.Cu")
		(net "RMII_BMC_MDC_R")
	)
	(segment
		(start 52.905914 -147.563332)
		(end 52.905914 -146.936714)
		(width 0.127)
		(layer "B.Cu")
		(net "RMII_BMC_MDC_R")
	)
	(segment
		(start 53.136292 -147.79371)
		(end 52.905914 -147.563332)
		(width 0.127)
		(layer "B.Cu")
		(net "RMII_BMC_MDC_R")
	)
	(segment
		(start 54.099714 -148.20011)
		(end 53.702204 -147.8026)
		(width 0.127)
		(layer "B.Cu")
		(net "RMII_BMC_MDC_R")
	)
	(segment
		(start 52.905914 -146.936714)
		(end 52.5526 -146.5834)
		(width 0.127)
		(layer "B.Cu")
		(net "RMII_BMC_MDC_R")
	)
	(segment
		(start 90.289634 -159.9946)
		(end 89.204546 -159.9946)
		(width 0.127)
		(layer "F.Cu")
		(net "RBIAS")
	)
	(segment
		(start 91.251532 -158.47568)
		(end 91.251532 -159.032702)
		(width 0.127)
		(layer "F.Cu")
		(net "RBIAS")
	)
	(segment
		(start 88.5444 -160.654746)
		(end 88.5444 -161.4297)
		(width 0.127)
		(layer "F.Cu")
		(net "RBIAS")
	)
	(segment
		(start 89.204546 -159.9946)
		(end 88.5444 -160.654746)
		(width 0.127)
		(layer "F.Cu")
		(net "RBIAS")
	)
	(segment
		(start 91.251532 -159.032702)
		(end 90.289634 -159.9946)
		(width 0.127)
		(layer "F.Cu")
		(net "RBIAS")
	)
	(segment
		(start 179.787804 -150.515066)
		(end 179.438808 -150.16607)
		(width 0.254)
		(layer "F.Cu")
		(net "PWRGD_P5V_STBY")
	)
	(segment
		(start 41.744646 -176.62271)
		(end 42.72661 -176.62271)
		(width 0.254)
		(layer "F.Cu")
		(net "PWRGD_P5V_STBY")
	)
	(segment
		(start 182.2323 -139.449556)
		(end 181.964838 -139.182094)
		(width 0.254)
		(layer "F.Cu")
		(net "PWRGD_P5V_STBY")
	)
	(segment
		(start 179.438808 -150.16607)
		(end 179.438808 -149.159468)
		(width 0.254)
		(layer "F.Cu")
		(net "PWRGD_P5V_STBY")
	)
	(segment
		(start 180.703728 -153.171652)
		(end 180.295042 -152.762966)
		(width 0.254)
		(layer "F.Cu")
		(net "PWRGD_P5V_STBY")
	)
	(segment
		(start 42.72661 -176.62271)
		(end 42.94378 -176.83988)
		(width 0.254)
		(layer "F.Cu")
		(net "PWRGD_P5V_STBY")
	)
	(segment
		(start 180.295042 -152.762966)
		(end 179.787804 -152.762966)
		(width 0.254)
		(layer "F.Cu")
		(net "PWRGD_P5V_STBY")
	)
	(segment
		(start 181.964838 -139.182094)
		(end 181.604412 -139.182094)
		(width 0.254)
		(layer "F.Cu")
		(net "PWRGD_P5V_STBY")
	)
	(segment
		(start 181.24805 -139.538456)
		(end 181.604412 -139.182094)
		(width 0.254)
		(layer "F.Cu")
		(net "PWRGD_P5V_STBY")
	)
	(segment
		(start 182.2323 -140.094716)
		(end 182.2323 -139.449556)
		(width 0.254)
		(layer "F.Cu")
		(net "PWRGD_P5V_STBY")
	)
	(segment
		(start 179.787804 -152.762966)
		(end 179.787804 -150.515066)
		(width 0.254)
		(layer "F.Cu")
		(net "PWRGD_P5V_STBY")
	)
	(segment
		(start 179.78247 -152.7683)
		(end 179.787804 -152.762966)
		(width 0.254)
		(layer "F.Cu")
		(net "PWRGD_P5V_STBY")
	)
	(segment
		(start 181.027832 -153.171652)
		(end 180.703728 -153.171652)
		(width 0.254)
		(layer "F.Cu")
		(net "PWRGD_P5V_STBY")
	)
	(segment
		(start 181.24805 -140.392658)
		(end 181.24805 -139.538456)
		(width 0.254)
		(layer "F.Cu")
		(net "PWRGD_P5V_STBY")
	)
	(segment
		(start 178.7652 -152.7683)
		(end 179.78247 -152.7683)
		(width 0.254)
		(layer "F.Cu")
		(net "PWRGD_P5V_STBY")
	)
	(via
		(at 181.604412 -139.182094)
		(size 0.6604)
		(drill 0.3302)
		(layers "F.Cu" "B.Cu")
		(net "PWRGD_P5V_STBY")
	)
	(via
		(at 42.94378 -176.83988)
		(size 0.508)
		(drill 0.254)
		(layers "F.Cu" "B.Cu")
		(net "PWRGD_P5V_STBY")
	)
	(via
		(at 181.027832 -153.171652)
		(size 0.508)
		(drill 0.254)
		(layers "F.Cu" "B.Cu")
		(net "PWRGD_P5V_STBY")
	)
	(via
		(at 67.2338 -177.8)
		(size 0.508)
		(drill 0.254)
		(layers "F.Cu" "B.Cu")
		(net "PWRGD_P5V_STBY")
	)
	(via
		(at 182.2323 -140.094716)
		(size 0.508)
		(drill 0.254)
		(layers "F.Cu" "B.Cu")
		(net "PWRGD_P5V_STBY")
	)
	(segment
		(start 46.808644 -178.355244)
		(end 66.678556 -178.355244)
		(width 0.254)
		(layer "B.Cu")
		(net "PWRGD_P5V_STBY")
	)
	(segment
		(start 42.94378 -176.83988)
		(end 45.29328 -176.83988)
		(width 0.254)
		(layer "B.Cu")
		(net "PWRGD_P5V_STBY")
	)
	(segment
		(start 66.678556 -178.355244)
		(end 67.2338 -177.8)
		(width 0.254)
		(layer "B.Cu")
		(net "PWRGD_P5V_STBY")
	)
	(segment
		(start 45.29328 -176.83988)
		(end 46.808644 -178.355244)
		(width 0.254)
		(layer "B.Cu")
		(net "PWRGD_P5V_STBY")
	)
	(segment
		(start 152.4889 -98.641408)
		(end 152.4889 -93.20403)
		(width 0.254)
		(layer "In2.Cu")
		(net "PWRGD_P5V_STBY")
	)
	(segment
		(start 144.807432 -4.536948)
		(end 142.523464 -2.25298)
		(width 0.254)
		(layer "In2.Cu")
		(net "PWRGD_P5V_STBY")
	)
	(segment
		(start 182.944516 -140.094716)
		(end 184.9374 -142.0876)
		(width 0.254)
		(layer "In2.Cu")
		(net "PWRGD_P5V_STBY")
	)
	(segment
		(start 67.390264 -139.168632)
		(end 67.390264 -141.114018)
		(width 0.254)
		(layer "In2.Cu")
		(net "PWRGD_P5V_STBY")
	)
	(segment
		(start 182.2323 -140.094716)
		(end 180.963316 -140.094716)
		(width 0.254)
		(layer "In2.Cu")
		(net "PWRGD_P5V_STBY")
	)
	(segment
		(start 68.1609 -145.559018)
		(end 68.1609 -151.221694)
		(width 0.254)
		(layer "In2.Cu")
		(net "PWRGD_P5V_STBY")
	)
	(segment
		(start 178.5239 -140.0048)
		(end 173.6471 -135.128)
		(width 0.254)
		(layer "In2.Cu")
		(net "PWRGD_P5V_STBY")
	)
	(segment
		(start 151.298402 -86.376002)
		(end 150.836884 -85.914484)
		(width 0.254)
		(layer "In2.Cu")
		(net "PWRGD_P5V_STBY")
	)
	(segment
		(start 73.727818 -112.3823)
		(end 69.9389 -112.3823)
		(width 0.254)
		(layer "In2.Cu")
		(net "PWRGD_P5V_STBY")
	)
	(segment
		(start 84.176616 -2.25298)
		(end 82.695796 -3.7338)
		(width 0.254)
		(layer "In2.Cu")
		(net "PWRGD_P5V_STBY")
	)
	(segment
		(start 77.944218 -108.1659)
		(end 73.727818 -112.3823)
		(width 0.254)
		(layer "In2.Cu")
		(net "PWRGD_P5V_STBY")
	)
	(segment
		(start 150.836884 -85.914484)
		(end 150.836884 -47.131986)
		(width 0.254)
		(layer "In2.Cu")
		(net "PWRGD_P5V_STBY")
	)
	(segment
		(start 81.459578 -101.854)
		(end 83.438746 -103.833168)
		(width 0.254)
		(layer "In2.Cu")
		(net "PWRGD_P5V_STBY")
	)
	(segment
		(start 67.390264 -141.114018)
		(end 67.3862 -141.118082)
		(width 0.254)
		(layer "In2.Cu")
		(net "PWRGD_P5V_STBY")
	)
	(segment
		(start 148.45538 -24.527002)
		(end 145.143728 -21.21535)
		(width 0.254)
		(layer "In2.Cu")
		(net "PWRGD_P5V_STBY")
	)
	(segment
		(start 70.9168 -167.644064)
		(end 70.9168 -170.5864)
		(width 0.254)
		(layer "In2.Cu")
		(net "PWRGD_P5V_STBY")
	)
	(segment
		(start 151.298402 -92.013532)
		(end 151.298402 -86.376002)
		(width 0.254)
		(layer "In2.Cu")
		(net "PWRGD_P5V_STBY")
	)
	(segment
		(start 81.882742 -37.17671)
		(end 81.882742 -40.434514)
		(width 0.254)
		(layer "In2.Cu")
		(net "PWRGD_P5V_STBY")
	)
	(segment
		(start 184.9374 -149.374606)
		(end 181.140354 -153.171652)
		(width 0.254)
		(layer "In2.Cu")
		(net "PWRGD_P5V_STBY")
	)
	(segment
		(start 68.5927 -122.410474)
		(end 67.951096 -123.052078)
		(width 0.254)
		(layer "In2.Cu")
		(net "PWRGD_P5V_STBY")
	)
	(segment
		(start 80.339692 -48.235108)
		(end 79.4766 -49.0982)
		(width 0.254)
		(layer "In2.Cu")
		(net "PWRGD_P5V_STBY")
	)
	(segment
		(start 67.951096 -134.584186)
		(end 66.892678 -135.642604)
		(width 0.254)
		(layer "In2.Cu")
		(net "PWRGD_P5V_STBY")
	)
	(segment
		(start 67.3862 -141.118082)
		(end 67.3862 -144.784318)
		(width 0.254)
		(layer "In2.Cu")
		(net "PWRGD_P5V_STBY")
	)
	(segment
		(start 77.8764 -95.181166)
		(end 76.308966 -96.7486)
		(width 0.254)
		(layer "In2.Cu")
		(net "PWRGD_P5V_STBY")
	)
	(segment
		(start 78.697328 -92.422472)
		(end 77.8764 -93.2434)
		(width 0.254)
		(layer "In2.Cu")
		(net "PWRGD_P5V_STBY")
	)
	(segment
		(start 77.65288 -8.678926)
		(end 76.925424 -9.406382)
		(width 0.254)
		(layer "In2.Cu")
		(net "PWRGD_P5V_STBY")
	)
	(segment
		(start 83.438746 -103.833168)
		(end 83.438746 -106.238802)
		(width 0.254)
		(layer "In2.Cu")
		(net "PWRGD_P5V_STBY")
	)
	(segment
		(start 144.807432 -9.398508)
		(end 144.807432 -4.536948)
		(width 0.254)
		(layer "In2.Cu")
		(net "PWRGD_P5V_STBY")
	)
	(segment
		(start 77.8764 -93.2434)
		(end 77.8764 -95.181166)
		(width 0.254)
		(layer "In2.Cu")
		(net "PWRGD_P5V_STBY")
	)
	(segment
		(start 181.140354 -153.171652)
		(end 181.027832 -153.171652)
		(width 0.254)
		(layer "In2.Cu")
		(net "PWRGD_P5V_STBY")
	)
	(segment
		(start 150.60422 -120.184164)
		(end 150.60422 -105.638346)
		(width 0.254)
		(layer "In2.Cu")
		(net "PWRGD_P5V_STBY")
	)
	(segment
		(start 66.892678 -138.671046)
		(end 67.390264 -139.168632)
		(width 0.254)
		(layer "In2.Cu")
		(net "PWRGD_P5V_STBY")
	)
	(segment
		(start 67.3862 -144.784318)
		(end 68.1609 -145.559018)
		(width 0.254)
		(layer "In2.Cu")
		(net "PWRGD_P5V_STBY")
	)
	(segment
		(start 152.932892 -99.0854)
		(end 152.4889 -98.641408)
		(width 0.254)
		(layer "In2.Cu")
		(net "PWRGD_P5V_STBY")
	)
	(segment
		(start 142.523464 -2.25298)
		(end 84.176616 -2.25298)
		(width 0.254)
		(layer "In2.Cu")
		(net "PWRGD_P5V_STBY")
	)
	(segment
		(start 68.5927 -121.683272)
		(end 68.5927 -122.410474)
		(width 0.254)
		(layer "In2.Cu")
		(net "PWRGD_P5V_STBY")
	)
	(segment
		(start 70.9168 -170.5864)
		(end 68.961 -172.5422)
		(width 0.254)
		(layer "In2.Cu")
		(net "PWRGD_P5V_STBY")
	)
	(segment
		(start 79.5528 -101.854)
		(end 81.459578 -101.854)
		(width 0.254)
		(layer "In2.Cu")
		(net "PWRGD_P5V_STBY")
	)
	(segment
		(start 68.961 -176.0728)
		(end 67.2338 -177.8)
		(width 0.254)
		(layer "In2.Cu")
		(net "PWRGD_P5V_STBY")
	)
	(segment
		(start 67.1576 -163.884864)
		(end 70.9168 -167.644064)
		(width 0.254)
		(layer "In2.Cu")
		(net "PWRGD_P5V_STBY")
	)
	(segment
		(start 184.9374 -142.0876)
		(end 184.9374 -149.374606)
		(width 0.254)
		(layer "In2.Cu")
		(net "PWRGD_P5V_STBY")
	)
	(segment
		(start 82.695796 -3.7338)
		(end 81.70037 -3.7338)
		(width 0.254)
		(layer "In2.Cu")
		(net "PWRGD_P5V_STBY")
	)
	(segment
		(start 76.308966 -96.7486)
		(end 76.308966 -98.610166)
		(width 0.254)
		(layer "In2.Cu")
		(net "PWRGD_P5V_STBY")
	)
	(segment
		(start 68.1609 -151.221694)
		(end 67.1576 -152.224994)
		(width 0.254)
		(layer "In2.Cu")
		(net "PWRGD_P5V_STBY")
	)
	(segment
		(start 78.697328 -54.906672)
		(end 78.697328 -92.422472)
		(width 0.254)
		(layer "In2.Cu")
		(net "PWRGD_P5V_STBY")
	)
	(segment
		(start 69.9389 -112.3823)
		(end 66.9925 -115.3287)
		(width 0.254)
		(layer "In2.Cu")
		(net "PWRGD_P5V_STBY")
	)
	(segment
		(start 152.4889 -93.20403)
		(end 151.298402 -92.013532)
		(width 0.254)
		(layer "In2.Cu")
		(net "PWRGD_P5V_STBY")
	)
	(segment
		(start 66.892678 -135.642604)
		(end 66.892678 -138.671046)
		(width 0.254)
		(layer "In2.Cu")
		(net "PWRGD_P5V_STBY")
	)
	(segment
		(start 67.1576 -152.224994)
		(end 67.1576 -163.884864)
		(width 0.254)
		(layer "In2.Cu")
		(net "PWRGD_P5V_STBY")
	)
	(segment
		(start 66.9925 -115.3287)
		(end 66.9925 -120.083072)
		(width 0.254)
		(layer "In2.Cu")
		(net "PWRGD_P5V_STBY")
	)
	(segment
		(start 180.8734 -140.0048)
		(end 178.5239 -140.0048)
		(width 0.254)
		(layer "In2.Cu")
		(net "PWRGD_P5V_STBY")
	)
	(segment
		(start 182.2323 -140.094716)
		(end 182.944516 -140.094716)
		(width 0.254)
		(layer "In2.Cu")
		(net "PWRGD_P5V_STBY")
	)
	(segment
		(start 76.308966 -98.610166)
		(end 79.5528 -101.854)
		(width 0.254)
		(layer "In2.Cu")
		(net "PWRGD_P5V_STBY")
	)
	(segment
		(start 81.70037 -3.7338)
		(end 77.65288 -7.78129)
		(width 0.254)
		(layer "In2.Cu")
		(net "PWRGD_P5V_STBY")
	)
	(segment
		(start 145.143728 -21.21535)
		(end 145.143728 -9.734804)
		(width 0.254)
		(layer "In2.Cu")
		(net "PWRGD_P5V_STBY")
	)
	(segment
		(start 81.511648 -108.1659)
		(end 77.944218 -108.1659)
		(width 0.254)
		(layer "In2.Cu")
		(net "PWRGD_P5V_STBY")
	)
	(segment
		(start 81.882742 -40.434514)
		(end 80.339692 -41.977564)
		(width 0.254)
		(layer "In2.Cu")
		(net "PWRGD_P5V_STBY")
	)
	(segment
		(start 150.60422 -105.638346)
		(end 152.932892 -103.309674)
		(width 0.254)
		(layer "In2.Cu")
		(net "PWRGD_P5V_STBY")
	)
	(segment
		(start 68.961 -172.5422)
		(end 68.961 -176.0728)
		(width 0.254)
		(layer "In2.Cu")
		(net "PWRGD_P5V_STBY")
	)
	(segment
		(start 165.548056 -135.128)
		(end 150.60422 -120.184164)
		(width 0.254)
		(layer "In2.Cu")
		(net "PWRGD_P5V_STBY")
	)
	(segment
		(start 150.836884 -47.131986)
		(end 148.45538 -44.750482)
		(width 0.254)
		(layer "In2.Cu")
		(net "PWRGD_P5V_STBY")
	)
	(segment
		(start 67.951096 -123.052078)
		(end 67.951096 -134.584186)
		(width 0.254)
		(layer "In2.Cu")
		(net "PWRGD_P5V_STBY")
	)
	(segment
		(start 145.143728 -9.734804)
		(end 144.807432 -9.398508)
		(width 0.254)
		(layer "In2.Cu")
		(net "PWRGD_P5V_STBY")
	)
	(segment
		(start 76.925424 -9.406382)
		(end 76.925424 -32.219392)
		(width 0.254)
		(layer "In2.Cu")
		(net "PWRGD_P5V_STBY")
	)
	(segment
		(start 148.45538 -44.750482)
		(end 148.45538 -24.527002)
		(width 0.254)
		(layer "In2.Cu")
		(net "PWRGD_P5V_STBY")
	)
	(segment
		(start 76.925424 -32.219392)
		(end 81.882742 -37.17671)
		(width 0.254)
		(layer "In2.Cu")
		(net "PWRGD_P5V_STBY")
	)
	(segment
		(start 79.4766 -54.1274)
		(end 78.697328 -54.906672)
		(width 0.254)
		(layer "In2.Cu")
		(net "PWRGD_P5V_STBY")
	)
	(segment
		(start 83.438746 -106.238802)
		(end 81.511648 -108.1659)
		(width 0.254)
		(layer "In2.Cu")
		(net "PWRGD_P5V_STBY")
	)
	(segment
		(start 152.932892 -103.309674)
		(end 152.932892 -99.0854)
		(width 0.254)
		(layer "In2.Cu")
		(net "PWRGD_P5V_STBY")
	)
	(segment
		(start 66.9925 -120.083072)
		(end 68.5927 -121.683272)
		(width 0.254)
		(layer "In2.Cu")
		(net "PWRGD_P5V_STBY")
	)
	(segment
		(start 77.65288 -7.78129)
		(end 77.65288 -8.678926)
		(width 0.254)
		(layer "In2.Cu")
		(net "PWRGD_P5V_STBY")
	)
	(segment
		(start 180.963316 -140.094716)
		(end 180.8734 -140.0048)
		(width 0.254)
		(layer "In2.Cu")
		(net "PWRGD_P5V_STBY")
	)
	(segment
		(start 80.339692 -41.977564)
		(end 80.339692 -48.235108)
		(width 0.254)
		(layer "In2.Cu")
		(net "PWRGD_P5V_STBY")
	)
	(segment
		(start 79.4766 -49.0982)
		(end 79.4766 -54.1274)
		(width 0.254)
		(layer "In2.Cu")
		(net "PWRGD_P5V_STBY")
	)
	(segment
		(start 173.6471 -135.128)
		(end 165.548056 -135.128)
		(width 0.254)
		(layer "In2.Cu")
		(net "PWRGD_P5V_STBY")
	)
	(segment
		(start 86.3854 -182.1688)
		(end 88.2142 -180.34)
		(width 0.254)
		(layer "F.Cu")
		(net "PWRGD_P3V3_STBY")
	)
	(segment
		(start 40.246046 -179.59451)
		(end 41.448482 -179.59451)
		(width 0.254)
		(layer "F.Cu")
		(net "PWRGD_P3V3_STBY")
	)
	(segment
		(start 36.744148 -180.070506)
		(end 37.75075 -180.070506)
		(width 0.254)
		(layer "F.Cu")
		(net "PWRGD_P3V3_STBY")
	)
	(segment
		(start 38.252146 -179.56911)
		(end 39.1922 -179.56911)
		(width 0.254)
		(layer "F.Cu")
		(net "PWRGD_P3V3_STBY")
	)
	(segment
		(start 39.1922 -179.56911)
		(end 40.220646 -179.56911)
		(width 0.254)
		(layer "F.Cu")
		(net "PWRGD_P3V3_STBY")
	)
	(segment
		(start 41.448482 -179.59451)
		(end 41.46804 -179.574952)
		(width 0.254)
		(layer "F.Cu")
		(net "PWRGD_P3V3_STBY")
	)
	(segment
		(start 88.2142 -180.34)
		(end 89.66708 -180.34)
		(width 0.254)
		(layer "F.Cu")
		(net "PWRGD_P3V3_STBY")
	)
	(segment
		(start 89.66708 -180.34)
		(end 90.63228 -179.3748)
		(width 0.254)
		(layer "F.Cu")
		(net "PWRGD_P3V3_STBY")
	)
	(segment
		(start 40.220646 -179.56911)
		(end 40.246046 -179.59451)
		(width 0.254)
		(layer "F.Cu")
		(net "PWRGD_P3V3_STBY")
	)
	(segment
		(start 27.901646 -178.17211)
		(end 27.08529 -178.17211)
		(width 0.254)
		(layer "F.Cu")
		(net "PWRGD_P3V3_STBY")
	)
	(segment
		(start 67.8561 -183.769)
		(end 66.9798 -183.769)
		(width 0.254)
		(layer "F.Cu")
		(net "PWRGD_P3V3_STBY")
	)
	(segment
		(start 90.63228 -179.3748)
		(end 93.853 -179.3748)
		(width 0.254)
		(layer "F.Cu")
		(net "PWRGD_P3V3_STBY")
	)
	(segment
		(start 37.75075 -180.070506)
		(end 38.252146 -179.56911)
		(width 0.254)
		(layer "F.Cu")
		(net "PWRGD_P3V3_STBY")
	)
	(segment
		(start 86.3854 -182.4228)
		(end 86.3854 -182.1688)
		(width 0.254)
		(layer "F.Cu")
		(net "PWRGD_P3V3_STBY")
	)
	(via
		(at 86.3854 -182.4228)
		(size 0.508)
		(drill 0.254)
		(layers "F.Cu" "B.Cu")
		(net "PWRGD_P3V3_STBY")
	)
	(via
		(at 27.08529 -178.17211)
		(size 0.508)
		(drill 0.254)
		(layers "F.Cu" "B.Cu")
		(net "PWRGD_P3V3_STBY")
	)
	(via
		(at 78.406498 -131.875022)
		(size 0.508)
		(drill 0.254)
		(layers "F.Cu" "B.Cu")
		(net "PWRGD_P3V3_STBY")
	)
	(via
		(at 66.9798 -183.769)
		(size 0.508)
		(drill 0.254)
		(layers "F.Cu" "B.Cu")
		(net "PWRGD_P3V3_STBY")
	)
	(via
		(at 79.84998 -132.280406)
		(size 0.6096)
		(drill 0.3048)
		(layers "F.Cu" "B.Cu")
		(net "PWRGD_P3V3_STBY")
	)
	(via
		(at 41.46804 -179.574952)
		(size 0.508)
		(drill 0.254)
		(layers "F.Cu" "B.Cu")
		(net "PWRGD_P3V3_STBY")
	)
	(segment
		(start 80.448404 -132.280406)
		(end 81.4451 -131.28371)
		(width 0.254)
		(layer "B.Cu")
		(net "PWRGD_P3V3_STBY")
	)
	(segment
		(start 78.811882 -132.280406)
		(end 79.84998 -132.280406)
		(width 0.254)
		(layer "B.Cu")
		(net "PWRGD_P3V3_STBY")
	)
	(segment
		(start 78.406498 -131.875022)
		(end 78.811882 -132.280406)
		(width 0.254)
		(layer "B.Cu")
		(net "PWRGD_P3V3_STBY")
	)
	(segment
		(start 81.4451 -131.28371)
		(end 81.4451 -130.69824)
		(width 0.254)
		(layer "B.Cu")
		(net "PWRGD_P3V3_STBY")
	)
	(segment
		(start 79.84998 -132.280406)
		(end 80.448404 -132.280406)
		(width 0.254)
		(layer "B.Cu")
		(net "PWRGD_P3V3_STBY")
	)
	(segment
		(start 78.740762 -141.01572)
		(end 78.8924 -141.167358)
		(width 0.254)
		(layer "In2.Cu")
		(net "PWRGD_P3V3_STBY")
	)
	(segment
		(start 78.406498 -134.588504)
		(end 78.207362 -134.78764)
		(width 0.254)
		(layer "In2.Cu")
		(net "PWRGD_P3V3_STBY")
	)
	(segment
		(start 84.1629 -165.68674)
		(end 83.722972 -166.126668)
		(width 0.254)
		(layer "In2.Cu")
		(net "PWRGD_P3V3_STBY")
	)
	(segment
		(start 82.0674 -159.612076)
		(end 82.0674 -162.848544)
		(width 0.254)
		(layer "In2.Cu")
		(net "PWRGD_P3V3_STBY")
	)
	(segment
		(start 82.64525 -163.426394)
		(end 82.802222 -163.426394)
		(width 0.254)
		(layer "In2.Cu")
		(net "PWRGD_P3V3_STBY")
	)
	(segment
		(start 85.0392 -181.0766)
		(end 86.3854 -182.4228)
		(width 0.254)
		(layer "In2.Cu")
		(net "PWRGD_P3V3_STBY")
	)
	(segment
		(start 82.0674 -162.848544)
		(end 82.64525 -163.426394)
		(width 0.254)
		(layer "In2.Cu")
		(net "PWRGD_P3V3_STBY")
	)
	(segment
		(start 78.740762 -137.587482)
		(end 78.740762 -141.01572)
		(width 0.254)
		(layer "In2.Cu")
		(net "PWRGD_P3V3_STBY")
	)
	(segment
		(start 78.8924 -141.167358)
		(end 78.8924 -146.772122)
		(width 0.254)
		(layer "In2.Cu")
		(net "PWRGD_P3V3_STBY")
	)
	(segment
		(start 78.8924 -146.772122)
		(end 79.1464 -147.026122)
		(width 0.254)
		(layer "In2.Cu")
		(net "PWRGD_P3V3_STBY")
	)
	(segment
		(start 83.722972 -166.126668)
		(end 83.225132 -166.126668)
		(width 0.254)
		(layer "In2.Cu")
		(net "PWRGD_P3V3_STBY")
	)
	(segment
		(start 81.277714 -150.947882)
		(end 81.277714 -158.82239)
		(width 0.254)
		(layer "In2.Cu")
		(net "PWRGD_P3V3_STBY")
	)
	(segment
		(start 81.277714 -158.82239)
		(end 82.0674 -159.612076)
		(width 0.254)
		(layer "In2.Cu")
		(net "PWRGD_P3V3_STBY")
	)
	(segment
		(start 83.225132 -166.126668)
		(end 79.7052 -169.6466)
		(width 0.254)
		(layer "In2.Cu")
		(net "PWRGD_P3V3_STBY")
	)
	(segment
		(start 79.7052 -173.4693)
		(end 81.6737 -175.4378)
		(width 0.254)
		(layer "In2.Cu")
		(net "PWRGD_P3V3_STBY")
	)
	(segment
		(start 85.0392 -179.9082)
		(end 85.0392 -181.0766)
		(width 0.254)
		(layer "In2.Cu")
		(net "PWRGD_P3V3_STBY")
	)
	(segment
		(start 84.201 -176.3014)
		(end 84.201 -179.07)
		(width 0.254)
		(layer "In2.Cu")
		(net "PWRGD_P3V3_STBY")
	)
	(segment
		(start 78.406498 -131.875022)
		(end 78.406498 -134.588504)
		(width 0.254)
		(layer "In2.Cu")
		(net "PWRGD_P3V3_STBY")
	)
	(segment
		(start 84.1629 -165.040818)
		(end 84.1629 -165.68674)
		(width 0.254)
		(layer "In2.Cu")
		(net "PWRGD_P3V3_STBY")
	)
	(segment
		(start 78.207362 -134.78764)
		(end 78.207362 -137.054082)
		(width 0.254)
		(layer "In2.Cu")
		(net "PWRGD_P3V3_STBY")
	)
	(segment
		(start 83.3374 -175.4378)
		(end 84.201 -176.3014)
		(width 0.254)
		(layer "In2.Cu")
		(net "PWRGD_P3V3_STBY")
	)
	(segment
		(start 82.802222 -163.426394)
		(end 83.782662 -164.406834)
		(width 0.254)
		(layer "In2.Cu")
		(net "PWRGD_P3V3_STBY")
	)
	(segment
		(start 79.1464 -147.026122)
		(end 79.1464 -148.816568)
		(width 0.254)
		(layer "In2.Cu")
		(net "PWRGD_P3V3_STBY")
	)
	(segment
		(start 79.1464 -148.816568)
		(end 81.277714 -150.947882)
		(width 0.254)
		(layer "In2.Cu")
		(net "PWRGD_P3V3_STBY")
	)
	(segment
		(start 78.207362 -137.054082)
		(end 78.740762 -137.587482)
		(width 0.254)
		(layer "In2.Cu")
		(net "PWRGD_P3V3_STBY")
	)
	(segment
		(start 79.7052 -169.6466)
		(end 79.7052 -173.4693)
		(width 0.254)
		(layer "In2.Cu")
		(net "PWRGD_P3V3_STBY")
	)
	(segment
		(start 83.782662 -164.406834)
		(end 83.782662 -164.66058)
		(width 0.254)
		(layer "In2.Cu")
		(net "PWRGD_P3V3_STBY")
	)
	(segment
		(start 83.782662 -164.66058)
		(end 84.1629 -165.040818)
		(width 0.254)
		(layer "In2.Cu")
		(net "PWRGD_P3V3_STBY")
	)
	(segment
		(start 81.6737 -175.4378)
		(end 83.3374 -175.4378)
		(width 0.254)
		(layer "In2.Cu")
		(net "PWRGD_P3V3_STBY")
	)
	(segment
		(start 84.201 -179.07)
		(end 85.0392 -179.9082)
		(width 0.254)
		(layer "In2.Cu")
		(net "PWRGD_P3V3_STBY")
	)
	(segment
		(start 27.08529 -178.17211)
		(end 27.57678 -178.6636)
		(width 0.254)
		(layer "In5.Cu")
		(net "PWRGD_P3V3_STBY")
	)
	(segment
		(start 57.348628 -177.3428)
		(end 50.71618 -177.3428)
		(width 0.254)
		(layer "In5.Cu")
		(net "PWRGD_P3V3_STBY")
	)
	(segment
		(start 63.6397 -180.6067)
		(end 60.612528 -180.6067)
		(width 0.254)
		(layer "In5.Cu")
		(net "PWRGD_P3V3_STBY")
	)
	(segment
		(start 66.171318 -183.138318)
		(end 63.6397 -180.6067)
		(width 0.254)
		(layer "In5.Cu")
		(net "PWRGD_P3V3_STBY")
	)
	(segment
		(start 49.78019 -176.84877)
		(end 49.46396 -177.165)
		(width 0.254)
		(layer "In5.Cu")
		(net "PWRGD_P3V3_STBY")
	)
	(segment
		(start 37.526722 -179.574952)
		(end 41.46804 -179.574952)
		(width 0.254)
		(layer "In5.Cu")
		(net "PWRGD_P3V3_STBY")
	)
	(segment
		(start 69.2404 -186.0296)
		(end 66.9798 -183.769)
		(width 0.254)
		(layer "In5.Cu")
		(net "PWRGD_P3V3_STBY")
	)
	(segment
		(start 27.57678 -178.6636)
		(end 36.61537 -178.6636)
		(width 0.254)
		(layer "In5.Cu")
		(net "PWRGD_P3V3_STBY")
	)
	(segment
		(start 36.61537 -178.6636)
		(end 37.526722 -179.574952)
		(width 0.254)
		(layer "In5.Cu")
		(net "PWRGD_P3V3_STBY")
	)
	(segment
		(start 66.349118 -183.138318)
		(end 66.171318 -183.138318)
		(width 0.254)
		(layer "In5.Cu")
		(net "PWRGD_P3V3_STBY")
	)
	(segment
		(start 43.877992 -177.165)
		(end 41.46804 -179.574952)
		(width 0.254)
		(layer "In5.Cu")
		(net "PWRGD_P3V3_STBY")
	)
	(segment
		(start 49.46396 -177.165)
		(end 43.877992 -177.165)
		(width 0.254)
		(layer "In5.Cu")
		(net "PWRGD_P3V3_STBY")
	)
	(segment
		(start 60.612528 -180.6067)
		(end 57.348628 -177.3428)
		(width 0.254)
		(layer "In5.Cu")
		(net "PWRGD_P3V3_STBY")
	)
	(segment
		(start 86.3854 -182.4228)
		(end 82.7786 -186.0296)
		(width 0.254)
		(layer "In5.Cu")
		(net "PWRGD_P3V3_STBY")
	)
	(segment
		(start 50.71618 -177.3428)
		(end 50.22215 -176.84877)
		(width 0.254)
		(layer "In5.Cu")
		(net "PWRGD_P3V3_STBY")
	)
	(segment
		(start 82.7786 -186.0296)
		(end 69.2404 -186.0296)
		(width 0.254)
		(layer "In5.Cu")
		(net "PWRGD_P3V3_STBY")
	)
	(segment
		(start 66.9798 -183.769)
		(end 66.349118 -183.138318)
		(width 0.254)
		(layer "In5.Cu")
		(net "PWRGD_P3V3_STBY")
	)
	(segment
		(start 50.22215 -176.84877)
		(end 49.78019 -176.84877)
		(width 0.254)
		(layer "In5.Cu")
		(net "PWRGD_P3V3_STBY")
	)
	(segment
		(start 158.379668 -144.069308)
		(end 158.204408 -144.069308)
		(width 0.254)
		(layer "F.Cu")
		(net "PWRGD_P1V8_STBY")
	)
	(segment
		(start 156.50464 -137.678922)
		(end 156.770578 -137.412984)
		(width 0.254)
		(layer "F.Cu")
		(net "PWRGD_P1V8_STBY")
	)
	(segment
		(start 8.7122 -172.085)
		(end 9.333484 -172.706284)
		(width 0.254)
		(layer "F.Cu")
		(net "PWRGD_P1V8_STBY")
	)
	(segment
		(start 156.6926 -142.5575)
		(end 157.3276 -143.1925)
		(width 0.254)
		(layer "F.Cu")
		(net "PWRGD_P1V8_STBY")
	)
	(segment
		(start 158.204408 -144.069308)
		(end 157.3276 -143.1925)
		(width 0.254)
		(layer "F.Cu")
		(net "PWRGD_P1V8_STBY")
	)
	(segment
		(start 155.956 -142.5575)
		(end 156.6926 -142.5575)
		(width 0.254)
		(layer "F.Cu")
		(net "PWRGD_P1V8_STBY")
	)
	(segment
		(start 5.6134 -123.1392)
		(end 5.6134 -168.9862)
		(width 0.254)
		(layer "F.Cu")
		(net "PWRGD_P1V8_STBY")
	)
	(segment
		(start 69.51599 -115.7478)
		(end 66.802 -115.7478)
		(width 0.254)
		(layer "F.Cu")
		(net "PWRGD_P1V8_STBY")
	)
	(segment
		(start 5.6134 -168.9862)
		(end 8.7122 -172.085)
		(width 0.254)
		(layer "F.Cu")
		(net "PWRGD_P1V8_STBY")
	)
	(segment
		(start 51.317398 -116.0018)
		(end 48.929798 -113.6142)
		(width 0.254)
		(layer "F.Cu")
		(net "PWRGD_P1V8_STBY")
	)
	(segment
		(start 48.929798 -113.6142)
		(end 15.1384 -113.6142)
		(width 0.254)
		(layer "F.Cu")
		(net "PWRGD_P1V8_STBY")
	)
	(segment
		(start 156.50464 -137.8458)
		(end 156.50464 -137.678922)
		(width 0.254)
		(layer "F.Cu")
		(net "PWRGD_P1V8_STBY")
	)
	(segment
		(start 66.802 -115.7478)
		(end 66.548 -116.0018)
		(width 0.254)
		(layer "F.Cu")
		(net "PWRGD_P1V8_STBY")
	)
	(segment
		(start 69.8754 -116.9162)
		(end 69.8754 -116.10721)
		(width 0.254)
		(layer "F.Cu")
		(net "PWRGD_P1V8_STBY")
	)
	(segment
		(start 156.770578 -137.412984)
		(end 157.747716 -137.412984)
		(width 0.254)
		(layer "F.Cu")
		(net "PWRGD_P1V8_STBY")
	)
	(segment
		(start 15.1384 -113.6142)
		(end 5.6134 -123.1392)
		(width 0.254)
		(layer "F.Cu")
		(net "PWRGD_P1V8_STBY")
	)
	(segment
		(start 69.8754 -116.10721)
		(end 69.51599 -115.7478)
		(width 0.254)
		(layer "F.Cu")
		(net "PWRGD_P1V8_STBY")
	)
	(segment
		(start 66.548 -116.0018)
		(end 51.317398 -116.0018)
		(width 0.254)
		(layer "F.Cu")
		(net "PWRGD_P1V8_STBY")
	)
	(segment
		(start 9.333484 -172.706284)
		(end 9.825482 -172.706284)
		(width 0.254)
		(layer "F.Cu")
		(net "PWRGD_P1V8_STBY")
	)
	(via
		(at 155.956 -142.5575)
		(size 0.508)
		(drill 0.254)
		(layers "F.Cu" "B.Cu")
		(net "PWRGD_P1V8_STBY")
	)
	(via
		(at 8.7122 -172.085)
		(size 0.6604)
		(drill 0.3302)
		(layers "F.Cu" "B.Cu")
		(net "PWRGD_P1V8_STBY")
	)
	(via
		(at 69.8754 -116.9162)
		(size 0.508)
		(drill 0.254)
		(layers "F.Cu" "B.Cu")
		(net "PWRGD_P1V8_STBY")
	)
	(via
		(at 156.50464 -137.8458)
		(size 0.508)
		(drill 0.254)
		(layers "F.Cu" "B.Cu")
		(net "PWRGD_P1V8_STBY")
	)
	(segment
		(start 81.609692 -48.997108)
		(end 81.609692 -42.503852)
		(width 0.254)
		(layer "In2.Cu")
		(net "PWRGD_P1V8_STBY")
	)
	(segment
		(start 149.929088 -87.60206)
		(end 149.929088 -95.532702)
		(width 0.254)
		(layer "In2.Cu")
		(net "PWRGD_P1V8_STBY")
	)
	(segment
		(start 83.185 -36.394136)
		(end 78.234794 -31.44393)
		(width 0.254)
		(layer "In2.Cu")
		(net "PWRGD_P1V8_STBY")
	)
	(segment
		(start 147.066 -24.93391)
		(end 147.066 -45.15739)
		(width 0.254)
		(layer "In2.Cu")
		(net "PWRGD_P1V8_STBY")
	)
	(segment
		(start 84.702904 -3.52298)
		(end 140.389864 -3.52298)
		(width 0.254)
		(layer "In2.Cu")
		(net "PWRGD_P1V8_STBY")
	)
	(segment
		(start 141.668754 -4.80187)
		(end 141.668754 -8.056118)
		(width 0.254)
		(layer "In2.Cu")
		(net "PWRGD_P1V8_STBY")
	)
	(segment
		(start 73.490074 -113.849658)
		(end 73.490328 -113.849404)
		(width 0.254)
		(layer "In2.Cu")
		(net "PWRGD_P1V8_STBY")
	)
	(segment
		(start 149.187154 -47.278544)
		(end 149.187154 -86.860126)
		(width 0.254)
		(layer "In2.Cu")
		(net "PWRGD_P1V8_STBY")
	)
	(segment
		(start 73.490328 -113.849404)
		(end 74.057002 -113.849404)
		(width 0.254)
		(layer "In2.Cu")
		(net "PWRGD_P1V8_STBY")
	)
	(segment
		(start 156.37764 -142.13586)
		(end 155.956 -142.5575)
		(width 0.254)
		(layer "In2.Cu")
		(net "PWRGD_P1V8_STBY")
	)
	(segment
		(start 74.057002 -113.849404)
		(end 78.470506 -109.4359)
		(width 0.254)
		(layer "In2.Cu")
		(net "PWRGD_P1V8_STBY")
	)
	(segment
		(start 78.470506 -109.4359)
		(end 82.037936 -109.4359)
		(width 0.254)
		(layer "In2.Cu")
		(net "PWRGD_P1V8_STBY")
	)
	(segment
		(start 78.92288 -9.205214)
		(end 78.92288 -8.307578)
		(width 0.254)
		(layer "In2.Cu")
		(net "PWRGD_P1V8_STBY")
	)
	(segment
		(start 72.964294 -113.849658)
		(end 73.490074 -113.849658)
		(width 0.254)
		(layer "In2.Cu")
		(net "PWRGD_P1V8_STBY")
	)
	(segment
		(start 142.748 -20.61591)
		(end 147.066 -24.93391)
		(width 0.254)
		(layer "In2.Cu")
		(net "PWRGD_P1V8_STBY")
	)
	(segment
		(start 69.8754 -116.9162)
		(end 69.8754 -115.0874)
		(width 0.254)
		(layer "In2.Cu")
		(net "PWRGD_P1V8_STBY")
	)
	(segment
		(start 149.33422 -136.1694)
		(end 155.72232 -142.5575)
		(width 0.254)
		(layer "In2.Cu")
		(net "PWRGD_P1V8_STBY")
	)
	(segment
		(start 79.2226 -99.727512)
		(end 79.2226 -97.4852)
		(width 0.254)
		(layer "In2.Cu")
		(net "PWRGD_P1V8_STBY")
	)
	(segment
		(start 71.113396 -113.849404)
		(end 72.96404 -113.849404)
		(width 0.254)
		(layer "In2.Cu")
		(net "PWRGD_P1V8_STBY")
	)
	(segment
		(start 81.4832 -96.647)
		(end 82.291428 -95.838772)
		(width 0.254)
		(layer "In2.Cu")
		(net "PWRGD_P1V8_STBY")
	)
	(segment
		(start 84.708746 -103.250746)
		(end 82.0166 -100.5586)
		(width 0.254)
		(layer "In2.Cu")
		(net "PWRGD_P1V8_STBY")
	)
	(segment
		(start 156.37764 -137.9728)
		(end 156.37764 -142.13586)
		(width 0.254)
		(layer "In2.Cu")
		(net "PWRGD_P1V8_STBY")
	)
	(segment
		(start 156.50464 -137.8458)
		(end 156.37764 -137.9728)
		(width 0.254)
		(layer "In2.Cu")
		(net "PWRGD_P1V8_STBY")
	)
	(segment
		(start 78.92288 -8.307578)
		(end 82.226658 -5.0038)
		(width 0.254)
		(layer "In2.Cu")
		(net "PWRGD_P1V8_STBY")
	)
	(segment
		(start 141.668754 -8.056118)
		(end 142.748 -9.135364)
		(width 0.254)
		(layer "In2.Cu")
		(net "PWRGD_P1V8_STBY")
	)
	(segment
		(start 80.996028 -49.610772)
		(end 81.609692 -48.997108)
		(width 0.254)
		(layer "In2.Cu")
		(net "PWRGD_P1V8_STBY")
	)
	(segment
		(start 80.996028 -68.397628)
		(end 80.996028 -49.610772)
		(width 0.254)
		(layer "In2.Cu")
		(net "PWRGD_P1V8_STBY")
	)
	(segment
		(start 142.748 -9.135364)
		(end 142.748 -20.61591)
		(width 0.254)
		(layer "In2.Cu")
		(net "PWRGD_P1V8_STBY")
	)
	(segment
		(start 82.226658 -5.0038)
		(end 83.222084 -5.0038)
		(width 0.254)
		(layer "In2.Cu")
		(net "PWRGD_P1V8_STBY")
	)
	(segment
		(start 83.185 -40.928544)
		(end 83.185 -36.394136)
		(width 0.254)
		(layer "In2.Cu")
		(net "PWRGD_P1V8_STBY")
	)
	(segment
		(start 83.222084 -5.0038)
		(end 84.702904 -3.52298)
		(width 0.254)
		(layer "In2.Cu")
		(net "PWRGD_P1V8_STBY")
	)
	(segment
		(start 82.291428 -95.838772)
		(end 82.291428 -69.693028)
		(width 0.254)
		(layer "In2.Cu")
		(net "PWRGD_P1V8_STBY")
	)
	(segment
		(start 80.053688 -100.5586)
		(end 79.2226 -99.727512)
		(width 0.254)
		(layer "In2.Cu")
		(net "PWRGD_P1V8_STBY")
	)
	(segment
		(start 140.389864 -3.52298)
		(end 141.668754 -4.80187)
		(width 0.254)
		(layer "In2.Cu")
		(net "PWRGD_P1V8_STBY")
	)
	(segment
		(start 72.96404 -113.849404)
		(end 72.964294 -113.849658)
		(width 0.254)
		(layer "In2.Cu")
		(net "PWRGD_P1V8_STBY")
	)
	(segment
		(start 155.72232 -142.5575)
		(end 155.956 -142.5575)
		(width 0.254)
		(layer "In2.Cu")
		(net "PWRGD_P1V8_STBY")
	)
	(segment
		(start 151.218138 -102.634796)
		(end 149.33422 -104.518714)
		(width 0.254)
		(layer "In2.Cu")
		(net "PWRGD_P1V8_STBY")
	)
	(segment
		(start 84.708746 -106.76509)
		(end 84.708746 -103.250746)
		(width 0.254)
		(layer "In2.Cu")
		(net "PWRGD_P1V8_STBY")
	)
	(segment
		(start 82.0166 -100.5586)
		(end 80.053688 -100.5586)
		(width 0.254)
		(layer "In2.Cu")
		(net "PWRGD_P1V8_STBY")
	)
	(segment
		(start 149.187154 -86.860126)
		(end 149.929088 -87.60206)
		(width 0.254)
		(layer "In2.Cu")
		(net "PWRGD_P1V8_STBY")
	)
	(segment
		(start 80.0608 -96.647)
		(end 81.4832 -96.647)
		(width 0.254)
		(layer "In2.Cu")
		(net "PWRGD_P1V8_STBY")
	)
	(segment
		(start 82.291428 -69.693028)
		(end 80.996028 -68.397628)
		(width 0.254)
		(layer "In2.Cu")
		(net "PWRGD_P1V8_STBY")
	)
	(segment
		(start 69.8754 -115.0874)
		(end 71.113396 -113.849404)
		(width 0.254)
		(layer "In2.Cu")
		(net "PWRGD_P1V8_STBY")
	)
	(segment
		(start 151.218138 -96.821752)
		(end 151.218138 -102.634796)
		(width 0.254)
		(layer "In2.Cu")
		(net "PWRGD_P1V8_STBY")
	)
	(segment
		(start 79.2226 -97.4852)
		(end 80.0608 -96.647)
		(width 0.254)
		(layer "In2.Cu")
		(net "PWRGD_P1V8_STBY")
	)
	(segment
		(start 81.609692 -42.503852)
		(end 83.185 -40.928544)
		(width 0.254)
		(layer "In2.Cu")
		(net "PWRGD_P1V8_STBY")
	)
	(segment
		(start 149.929088 -95.532702)
		(end 151.218138 -96.821752)
		(width 0.254)
		(layer "In2.Cu")
		(net "PWRGD_P1V8_STBY")
	)
	(segment
		(start 78.234794 -9.8933)
		(end 78.92288 -9.205214)
		(width 0.254)
		(layer "In2.Cu")
		(net "PWRGD_P1V8_STBY")
	)
	(segment
		(start 149.33422 -104.518714)
		(end 149.33422 -136.1694)
		(width 0.254)
		(layer "In2.Cu")
		(net "PWRGD_P1V8_STBY")
	)
	(segment
		(start 147.066 -45.15739)
		(end 149.187154 -47.278544)
		(width 0.254)
		(layer "In2.Cu")
		(net "PWRGD_P1V8_STBY")
	)
	(segment
		(start 82.037936 -109.4359)
		(end 84.708746 -106.76509)
		(width 0.254)
		(layer "In2.Cu")
		(net "PWRGD_P1V8_STBY")
	)
	(segment
		(start 78.234794 -31.44393)
		(end 78.234794 -9.8933)
		(width 0.254)
		(layer "In2.Cu")
		(net "PWRGD_P1V8_STBY")
	)
	(segment
		(start 52.499768 -137.800334)
		(end 52.499514 -137.800334)
		(width 0.127)
		(layer "F.Cu")
		(net "PWRBTN_OUT_N_R")
	)
	(segment
		(start 52.499514 -137.800334)
		(end 52.099972 -138.199876)
		(width 0.127)
		(layer "F.Cu")
		(net "PWRBTN_OUT_N_R")
	)
	(via
		(at 52.499768 -137.800334)
		(size 0.4572)
		(drill 0.2032)
		(layers "F.Cu" "B.Cu")
		(net "PWRBTN_OUT_N_R")
	)
	(via
		(at 51.7906 -137.827004)
		(size 0.6096)
		(drill 0.3048)
		(layers "F.Cu" "B.Cu")
		(net "PWRBTN_OUT_N_R")
	)
	(segment
		(start 51.7906 -137.827004)
		(end 52.473098 -137.827004)
		(width 0.127)
		(layer "B.Cu")
		(net "PWRBTN_OUT_N_R")
	)
	(segment
		(start 52.473098 -137.827004)
		(end 52.499768 -137.800334)
		(width 0.127)
		(layer "B.Cu")
		(net "PWRBTN_OUT_N_R")
	)
	(segment
		(start 51.4858 -137.522204)
		(end 51.7906 -137.827004)
		(width 0.127)
		(layer "B.Cu")
		(net "PWRBTN_OUT_N_R")
	)
	(segment
		(start 51.4858 -136.1821)
		(end 51.4858 -137.522204)
		(width 0.127)
		(layer "B.Cu")
		(net "PWRBTN_OUT_N_R")
	)
	(segment
		(start 91.751658 -160.0962)
		(end 91.751658 -158.47568)
		(width 0.127)
		(layer "F.Cu")
		(net "PLLFILT")
	)
	(segment
		(start 91.396058 -160.4518)
		(end 91.751658 -160.0962)
		(width 0.127)
		(layer "F.Cu")
		(net "PLLFILT")
	)
	(segment
		(start 89.65692 -161.496756)
		(end 90.701876 -160.4518)
		(width 0.127)
		(layer "F.Cu")
		(net "PLLFILT")
	)
	(segment
		(start 89.65692 -161.572956)
		(end 89.65692 -161.496756)
		(width 0.127)
		(layer "F.Cu")
		(net "PLLFILT")
	)
	(segment
		(start 90.701876 -160.4518)
		(end 91.396058 -160.4518)
		(width 0.127)
		(layer "F.Cu")
		(net "PLLFILT")
	)
	(via
		(at 91.751658 -160.0962)
		(size 0.508)
		(drill 0.254)
		(layers "F.Cu" "B.Cu")
		(net "PLLFILT")
	)
	(segment
		(start 91.421966 -159.160718)
		(end 91.421966 -159.766508)
		(width 0.127)
		(layer "B.Cu")
		(net "PLLFILT")
	)
	(segment
		(start 91.421966 -159.766508)
		(end 91.751658 -160.0962)
		(width 0.127)
		(layer "B.Cu")
		(net "PLLFILT")
	)
	(segment
		(start 186.714638 -151.289766)
		(end 187.044076 -150.960328)
		(width 0.254)
		(layer "F.Cu")
		(net "P5V_VFB_R")
	)
	(segment
		(start 185.693304 -151.289766)
		(end 186.714638 -151.289766)
		(width 0.254)
		(layer "F.Cu")
		(net "P5V_VFB_R")
	)
	(segment
		(start 187.044076 -150.4061)
		(end 186.797442 -150.159466)
		(width 0.254)
		(layer "F.Cu")
		(net "P5V_VFB_R")
	)
	(segment
		(start 184.829704 -150.159466)
		(end 185.845704 -150.159466)
		(width 0.254)
		(layer "F.Cu")
		(net "P5V_VFB_R")
	)
	(segment
		(start 187.044076 -150.769066)
		(end 187.044076 -150.4061)
		(width 0.254)
		(layer "F.Cu")
		(net "P5V_VFB_R")
	)
	(segment
		(start 186.797442 -150.159466)
		(end 185.845704 -150.159466)
		(width 0.254)
		(layer "F.Cu")
		(net "P5V_VFB_R")
	)
	(segment
		(start 187.044076 -150.960328)
		(end 187.044076 -150.769066)
		(width 0.254)
		(layer "F.Cu")
		(net "P5V_VFB_R")
	)
	(via
		(at 187.044076 -150.769066)
		(size 0.6604)
		(drill 0.3302)
		(layers "F.Cu" "B.Cu")
		(net "P5V_VFB_R")
	)
	(segment
		(start 184.829704 -149.270466)
		(end 183.813704 -149.270466)
		(width 0.254)
		(layer "F.Cu")
		(net "P5V_VFB")
	)
	(segment
		(start 185.845704 -149.270466)
		(end 185.845704 -148.741638)
		(width 0.254)
		(layer "F.Cu")
		(net "P5V_VFB")
	)
	(segment
		(start 182.197756 -149.159468)
		(end 182.918608 -149.159468)
		(width 0.254)
		(layer "F.Cu")
		(net "P5V_VFB")
	)
	(segment
		(start 182.918608 -149.159468)
		(end 183.029606 -149.270466)
		(width 0.254)
		(layer "F.Cu")
		(net "P5V_VFB")
	)
	(segment
		(start 180.438806 -149.159468)
		(end 182.197756 -149.159468)
		(width 0.254)
		(layer "F.Cu")
		(net "P5V_VFB")
	)
	(segment
		(start 185.845704 -148.741638)
		(end 185.363866 -148.2598)
		(width 0.254)
		(layer "F.Cu")
		(net "P5V_VFB")
	)
	(segment
		(start 185.845704 -149.270466)
		(end 184.829704 -149.270466)
		(width 0.254)
		(layer "F.Cu")
		(net "P5V_VFB")
	)
	(segment
		(start 183.029606 -149.270466)
		(end 183.813704 -149.270466)
		(width 0.254)
		(layer "F.Cu")
		(net "P5V_VFB")
	)
	(segment
		(start 185.363866 -148.2598)
		(end 184.912 -148.2598)
		(width 0.254)
		(layer "F.Cu")
		(net "P5V_VFB")
	)
	(via
		(at 182.197756 -149.159468)
		(size 0.6604)
		(drill 0.3302)
		(layers "F.Cu" "B.Cu")
		(net "P5V_VFB")
	)
	(via
		(at 177.774346 -153.15438)
		(size 0.6096)
		(drill 0.3048)
		(layers "F.Cu" "B.Cu")
		(net "P5V_VBST_RC")
	)
	(segment
		(start 179.368958 -153.15438)
		(end 179.452524 -153.237946)
		(width 0.508)
		(layer "B.Cu")
		(net "P5V_VBST_RC")
	)
	(segment
		(start 177.774346 -154.319732)
		(end 177.774346 -153.15438)
		(width 0.508)
		(layer "B.Cu")
		(net "P5V_VBST_RC")
	)
	(segment
		(start 177.774346 -153.15438)
		(end 179.368958 -153.15438)
		(width 0.508)
		(layer "B.Cu")
		(net "P5V_VBST_RC")
	)
	(segment
		(start 179.114704 -150.730966)
		(end 178.938682 -150.554944)
		(width 0.254)
		(layer "F.Cu")
		(net "P5V_VBST")
	)
	(segment
		(start 178.938682 -150.554944)
		(end 178.938682 -149.159468)
		(width 0.254)
		(layer "F.Cu")
		(net "P5V_VBST")
	)
	(via
		(at 180.659024 -151.256746)
		(size 0.6096)
		(drill 0.3048)
		(layers "F.Cu" "B.Cu")
		(net "P5V_VBST")
	)
	(via
		(at 179.114704 -150.730966)
		(size 0.508)
		(drill 0.254)
		(layers "F.Cu" "B.Cu")
		(net "P5V_VBST")
	)
	(segment
		(start 179.114704 -150.730966)
		(end 180.133244 -150.730966)
		(width 0.508)
		(layer "B.Cu")
		(net "P5V_VBST")
	)
	(segment
		(start 180.201824 -151.713946)
		(end 180.659024 -151.256746)
		(width 0.508)
		(layer "B.Cu")
		(net "P5V_VBST")
	)
	(segment
		(start 180.133244 -150.730966)
		(end 180.659024 -151.256746)
		(width 0.508)
		(layer "B.Cu")
		(net "P5V_VBST")
	)
	(segment
		(start 179.452524 -151.713946)
		(end 180.201824 -151.713946)
		(width 0.508)
		(layer "B.Cu")
		(net "P5V_VBST")
	)
	(segment
		(start 182.036466 -142.526766)
		(end 182.9181 -143.4084)
		(width 0.254)
		(layer "F.Cu")
		(net "P5V_TRIP")
	)
	(segment
		(start 179.93868 -143.68399)
		(end 180.376576 -143.246094)
		(width 0.254)
		(layer "F.Cu")
		(net "P5V_TRIP")
	)
	(segment
		(start 181.553358 -142.526766)
		(end 182.036466 -142.526766)
		(width 0.254)
		(layer "F.Cu")
		(net "P5V_TRIP")
	)
	(segment
		(start 179.93868 -144.260824)
		(end 179.93868 -143.68399)
		(width 0.254)
		(layer "F.Cu")
		(net "P5V_TRIP")
	)
	(segment
		(start 180.376576 -143.246094)
		(end 180.83403 -143.246094)
		(width 0.254)
		(layer "F.Cu")
		(net "P5V_TRIP")
	)
	(segment
		(start 180.83403 -143.246094)
		(end 181.553358 -142.526766)
		(width 0.254)
		(layer "F.Cu")
		(net "P5V_TRIP")
	)
	(via
		(at 181.553358 -142.526766)
		(size 0.6604)
		(drill 0.3302)
		(layers "F.Cu" "B.Cu")
		(net "P5V_TRIP")
	)
	(segment
		(start 178.584352 -141.779752)
		(end 178.584352 -140.614908)
		(width 0.254)
		(layer "F.Cu")
		(net "P5V_STBY_VREG")
	)
	(segment
		(start 178.584352 -140.244068)
		(end 179.20716 -139.62126)
		(width 0.254)
		(layer "F.Cu")
		(net "P5V_STBY_VREG")
	)
	(segment
		(start 180.3654 -138.5824)
		(end 179.7812 -138.5824)
		(width 0.254)
		(layer "F.Cu")
		(net "P5V_STBY_VREG")
	)
	(segment
		(start 178.7652 -153.6573)
		(end 178.7652 -154.5336)
		(width 0.254)
		(layer "F.Cu")
		(net "P5V_STBY_VREG")
	)
	(segment
		(start 178.43881 -142.57274)
		(end 178.6128 -142.39875)
		(width 0.254)
		(layer "F.Cu")
		(net "P5V_STBY_VREG")
	)
	(segment
		(start 178.6128 -141.8082)
		(end 178.584352 -141.779752)
		(width 0.254)
		(layer "F.Cu")
		(net "P5V_STBY_VREG")
	)
	(segment
		(start 179.20716 -139.15644)
		(end 179.4764 -138.8872)
		(width 0.254)
		(layer "F.Cu")
		(net "P5V_STBY_VREG")
	)
	(segment
		(start 179.7812 -138.5824)
		(end 179.4764 -138.8872)
		(width 0.254)
		(layer "F.Cu")
		(net "P5V_STBY_VREG")
	)
	(segment
		(start 178.43881 -144.260824)
		(end 178.43881 -142.57274)
		(width 0.254)
		(layer "F.Cu")
		(net "P5V_STBY_VREG")
	)
	(segment
		(start 178.6128 -142.39875)
		(end 178.6128 -141.8082)
		(width 0.254)
		(layer "F.Cu")
		(net "P5V_STBY_VREG")
	)
	(segment
		(start 178.584352 -140.614908)
		(end 178.584352 -140.244068)
		(width 0.254)
		(layer "F.Cu")
		(net "P5V_STBY_VREG")
	)
	(segment
		(start 179.20716 -139.62126)
		(end 179.20716 -139.15644)
		(width 0.254)
		(layer "F.Cu")
		(net "P5V_STBY_VREG")
	)
	(via
		(at 180.3654 -138.5824)
		(size 0.508)
		(drill 0.254)
		(layers "F.Cu" "B.Cu")
		(net "P5V_STBY_VREG")
	)
	(via
		(at 179.4764 -138.8872)
		(size 0.6604)
		(drill 0.3302)
		(layers "F.Cu" "B.Cu")
		(net "P5V_STBY_VREG")
	)
	(via
		(at 178.7652 -154.5336)
		(size 0.508)
		(drill 0.254)
		(layers "F.Cu" "B.Cu")
		(net "P5V_STBY_VREG")
	)
	(segment
		(start 180.3654 -138.5824)
		(end 181.0766 -139.2936)
		(width 0.254)
		(layer "In2.Cu")
		(net "P5V_STBY_VREG")
	)
	(segment
		(start 183.041544 -139.2936)
		(end 185.5724 -141.824456)
		(width 0.254)
		(layer "In2.Cu")
		(net "P5V_STBY_VREG")
	)
	(segment
		(start 185.5724 -149.63775)
		(end 181.23535 -153.9748)
		(width 0.254)
		(layer "In2.Cu")
		(net "P5V_STBY_VREG")
	)
	(segment
		(start 181.0766 -139.2936)
		(end 183.041544 -139.2936)
		(width 0.254)
		(layer "In2.Cu")
		(net "P5V_STBY_VREG")
	)
	(segment
		(start 185.5724 -141.824456)
		(end 185.5724 -149.63775)
		(width 0.254)
		(layer "In2.Cu")
		(net "P5V_STBY_VREG")
	)
	(segment
		(start 179.324 -153.9748)
		(end 178.7652 -154.5336)
		(width 0.254)
		(layer "In2.Cu")
		(net "P5V_STBY_VREG")
	)
	(segment
		(start 181.23535 -153.9748)
		(end 179.324 -153.9748)
		(width 0.254)
		(layer "In2.Cu")
		(net "P5V_STBY_VREG")
	)
	(segment
		(start 171.753276 -148.889466)
		(end 170.336718 -148.889466)
		(width 0.508)
		(layer "F.Cu")
		(net "P5V_SNB")
	)
	(segment
		(start 170.336718 -148.889466)
		(end 169.977308 -148.530056)
		(width 0.508)
		(layer "F.Cu")
		(net "P5V_SNB")
	)
	(segment
		(start 169.977308 -147.234402)
		(end 170.000676 -147.211034)
		(width 0.508)
		(layer "F.Cu")
		(net "P5V_SNB")
	)
	(segment
		(start 171.621704 -147.211034)
		(end 170.000676 -147.211034)
		(width 0.508)
		(layer "F.Cu")
		(net "P5V_SNB")
	)
	(segment
		(start 169.977308 -148.530056)
		(end 169.977308 -147.234402)
		(width 0.508)
		(layer "F.Cu")
		(net "P5V_SNB")
	)
	(via
		(at 170.000676 -147.211034)
		(size 0.6604)
		(drill 0.3302)
		(layers "F.Cu" "B.Cu")
		(net "P5V_SNB")
	)
	(segment
		(start 182.221124 -144.260824)
		(end 181.5592 -144.260824)
		(width 0.254)
		(layer "F.Cu")
		(net "P5V_RF")
	)
	(segment
		(start 179.473352 -140.338048)
		(end 180.34 -139.4714)
		(width 0.254)
		(layer "F.Cu")
		(net "P5V_RF")
	)
	(segment
		(start 182.5117 -144.5514)
		(end 182.221124 -144.260824)
		(width 0.254)
		(layer "F.Cu")
		(net "P5V_RF")
	)
	(segment
		(start 181.5592 -144.260824)
		(end 180.438806 -144.260824)
		(width 0.254)
		(layer "F.Cu")
		(net "P5V_RF")
	)
	(segment
		(start 179.473352 -140.614908)
		(end 179.473352 -140.338048)
		(width 0.254)
		(layer "F.Cu")
		(net "P5V_RF")
	)
	(via
		(at 181.5592 -144.260824)
		(size 0.508)
		(drill 0.254)
		(layers "F.Cu" "B.Cu")
		(net "P5V_RF")
	)
	(via
		(at 181.976268 -142.30604)
		(size 0.6096)
		(drill 0.3048)
		(layers "F.Cu" "B.Cu")
		(net "P5V_RF")
	)
	(via
		(at 180.34 -139.4714)
		(size 0.508)
		(drill 0.254)
		(layers "F.Cu" "B.Cu")
		(net "P5V_RF")
	)
	(segment
		(start 181.976268 -143.843756)
		(end 181.976268 -142.30604)
		(width 0.254)
		(layer "B.Cu")
		(net "P5V_RF")
	)
	(segment
		(start 180.34 -139.4714)
		(end 180.34 -139.626594)
		(width 0.254)
		(layer "B.Cu")
		(net "P5V_RF")
	)
	(segment
		(start 181.976268 -141.262862)
		(end 181.976268 -142.30604)
		(width 0.254)
		(layer "B.Cu")
		(net "P5V_RF")
	)
	(segment
		(start 181.5592 -144.260824)
		(end 181.976268 -143.843756)
		(width 0.254)
		(layer "B.Cu")
		(net "P5V_RF")
	)
	(segment
		(start 180.34 -139.626594)
		(end 181.976268 -141.262862)
		(width 0.254)
		(layer "B.Cu")
		(net "P5V_RF")
	)
	(segment
		(start 182.511954 -141.212062)
		(end 182.511954 -141.751558)
		(width 0.254)
		(layer "F.Cu")
		(net "P5V_MODE")
	)
	(segment
		(start 182.9181 -142.157704)
		(end 182.9181 -142.3924)
		(width 0.254)
		(layer "F.Cu")
		(net "P5V_MODE")
	)
	(segment
		(start 179.438808 -143.572992)
		(end 179.438808 -144.260824)
		(width 0.254)
		(layer "F.Cu")
		(net "P5V_MODE")
	)
	(segment
		(start 181.24805 -141.86916)
		(end 180.62321 -142.494)
		(width 0.254)
		(layer "F.Cu")
		(net "P5V_MODE")
	)
	(segment
		(start 181.317646 -141.212062)
		(end 182.511954 -141.212062)
		(width 0.254)
		(layer "F.Cu")
		(net "P5V_MODE")
	)
	(segment
		(start 181.24805 -141.281658)
		(end 181.317646 -141.212062)
		(width 0.254)
		(layer "F.Cu")
		(net "P5V_MODE")
	)
	(segment
		(start 179.755546 -142.96898)
		(end 179.755546 -143.256254)
		(width 0.254)
		(layer "F.Cu")
		(net "P5V_MODE")
	)
	(segment
		(start 182.511954 -141.751558)
		(end 182.9181 -142.157704)
		(width 0.254)
		(layer "F.Cu")
		(net "P5V_MODE")
	)
	(segment
		(start 179.755546 -143.256254)
		(end 179.438808 -143.572992)
		(width 0.254)
		(layer "F.Cu")
		(net "P5V_MODE")
	)
	(segment
		(start 180.230526 -142.494)
		(end 179.755546 -142.96898)
		(width 0.254)
		(layer "F.Cu")
		(net "P5V_MODE")
	)
	(segment
		(start 181.24805 -141.281658)
		(end 181.24805 -141.86916)
		(width 0.254)
		(layer "F.Cu")
		(net "P5V_MODE")
	)
	(segment
		(start 180.62321 -142.494)
		(end 180.230526 -142.494)
		(width 0.254)
		(layer "F.Cu")
		(net "P5V_MODE")
	)
	(via
		(at 182.511954 -141.212062)
		(size 0.6604)
		(drill 0.3302)
		(layers "F.Cu" "B.Cu")
		(net "P5V_MODE")
	)
	(segment
		(start 180.6575 -156.5275)
		(end 181.356 -157.226)
		(width 0.254)
		(layer "F.Cu")
		(net "P5V_LL_R")
	)
	(segment
		(start 181.356 -157.226)
		(end 181.906164 -157.776164)
		(width 0.254)
		(layer "F.Cu")
		(net "P5V_LL_R")
	)
	(segment
		(start 183.813704 -150.159466)
		(end 183.813704 -151.433276)
		(width 0.254)
		(layer "F.Cu")
		(net "P5V_LL_R")
	)
	(segment
		(start 184.5564 -154.2542)
		(end 184.879488 -154.577288)
		(width 0.254)
		(layer "F.Cu")
		(net "P5V_LL_R")
	)
	(segment
		(start 183.813704 -151.433276)
		(end 184.5564 -152.175972)
		(width 0.254)
		(layer "F.Cu")
		(net "P5V_LL_R")
	)
	(segment
		(start 180.6575 -156.083)
		(end 180.6575 -156.5275)
		(width 0.254)
		(layer "F.Cu")
		(net "P5V_LL_R")
	)
	(segment
		(start 184.5564 -152.175972)
		(end 184.5564 -154.2542)
		(width 0.254)
		(layer "F.Cu")
		(net "P5V_LL_R")
	)
	(segment
		(start 181.906164 -157.776164)
		(end 183.74741 -157.776164)
		(width 0.254)
		(layer "F.Cu")
		(net "P5V_LL_R")
	)
	(segment
		(start 184.879488 -156.644086)
		(end 183.74741 -157.776164)
		(width 0.254)
		(layer "F.Cu")
		(net "P5V_LL_R")
	)
	(segment
		(start 184.879488 -154.577288)
		(end 184.879488 -156.644086)
		(width 0.254)
		(layer "F.Cu")
		(net "P5V_LL_R")
	)
	(via
		(at 183.74741 -157.776164)
		(size 0.6604)
		(drill 0.3302)
		(layers "F.Cu" "B.Cu")
		(net "P5V_LL_R")
	)
	(segment
		(start 179.4637 -156.3878)
		(end 173.1518 -156.3878)
		(width 0.254)
		(layer "F.Cu")
		(net "P5V_LL")
	)
	(segment
		(start 173.1518 -156.3878)
		(end 172.6692 -155.9052)
		(width 0.254)
		(layer "F.Cu")
		(net "P5V_LL")
	)
	(segment
		(start 172.6692 -155.9052)
		(end 172.6692 -152.333706)
		(width 0.254)
		(layer "F.Cu")
		(net "P5V_LL")
	)
	(segment
		(start 179.7685 -156.083)
		(end 179.4637 -156.3878)
		(width 0.254)
		(layer "F.Cu")
		(net "P5V_LL")
	)
	(via
		(at 176.2506 -151.8412)
		(size 0.508)
		(drill 0.254)
		(layers "F.Cu" "B.Cu")
		(net "P5V_LL")
	)
	(via
		(at 176.276 -153.162)
		(size 0.6096)
		(drill 0.3048)
		(layers "F.Cu" "B.Cu")
		(net "P5V_LL")
	)
	(segment
		(start 176.276 -153.162)
		(end 176.276 -151.8666)
		(width 0.508)
		(layer "B.Cu")
		(net "P5V_LL")
	)
	(segment
		(start 176.250346 -153.187654)
		(end 176.276 -153.162)
		(width 0.508)
		(layer "B.Cu")
		(net "P5V_LL")
	)
	(segment
		(start 176.250346 -154.319732)
		(end 176.250346 -153.187654)
		(width 0.508)
		(layer "B.Cu")
		(net "P5V_LL")
	)
	(segment
		(start 176.276 -151.8666)
		(end 176.2506 -151.8412)
		(width 0.508)
		(layer "B.Cu")
		(net "P5V_LL")
	)
	(segment
		(start 179.93868 -149.767798)
		(end 180.614574 -150.443692)
		(width 0.254)
		(layer "F.Cu")
		(net "P5V_EN_R")
	)
	(segment
		(start 181.896004 -151.975566)
		(end 181.896004 -150.883366)
		(width 0.254)
		(layer "F.Cu")
		(net "P5V_EN_R")
	)
	(segment
		(start 180.614574 -150.443692)
		(end 180.614574 -151.186642)
		(width 0.254)
		(layer "F.Cu")
		(net "P5V_EN_R")
	)
	(segment
		(start 181.9402 -153.3398)
		(end 181.896004 -153.295604)
		(width 0.254)
		(layer "F.Cu")
		(net "P5V_EN_R")
	)
	(segment
		(start 181.245256 -151.186642)
		(end 180.614574 -151.186642)
		(width 0.254)
		(layer "F.Cu")
		(net "P5V_EN_R")
	)
	(segment
		(start 181.95163 -153.35123)
		(end 181.9402 -153.3398)
		(width 0.254)
		(layer "F.Cu")
		(net "P5V_EN_R")
	)
	(segment
		(start 181.896004 -150.883366)
		(end 181.548532 -150.883366)
		(width 0.254)
		(layer "F.Cu")
		(net "P5V_EN_R")
	)
	(segment
		(start 181.896004 -153.295604)
		(end 181.896004 -151.975566)
		(width 0.254)
		(layer "F.Cu")
		(net "P5V_EN_R")
	)
	(segment
		(start 181.548532 -150.883366)
		(end 181.245256 -151.186642)
		(width 0.254)
		(layer "F.Cu")
		(net "P5V_EN_R")
	)
	(segment
		(start 179.93868 -149.159468)
		(end 179.93868 -149.767798)
		(width 0.254)
		(layer "F.Cu")
		(net "P5V_EN_R")
	)
	(segment
		(start 181.95163 -154.51836)
		(end 181.95163 -153.35123)
		(width 0.254)
		(layer "F.Cu")
		(net "P5V_EN_R")
	)
	(via
		(at 180.614574 -151.186642)
		(size 0.6604)
		(drill 0.3302)
		(layers "F.Cu" "B.Cu")
		(net "P5V_EN_R")
	)
	(segment
		(start 186.403488 -170.942)
		(end 186.403488 -159.893)
		(width 0.254)
		(layer "F.Cu")
		(net "P5V_CC")
	)
	(segment
		(start 186.403488 -153.52395)
		(end 185.693304 -152.813766)
		(width 0.254)
		(layer "F.Cu")
		(net "P5V_CC")
	)
	(segment
		(start 186.403488 -159.893)
		(end 186.403488 -153.52395)
		(width 0.254)
		(layer "F.Cu")
		(net "P5V_CC")
	)
	(segment
		(start 176.116488 -181.229)
		(end 186.403488 -170.942)
		(width 0.254)
		(layer "F.Cu")
		(net "P5V_CC")
	)
	(segment
		(start 169.799 -180.975)
		(end 170.053 -181.229)
		(width 0.254)
		(layer "F.Cu")
		(net "P5V_CC")
	)
	(segment
		(start 169.799 -180.3527)
		(end 169.799 -180.975)
		(width 0.254)
		(layer "F.Cu")
		(net "P5V_CC")
	)
	(segment
		(start 170.053 -181.229)
		(end 176.116488 -181.229)
		(width 0.254)
		(layer "F.Cu")
		(net "P5V_CC")
	)
	(via
		(at 186.403488 -159.893)
		(size 0.6604)
		(drill 0.3302)
		(layers "F.Cu" "B.Cu")
		(net "P5V_CC")
	)
	(via
		(at 39.584884 -183.713628)
		(size 0.6096)
		(drill 0.3048)
		(layers "F.Cu" "B.Cu")
		(net "P3V3_VBST_RC")
	)
	(segment
		(start 39.513256 -183.642)
		(end 39.584884 -183.713628)
		(width 0.508)
		(layer "B.Cu")
		(net "P3V3_VBST_RC")
	)
	(segment
		(start 38.0238 -183.642)
		(end 39.513256 -183.642)
		(width 0.508)
		(layer "B.Cu")
		(net "P3V3_VBST_RC")
	)
	(segment
		(start 39.58844 -183.710072)
		(end 39.584884 -183.713628)
		(width 0.508)
		(layer "B.Cu")
		(net "P3V3_VBST_RC")
	)
	(segment
		(start 40.884856 -183.710072)
		(end 39.58844 -183.710072)
		(width 0.508)
		(layer "B.Cu")
		(net "P3V3_VBST_RC")
	)
	(segment
		(start 38.139624 -180.570632)
		(end 36.744148 -180.570632)
		(width 0.254)
		(layer "F.Cu")
		(net "P3V3_VBST")
	)
	(segment
		(start 38.315646 -180.39461)
		(end 38.139624 -180.570632)
		(width 0.254)
		(layer "F.Cu")
		(net "P3V3_VBST")
	)
	(via
		(at 38.315646 -180.39461)
		(size 0.508)
		(drill 0.254)
		(layers "F.Cu" "B.Cu")
		(net "P3V3_VBST")
	)
	(segment
		(start 38.315646 -180.39461)
		(end 38.0238 -180.686456)
		(width 0.508)
		(layer "B.Cu")
		(net "P3V3_VBST")
	)
	(segment
		(start 38.0238 -180.686456)
		(end 38.0238 -181.7116)
		(width 0.508)
		(layer "B.Cu")
		(net "P3V3_VBST")
	)
	(segment
		(start 27.67584 -181.1909)
		(end 27.01417 -180.52923)
		(width 0.254)
		(layer "F.Cu")
		(net "P3V3_STBY_VREG")
	)
	(segment
		(start 31.845504 -181.070504)
		(end 29.397452 -181.070504)
		(width 0.254)
		(layer "F.Cu")
		(net "P3V3_STBY_VREG")
	)
	(segment
		(start 28.2448 -181.1909)
		(end 27.67584 -181.1909)
		(width 0.254)
		(layer "F.Cu")
		(net "P3V3_STBY_VREG")
	)
	(segment
		(start 29.397452 -181.070504)
		(end 29.367226 -181.10073)
		(width 0.254)
		(layer "F.Cu")
		(net "P3V3_STBY_VREG")
	)
	(segment
		(start 40.220646 -178.68011)
		(end 41.300146 -178.68011)
		(width 0.254)
		(layer "F.Cu")
		(net "P3V3_STBY_VREG")
	)
	(segment
		(start 28.33497 -181.10073)
		(end 28.2448 -181.1909)
		(width 0.254)
		(layer "F.Cu")
		(net "P3V3_STBY_VREG")
	)
	(segment
		(start 29.367226 -181.10073)
		(end 28.33497 -181.10073)
		(width 0.254)
		(layer "F.Cu")
		(net "P3V3_STBY_VREG")
	)
	(segment
		(start 41.300146 -178.68011)
		(end 41.490646 -178.48961)
		(width 0.254)
		(layer "F.Cu")
		(net "P3V3_STBY_VREG")
	)
	(via
		(at 29.361892 -179.889912)
		(size 0.6096)
		(drill 0.3048)
		(layers "F.Cu" "B.Cu")
		(net "P3V3_STBY_VREG")
	)
	(via
		(at 41.490646 -178.48961)
		(size 0.508)
		(drill 0.254)
		(layers "F.Cu" "B.Cu")
		(net "P3V3_STBY_VREG")
	)
	(via
		(at 27.01417 -180.52923)
		(size 0.508)
		(drill 0.254)
		(layers "F.Cu" "B.Cu")
		(net "P3V3_STBY_VREG")
	)
	(segment
		(start 29.915358 -179.336446)
		(end 29.361892 -179.889912)
		(width 0.254)
		(layer "B.Cu")
		(net "P3V3_STBY_VREG")
	)
	(segment
		(start 41.490646 -178.48961)
		(end 39.233602 -178.48961)
		(width 0.254)
		(layer "B.Cu")
		(net "P3V3_STBY_VREG")
	)
	(segment
		(start 39.233602 -178.48961)
		(end 38.884352 -178.14036)
		(width 0.254)
		(layer "B.Cu")
		(net "P3V3_STBY_VREG")
	)
	(segment
		(start 27.01417 -180.52923)
		(end 28.722574 -180.52923)
		(width 0.254)
		(layer "B.Cu")
		(net "P3V3_STBY_VREG")
	)
	(segment
		(start 28.722574 -180.52923)
		(end 29.361892 -179.889912)
		(width 0.254)
		(layer "B.Cu")
		(net "P3V3_STBY_VREG")
	)
	(segment
		(start 38.884352 -178.14036)
		(end 32.842708 -178.14036)
		(width 0.254)
		(layer "B.Cu")
		(net "P3V3_STBY_VREG")
	)
	(segment
		(start 32.842708 -178.14036)
		(end 31.646622 -179.336446)
		(width 0.254)
		(layer "B.Cu")
		(net "P3V3_STBY_VREG")
	)
	(segment
		(start 31.646622 -179.336446)
		(end 29.915358 -179.336446)
		(width 0.254)
		(layer "B.Cu")
		(net "P3V3_STBY_VREG")
	)
	(segment
		(start 37.744146 -174.67961)
		(end 37.744146 -173.66361)
		(width 0.254)
		(layer "F.Cu")
		(net "P3V3_STBY_VFB_R")
	)
	(segment
		(start 38.950646 -174.67961)
		(end 37.744146 -174.67961)
		(width 0.254)
		(layer "F.Cu")
		(net "P3V3_STBY_VFB_R")
	)
	(segment
		(start 35.839146 -174.67961)
		(end 35.839146 -174.055786)
		(width 0.254)
		(layer "F.Cu")
		(net "P3V3_STBY_VFB")
	)
	(segment
		(start 36.8681 -175.6664)
		(end 36.8681 -176.749456)
		(width 0.254)
		(layer "F.Cu")
		(net "P3V3_STBY_VFB")
	)
	(segment
		(start 36.240974 -173.653958)
		(end 36.845494 -173.653958)
		(width 0.254)
		(layer "F.Cu")
		(net "P3V3_STBY_VFB")
	)
	(segment
		(start 36.744148 -176.873408)
		(end 36.744148 -177.188622)
		(width 0.254)
		(layer "F.Cu")
		(net "P3V3_STBY_VFB")
	)
	(segment
		(start 36.8681 -176.749456)
		(end 36.744148 -176.873408)
		(width 0.254)
		(layer "F.Cu")
		(net "P3V3_STBY_VFB")
	)
	(segment
		(start 36.845494 -173.653958)
		(end 36.855146 -173.66361)
		(width 0.254)
		(layer "F.Cu")
		(net "P3V3_STBY_VFB")
	)
	(segment
		(start 36.744148 -179.070508)
		(end 36.744148 -177.188622)
		(width 0.254)
		(layer "F.Cu")
		(net "P3V3_STBY_VFB")
	)
	(segment
		(start 35.839146 -174.055786)
		(end 36.240974 -173.653958)
		(width 0.254)
		(layer "F.Cu")
		(net "P3V3_STBY_VFB")
	)
	(segment
		(start 36.8681 -174.692564)
		(end 36.8681 -175.6664)
		(width 0.254)
		(layer "F.Cu")
		(net "P3V3_STBY_VFB")
	)
	(segment
		(start 36.855146 -174.67961)
		(end 36.8681 -174.692564)
		(width 0.254)
		(layer "F.Cu")
		(net "P3V3_STBY_VFB")
	)
	(segment
		(start 36.855146 -173.66361)
		(end 36.855146 -174.67961)
		(width 0.254)
		(layer "F.Cu")
		(net "P3V3_STBY_VFB")
	)
	(via
		(at 36.744148 -177.188622)
		(size 0.6604)
		(drill 0.3302)
		(layers "F.Cu" "B.Cu")
		(net "P3V3_STBY_VFB")
	)
	(segment
		(start 30.861254 -179.163218)
		(end 30.861254 -177.558446)
		(width 0.254)
		(layer "F.Cu")
		(net "P3V3_STBY_TRIP")
	)
	(segment
		(start 31.845504 -179.570634)
		(end 31.26867 -179.570634)
		(width 0.254)
		(layer "F.Cu")
		(net "P3V3_STBY_TRIP")
	)
	(segment
		(start 29.832046 -177.062638)
		(end 30.365446 -177.062638)
		(width 0.254)
		(layer "F.Cu")
		(net "P3V3_STBY_TRIP")
	)
	(segment
		(start 30.365446 -177.062638)
		(end 30.861254 -177.558446)
		(width 0.254)
		(layer "F.Cu")
		(net "P3V3_STBY_TRIP")
	)
	(segment
		(start 31.26867 -179.570634)
		(end 30.861254 -179.163218)
		(width 0.254)
		(layer "F.Cu")
		(net "P3V3_STBY_TRIP")
	)
	(via
		(at 30.861254 -177.558446)
		(size 0.6604)
		(drill 0.3302)
		(layers "F.Cu" "B.Cu")
		(net "P3V3_STBY_TRIP")
	)
	(segment
		(start 38.655752 -181.070504)
		(end 36.744148 -181.070504)
		(width 0.254)
		(layer "F.Cu")
		(net "P3V3_STBY_ROVP")
	)
	(segment
		(start 39.077646 -180.64861)
		(end 38.655752 -181.070504)
		(width 0.254)
		(layer "F.Cu")
		(net "P3V3_STBY_ROVP")
	)
	(segment
		(start 39.395146 -180.64861)
		(end 39.077646 -180.64861)
		(width 0.254)
		(layer "F.Cu")
		(net "P3V3_STBY_ROVP")
	)
	(segment
		(start 28.2448 -180.3019)
		(end 27.808936 -180.3019)
		(width 0.254)
		(layer "F.Cu")
		(net "P3V3_STBY_RF")
	)
	(segment
		(start 30.873446 -176.478438)
		(end 31.845504 -177.450496)
		(width 0.254)
		(layer "F.Cu")
		(net "P3V3_STBY_RF")
	)
	(segment
		(start 31.845504 -178.085496)
		(end 31.845504 -179.070508)
		(width 0.254)
		(layer "F.Cu")
		(net "P3V3_STBY_RF")
	)
	(segment
		(start 27.808936 -180.3019)
		(end 27.147266 -179.64023)
		(width 0.254)
		(layer "F.Cu")
		(net "P3V3_STBY_RF")
	)
	(segment
		(start 31.845504 -177.450496)
		(end 31.845504 -178.085496)
		(width 0.254)
		(layer "F.Cu")
		(net "P3V3_STBY_RF")
	)
	(via
		(at 27.147266 -179.64023)
		(size 0.508)
		(drill 0.254)
		(layers "F.Cu" "B.Cu")
		(net "P3V3_STBY_RF")
	)
	(via
		(at 30.225492 -178.085496)
		(size 0.6096)
		(drill 0.3048)
		(layers "F.Cu" "B.Cu")
		(net "P3V3_STBY_RF")
	)
	(via
		(at 31.845504 -178.085496)
		(size 0.508)
		(drill 0.254)
		(layers "F.Cu" "B.Cu")
		(net "P3V3_STBY_RF")
	)
	(segment
		(start 27.147266 -179.64023)
		(end 27.7368 -179.050696)
		(width 0.254)
		(layer "B.Cu")
		(net "P3V3_STBY_RF")
	)
	(segment
		(start 28.627324 -178.085496)
		(end 30.225492 -178.085496)
		(width 0.254)
		(layer "B.Cu")
		(net "P3V3_STBY_RF")
	)
	(segment
		(start 27.7368 -178.97602)
		(end 28.627324 -178.085496)
		(width 0.254)
		(layer "B.Cu")
		(net "P3V3_STBY_RF")
	)
	(segment
		(start 27.7368 -179.050696)
		(end 27.7368 -178.97602)
		(width 0.254)
		(layer "B.Cu")
		(net "P3V3_STBY_RF")
	)
	(segment
		(start 31.845504 -178.085496)
		(end 30.225492 -178.085496)
		(width 0.254)
		(layer "B.Cu")
		(net "P3V3_STBY_RF")
	)
	(segment
		(start 43.0022 -184.1246)
		(end 43.0022 -180.0733)
		(width 0.254)
		(layer "F.Cu")
		(net "P3V3_STBY_OUT")
	)
	(segment
		(start 43.0022 -180.0733)
		(end 43.2054 -179.8701)
		(width 0.254)
		(layer "F.Cu")
		(net "P3V3_STBY_OUT")
	)
	(segment
		(start 59.0042 -181.0004)
		(end 59.0042 -178.8922)
		(width 0.381)
		(layer "F.Cu")
		(net "P3V3_STBY_OUT")
	)
	(segment
		(start 43.4086 -184.531)
		(end 43.0022 -184.1246)
		(width 0.254)
		(layer "F.Cu")
		(net "P3V3_STBY_OUT")
	)
	(segment
		(start 42.52087 -174.67961)
		(end 40.474646 -174.67961)
		(width 0.381)
		(layer "F.Cu")
		(net "P3V3_STBY_OUT")
	)
	(segment
		(start 45.349922 -184.531)
		(end 43.4086 -184.531)
		(width 0.254)
		(layer "F.Cu")
		(net "P3V3_STBY_OUT")
	)
	(segment
		(start 59.0042 -178.8922)
		(end 58.348626 -178.236626)
		(width 0.381)
		(layer "F.Cu")
		(net "P3V3_STBY_OUT")
	)
	(segment
		(start 46.077886 -178.236626)
		(end 42.52087 -174.67961)
		(width 0.381)
		(layer "F.Cu")
		(net "P3V3_STBY_OUT")
	)
	(segment
		(start 58.348626 -178.236626)
		(end 46.077886 -178.236626)
		(width 0.381)
		(layer "F.Cu")
		(net "P3V3_STBY_OUT")
	)
	(via
		(at 56.384698 -185.046112)
		(size 0.6604)
		(drill 0.3302)
		(layers "F.Cu" "B.Cu")
		(net "P3V3_STBY_OUT")
	)
	(via
		(at 56.465724 -187.414154)
		(size 0.6604)
		(drill 0.3302)
		(layers "F.Cu" "B.Cu")
		(net "P3V3_STBY_OUT")
	)
	(segment
		(start 30.187646 -178.74361)
		(end 29.912818 -178.468782)
		(width 0.254)
		(layer "F.Cu")
		(net "P3V3_STBY_MODE")
	)
	(segment
		(start 28.790646 -178.17211)
		(end 29.616146 -178.17211)
		(width 0.254)
		(layer "F.Cu")
		(net "P3V3_STBY_MODE")
	)
	(segment
		(start 29.616146 -178.17211)
		(end 29.912818 -178.468782)
		(width 0.254)
		(layer "F.Cu")
		(net "P3V3_STBY_MODE")
	)
	(segment
		(start 31.845504 -180.070506)
		(end 31.048706 -180.070506)
		(width 0.254)
		(layer "F.Cu")
		(net "P3V3_STBY_MODE")
	)
	(segment
		(start 30.187646 -179.209446)
		(end 30.187646 -178.74361)
		(width 0.254)
		(layer "F.Cu")
		(net "P3V3_STBY_MODE")
	)
	(segment
		(start 28.790646 -177.062638)
		(end 28.790646 -178.17211)
		(width 0.254)
		(layer "F.Cu")
		(net "P3V3_STBY_MODE")
	)
	(segment
		(start 31.048706 -180.070506)
		(end 30.187646 -179.209446)
		(width 0.254)
		(layer "F.Cu")
		(net "P3V3_STBY_MODE")
	)
	(via
		(at 29.912818 -178.468782)
		(size 0.6604)
		(drill 0.3302)
		(layers "F.Cu" "B.Cu")
		(net "P3V3_STBY_MODE")
	)
	(segment
		(start 42.2656 -179.0065)
		(end 42.291 -178.9811)
		(width 0.254)
		(layer "F.Cu")
		(net "P3V3_STBY_LL_R")
	)
	(segment
		(start 37.7571 -175.6664)
		(end 38.565836 -175.6664)
		(width 0.254)
		(layer "F.Cu")
		(net "P3V3_STBY_LL_R")
	)
	(segment
		(start 42.291 -178.9811)
		(end 43.2054 -178.9811)
		(width 0.254)
		(layer "F.Cu")
		(net "P3V3_STBY_LL_R")
	)
	(segment
		(start 44.44111 -178.9811)
		(end 44.509182 -178.913028)
		(width 0.254)
		(layer "F.Cu")
		(net "P3V3_STBY_LL_R")
	)
	(segment
		(start 38.565836 -175.6664)
		(end 38.595046 -175.69561)
		(width 0.254)
		(layer "F.Cu")
		(net "P3V3_STBY_LL_R")
	)
	(segment
		(start 43.2054 -178.9811)
		(end 44.44111 -178.9811)
		(width 0.254)
		(layer "F.Cu")
		(net "P3V3_STBY_LL_R")
	)
	(via
		(at 44.509182 -178.913028)
		(size 0.508)
		(drill 0.254)
		(layers "F.Cu" "B.Cu")
		(net "P3V3_STBY_LL_R")
	)
	(via
		(at 38.595046 -175.69561)
		(size 0.508)
		(drill 0.254)
		(layers "F.Cu" "B.Cu")
		(net "P3V3_STBY_LL_R")
	)
	(via
		(at 41.172892 -177.09769)
		(size 0.6096)
		(drill 0.3048)
		(layers "F.Cu" "B.Cu")
		(net "P3V3_STBY_LL_R")
	)
	(segment
		(start 43.84167 -178.913028)
		(end 42.026332 -177.09769)
		(width 0.254)
		(layer "B.Cu")
		(net "P3V3_STBY_LL_R")
	)
	(segment
		(start 44.509182 -178.913028)
		(end 43.84167 -178.913028)
		(width 0.254)
		(layer "B.Cu")
		(net "P3V3_STBY_LL_R")
	)
	(segment
		(start 38.595046 -175.69561)
		(end 39.997126 -177.09769)
		(width 0.254)
		(layer "B.Cu")
		(net "P3V3_STBY_LL_R")
	)
	(segment
		(start 42.026332 -177.09769)
		(end 41.172892 -177.09769)
		(width 0.254)
		(layer "B.Cu")
		(net "P3V3_STBY_LL_R")
	)
	(segment
		(start 39.997126 -177.09769)
		(end 41.172892 -177.09769)
		(width 0.254)
		(layer "B.Cu")
		(net "P3V3_STBY_LL_R")
	)
	(segment
		(start 39.790878 -184.531)
		(end 42.0878 -184.531)
		(width 0.254)
		(layer "F.Cu")
		(net "P3V3_STBY_LL")
	)
	(segment
		(start 42.545 -184.0738)
		(end 42.545 -180.1749)
		(width 0.254)
		(layer "F.Cu")
		(net "P3V3_STBY_LL")
	)
	(segment
		(start 42.0878 -184.531)
		(end 42.545 -184.0738)
		(width 0.254)
		(layer "F.Cu")
		(net "P3V3_STBY_LL")
	)
	(segment
		(start 42.545 -180.1749)
		(end 42.2656 -179.8955)
		(width 0.254)
		(layer "F.Cu")
		(net "P3V3_STBY_LL")
	)
	(via
		(at 36.639246 -186.2328)
		(size 0.6604)
		(drill 0.3302)
		(layers "F.Cu" "B.Cu")
		(net "P3V3_STBY_LL")
	)
	(via
		(at 39.4716 -182.2958)
		(size 0.7112)
		(drill 0.4064)
		(layers "F.Cu" "B.Cu")
		(net "P3V3_STBY_LL")
	)
	(segment
		(start 40.884856 -182.186072)
		(end 39.581328 -182.186072)
		(width 0.508)
		(layer "B.Cu")
		(net "P3V3_STBY_LL")
	)
	(segment
		(start 39.581328 -182.186072)
		(end 39.4716 -182.2958)
		(width 0.508)
		(layer "B.Cu")
		(net "P3V3_STBY_LL")
	)
	(segment
		(start 149.371304 -95.926656)
		(end 149.827742 -96.383094)
		(width 0.254)
		(layer "F.Cu")
		(net "P3V3_STBY_G")
	)
	(segment
		(start 149.371304 -94.9706)
		(end 149.371304 -95.926656)
		(width 0.254)
		(layer "F.Cu")
		(net "P3V3_STBY_G")
	)
	(segment
		(start 153.888694 -98.288094)
		(end 154.367992 -98.288094)
		(width 0.254)
		(layer "F.Cu")
		(net "P3V3_STBY_G")
	)
	(segment
		(start 151.983694 -96.383094)
		(end 153.888694 -98.288094)
		(width 0.254)
		(layer "F.Cu")
		(net "P3V3_STBY_G")
	)
	(segment
		(start 149.523704 -94.8182)
		(end 149.371304 -94.9706)
		(width 0.254)
		(layer "F.Cu")
		(net "P3V3_STBY_G")
	)
	(segment
		(start 150.7363 -94.8182)
		(end 149.523704 -94.8182)
		(width 0.254)
		(layer "F.Cu")
		(net "P3V3_STBY_G")
	)
	(segment
		(start 149.827742 -96.383094)
		(end 151.983694 -96.383094)
		(width 0.254)
		(layer "F.Cu")
		(net "P3V3_STBY_G")
	)
	(via
		(at 149.523704 -94.8182)
		(size 0.6604)
		(drill 0.3302)
		(layers "F.Cu" "B.Cu")
		(net "P3V3_STBY_G")
	)
	(segment
		(start 38.544246 -177.58791)
		(end 38.18509 -177.58791)
		(width 0.254)
		(layer "F.Cu")
		(net "P3V3_STBY_EN")
	)
	(segment
		(start 37.680646 -178.092354)
		(end 37.680646 -179.37861)
		(width 0.254)
		(layer "F.Cu")
		(net "P3V3_STBY_EN")
	)
	(segment
		(start 38.18509 -177.58791)
		(end 37.680646 -178.092354)
		(width 0.254)
		(layer "F.Cu")
		(net "P3V3_STBY_EN")
	)
	(segment
		(start 40.779446 -177.51171)
		(end 40.703246 -177.58791)
		(width 0.254)
		(layer "F.Cu")
		(net "P3V3_STBY_EN")
	)
	(segment
		(start 41.744646 -177.51171)
		(end 40.779446 -177.51171)
		(width 0.254)
		(layer "F.Cu")
		(net "P3V3_STBY_EN")
	)
	(segment
		(start 37.680646 -179.37861)
		(end 37.488622 -179.570634)
		(width 0.254)
		(layer "F.Cu")
		(net "P3V3_STBY_EN")
	)
	(segment
		(start 37.488622 -179.570634)
		(end 36.744148 -179.570634)
		(width 0.254)
		(layer "F.Cu")
		(net "P3V3_STBY_EN")
	)
	(segment
		(start 39.585646 -177.58791)
		(end 38.544246 -177.58791)
		(width 0.254)
		(layer "F.Cu")
		(net "P3V3_STBY_EN")
	)
	(segment
		(start 40.703246 -177.58791)
		(end 39.585646 -177.58791)
		(width 0.254)
		(layer "F.Cu")
		(net "P3V3_STBY_EN")
	)
	(via
		(at 40.703246 -177.58791)
		(size 0.6604)
		(drill 0.3302)
		(layers "F.Cu" "B.Cu")
		(net "P3V3_STBY_EN")
	)
	(segment
		(start 35.181286 -187.96381)
		(end 35.217862 -187.927234)
		(width 0.508)
		(layer "F.Cu")
		(net "P3V3_SNB")
	)
	(segment
		(start 33.693354 -187.96381)
		(end 35.181286 -187.96381)
		(width 0.508)
		(layer "F.Cu")
		(net "P3V3_SNB")
	)
	(segment
		(start 36.31057 -187.927234)
		(end 35.217862 -187.927234)
		(width 0.508)
		(layer "F.Cu")
		(net "P3V3_SNB")
	)
	(segment
		(start 36.347146 -187.96381)
		(end 36.31057 -187.927234)
		(width 0.508)
		(layer "F.Cu")
		(net "P3V3_SNB")
	)
	(via
		(at 35.217862 -187.927234)
		(size 0.6604)
		(drill 0.3302)
		(layers "F.Cu" "B.Cu")
		(net "P3V3_SNB")
	)
	(segment
		(start 158.905448 -142.123922)
		(end 159.55264 -142.123922)
		(width 0.254)
		(layer "F.Cu")
		(net "P1V8_STBY_VRG5")
	)
	(segment
		(start 158.379668 -143.180308)
		(end 158.325058 -143.125698)
		(width 0.254)
		(layer "F.Cu")
		(net "P1V8_STBY_VRG5")
	)
	(segment
		(start 158.825692 -142.044166)
		(end 158.905448 -142.123922)
		(width 0.254)
		(layer "F.Cu")
		(net "P1V8_STBY_VRG5")
	)
	(segment
		(start 159.548576 -138.201146)
		(end 159.548576 -142.119858)
		(width 0.254)
		(layer "F.Cu")
		(net "P1V8_STBY_VRG5")
	)
	(segment
		(start 158.325058 -143.125698)
		(end 158.325058 -142.044166)
		(width 0.254)
		(layer "F.Cu")
		(net "P1V8_STBY_VRG5")
	)
	(segment
		(start 158.325058 -142.044166)
		(end 158.825692 -142.044166)
		(width 0.254)
		(layer "F.Cu")
		(net "P1V8_STBY_VRG5")
	)
	(segment
		(start 159.548576 -142.119858)
		(end 159.55264 -142.123922)
		(width 0.254)
		(layer "F.Cu")
		(net "P1V8_STBY_VRG5")
	)
	(via
		(at 158.325058 -142.044166)
		(size 0.6604)
		(drill 0.3302)
		(layers "F.Cu" "B.Cu")
		(net "P1V8_STBY_VRG5")
	)
	(segment
		(start 160.849564 -139.54633)
		(end 161.133536 -139.830302)
		(width 0.254)
		(layer "F.Cu")
		(net "P1V8_STBY_VO")
	)
	(segment
		(start 160.849564 -137.412984)
		(end 160.849564 -139.54633)
		(width 0.254)
		(layer "F.Cu")
		(net "P1V8_STBY_VO")
	)
	(segment
		(start 162.16376 -139.830302)
		(end 161.133536 -139.830302)
		(width 0.254)
		(layer "F.Cu")
		(net "P1V8_STBY_VO")
	)
	(segment
		(start 162.41014 -139.583922)
		(end 162.16376 -139.830302)
		(width 0.254)
		(layer "F.Cu")
		(net "P1V8_STBY_VO")
	)
	(via
		(at 161.133536 -139.830302)
		(size 0.6604)
		(drill 0.3302)
		(layers "F.Cu" "B.Cu")
		(net "P1V8_STBY_VO")
	)
	(segment
		(start 162.53714 -132.471922)
		(end 161.45764 -132.471922)
		(width 0.508)
		(layer "F.Cu")
		(net "P1V8_STBY_VBST_RR")
	)
	(segment
		(start 162.60064 -132.535422)
		(end 162.53714 -132.471922)
		(width 0.508)
		(layer "F.Cu")
		(net "P1V8_STBY_VBST_RR")
	)
	(segment
		(start 162.60064 -131.386326)
		(end 162.60064 -132.535422)
		(width 0.508)
		(layer "F.Cu")
		(net "P1V8_STBY_VBST_RR")
	)
	(via
		(at 162.60064 -131.386326)
		(size 0.6604)
		(drill 0.3302)
		(layers "F.Cu" "B.Cu")
		(net "P1V8_STBY_VBST_RR")
	)
	(segment
		(start 158.9786 -127.8636)
		(end 163.30676 -127.8636)
		(width 0.254)
		(layer "F.Cu")
		(net "P1V8_STBY_SW")
	)
	(segment
		(start 163.30676 -127.8636)
		(end 163.48456 -128.0414)
		(width 0.254)
		(layer "F.Cu")
		(net "P1V8_STBY_SW")
	)
	(segment
		(start 158.7754 -129.558796)
		(end 158.7754 -128.0668)
		(width 0.254)
		(layer "F.Cu")
		(net "P1V8_STBY_SW")
	)
	(segment
		(start 158.7754 -128.0668)
		(end 158.9786 -127.8636)
		(width 0.254)
		(layer "F.Cu")
		(net "P1V8_STBY_SW")
	)
	(segment
		(start 163.48456 -128.0414)
		(end 164.1729 -128.0414)
		(width 0.254)
		(layer "F.Cu")
		(net "P1V8_STBY_SW")
	)
	(segment
		(start 158.7754 -129.604008)
		(end 158.7754 -129.558796)
		(width 0.254)
		(layer "F.Cu")
		(net "P1V8_STBY_SW")
	)
	(via
		(at 157.761432 -132.296408)
		(size 0.6604)
		(drill 0.3302)
		(layers "F.Cu" "B.Cu")
		(net "P1V8_STBY_SW")
	)
	(segment
		(start 159.048704 -138.201146)
		(end 159.048704 -139.138406)
		(width 0.254)
		(layer "F.Cu")
		(net "P1V8_STBY_SS")
	)
	(segment
		(start 158.851092 -140.952474)
		(end 158.85414 -140.955522)
		(width 0.254)
		(layer "F.Cu")
		(net "P1V8_STBY_SS")
	)
	(segment
		(start 159.048704 -139.138406)
		(end 158.851092 -139.336018)
		(width 0.254)
		(layer "F.Cu")
		(net "P1V8_STBY_SS")
	)
	(segment
		(start 158.851092 -139.827)
		(end 158.851092 -140.952474)
		(width 0.254)
		(layer "F.Cu")
		(net "P1V8_STBY_SS")
	)
	(segment
		(start 158.851092 -139.336018)
		(end 158.851092 -139.827)
		(width 0.254)
		(layer "F.Cu")
		(net "P1V8_STBY_SS")
	)
	(via
		(at 158.851092 -139.827)
		(size 0.6604)
		(drill 0.3302)
		(layers "F.Cu" "B.Cu")
		(net "P1V8_STBY_SS")
	)
	(segment
		(start 155.575 -137.3632)
		(end 154.349704 -137.3632)
		(width 0.254)
		(layer "F.Cu")
		(net "P1V8_STBY_EN_R")
	)
	(segment
		(start 157.760416 -136.912858)
		(end 156.025342 -136.912858)
		(width 0.254)
		(layer "F.Cu")
		(net "P1V8_STBY_EN_R")
	)
	(segment
		(start 156.025342 -136.912858)
		(end 155.575 -137.3632)
		(width 0.254)
		(layer "F.Cu")
		(net "P1V8_STBY_EN_R")
	)
	(segment
		(start 154.337766 -137.351262)
		(end 154.349704 -137.3632)
		(width 0.254)
		(layer "F.Cu")
		(net "P1V8_STBY_EN_R")
	)
	(segment
		(start 153.203656 -137.351262)
		(end 154.337766 -137.351262)
		(width 0.254)
		(layer "F.Cu")
		(net "P1V8_STBY_EN_R")
	)
	(via
		(at 154.349704 -137.3632)
		(size 0.6604)
		(drill 0.3302)
		(layers "F.Cu" "B.Cu")
		(net "P1V8_STBY_EN_R")
	)
	(segment
		(start 163.2839 -141.605)
		(end 163.3093 -141.5796)
		(width 0.254)
		(layer "F.Cu")
		(net "P1V8_STBY_CC_R")
	)
	(segment
		(start 163.23564 -142.758922)
		(end 163.926266 -142.758922)
		(width 0.254)
		(layer "F.Cu")
		(net "P1V8_STBY_CC_R")
	)
	(segment
		(start 164.429186 -142.256002)
		(end 163.778184 -141.605)
		(width 0.254)
		(layer "F.Cu")
		(net "P1V8_STBY_CC_R")
	)
	(segment
		(start 163.778184 -141.605)
		(end 163.2839 -141.605)
		(width 0.254)
		(layer "F.Cu")
		(net "P1V8_STBY_CC_R")
	)
	(segment
		(start 163.3093 -140.6398)
		(end 163.29914 -140.62964)
		(width 0.254)
		(layer "F.Cu")
		(net "P1V8_STBY_CC_R")
	)
	(segment
		(start 163.29914 -140.62964)
		(end 163.29914 -139.583922)
		(width 0.254)
		(layer "F.Cu")
		(net "P1V8_STBY_CC_R")
	)
	(segment
		(start 163.926266 -142.758922)
		(end 164.429186 -142.256002)
		(width 0.254)
		(layer "F.Cu")
		(net "P1V8_STBY_CC_R")
	)
	(segment
		(start 163.3093 -141.5796)
		(end 163.3093 -140.6398)
		(width 0.254)
		(layer "F.Cu")
		(net "P1V8_STBY_CC_R")
	)
	(via
		(at 164.429186 -142.256002)
		(size 0.6604)
		(drill 0.3302)
		(layers "F.Cu" "B.Cu")
		(net "P1V8_STBY_CC_R")
	)
	(segment
		(start 163.23564 -144.282922)
		(end 162.21964 -144.282922)
		(width 0.254)
		(layer "F.Cu")
		(net "P1V8_STBY_CC")
	)
	(segment
		(start 156.4005 -117.602)
		(end 155.702 -117.602)
		(width 0.254)
		(layer "F.Cu")
		(net "P1V8_STBY_CC")
	)
	(via
		(at 162.21964 -144.282922)
		(size 0.508)
		(drill 0.254)
		(layers "F.Cu" "B.Cu")
		(net "P1V8_STBY_CC")
	)
	(via
		(at 155.702 -117.602)
		(size 0.508)
		(drill 0.254)
		(layers "F.Cu" "B.Cu")
		(net "P1V8_STBY_CC")
	)
	(via
		(at 153.416 -127.458724)
		(size 0.6096)
		(drill 0.3048)
		(layers "F.Cu" "B.Cu")
		(net "P1V8_STBY_CC")
	)
	(segment
		(start 160.90138 -141.003782)
		(end 153.416 -133.518402)
		(width 0.254)
		(layer "B.Cu")
		(net "P1V8_STBY_CC")
	)
	(segment
		(start 160.90138 -141.825726)
		(end 160.90138 -141.003782)
		(width 0.254)
		(layer "B.Cu")
		(net "P1V8_STBY_CC")
	)
	(segment
		(start 162.21964 -144.282922)
		(end 161.544 -143.607282)
		(width 0.254)
		(layer "B.Cu")
		(net "P1V8_STBY_CC")
	)
	(segment
		(start 153.416 -133.518402)
		(end 153.416 -127.458724)
		(width 0.254)
		(layer "B.Cu")
		(net "P1V8_STBY_CC")
	)
	(segment
		(start 161.544 -142.468346)
		(end 160.90138 -141.825726)
		(width 0.254)
		(layer "B.Cu")
		(net "P1V8_STBY_CC")
	)
	(segment
		(start 153.416 -118.364)
		(end 153.416 -127.458724)
		(width 0.254)
		(layer "B.Cu")
		(net "P1V8_STBY_CC")
	)
	(segment
		(start 154.178 -117.602)
		(end 153.416 -118.364)
		(width 0.254)
		(layer "B.Cu")
		(net "P1V8_STBY_CC")
	)
	(segment
		(start 155.702 -117.602)
		(end 154.178 -117.602)
		(width 0.254)
		(layer "B.Cu")
		(net "P1V8_STBY_CC")
	)
	(segment
		(start 161.544 -143.607282)
		(end 161.544 -142.468346)
		(width 0.254)
		(layer "B.Cu")
		(net "P1V8_STBY_CC")
	)
	(segment
		(start 73.77938 -138.676634)
		(end 72.966834 -138.676634)
		(width 0.127)
		(layer "F.Cu")
		(net "FP_PWR_BTN_N_R")
	)
	(segment
		(start 71.53783 -138.895836)
		(end 72.747632 -138.895836)
		(width 0.127)
		(layer "F.Cu")
		(net "FP_PWR_BTN_N_R")
	)
	(segment
		(start 74.01687 -138.914124)
		(end 73.77938 -138.676634)
		(width 0.127)
		(layer "F.Cu")
		(net "FP_PWR_BTN_N_R")
	)
	(segment
		(start 72.747632 -138.895836)
		(end 72.966834 -138.676634)
		(width 0.127)
		(layer "F.Cu")
		(net "FP_PWR_BTN_N_R")
	)
	(via
		(at 72.966834 -138.676634)
		(size 0.6604)
		(drill 0.3302)
		(layers "F.Cu" "B.Cu")
		(net "FP_PWR_BTN_N_R")
	)
	(segment
		(start 71.05523 -157.10281)
		(end 72.65289 -157.10281)
		(width 0.127)
		(layer "F.Cu")
		(net "FM_OSC_50M_EN")
	)
	(segment
		(start 72.65289 -157.10281)
		(end 73.0377 -156.718)
		(width 0.127)
		(layer "F.Cu")
		(net "FM_OSC_50M_EN")
	)
	(segment
		(start 144.15389 -15.96009)
		(end 143.5354 -15.3416)
		(width 0.254)
		(layer "F.Cu")
		(net "EXT2_LED_BLUE_D")
	)
	(segment
		(start 143.22298 -15.02918)
		(end 143.5354 -15.3416)
		(width 0.254)
		(layer "F.Cu")
		(net "EXT2_LED_BLUE_D")
	)
	(segment
		(start 143.22298 -14.072362)
		(end 143.22298 -15.02918)
		(width 0.254)
		(layer "F.Cu")
		(net "EXT2_LED_BLUE_D")
	)
	(segment
		(start 145.04416 -15.96009)
		(end 144.15389 -15.96009)
		(width 0.254)
		(layer "F.Cu")
		(net "EXT2_LED_BLUE_D")
	)
	(via
		(at 143.5354 -15.3416)
		(size 0.6604)
		(drill 0.3302)
		(layers "F.Cu" "B.Cu")
		(net "EXT2_LED_BLUE_D")
	)
	(segment
		(start 193.07556 -15.59941)
		(end 192.639696 -16.035274)
		(width 0.254)
		(layer "F.Cu")
		(net "EXT1_LED_BLUE_D")
	)
	(segment
		(start 192.639696 -16.035274)
		(end 191.615314 -16.035274)
		(width 0.254)
		(layer "F.Cu")
		(net "EXT1_LED_BLUE_D")
	)
	(segment
		(start 193.07556 -14.75232)
		(end 193.07556 -15.59941)
		(width 0.254)
		(layer "F.Cu")
		(net "EXT1_LED_BLUE_D")
	)
	(segment
		(start 190.881 -15.30096)
		(end 191.092074 -15.512034)
		(width 0.254)
		(layer "F.Cu")
		(net "EXT1_LED_BLUE_D")
	)
	(segment
		(start 191.615314 -16.035274)
		(end 191.092074 -15.512034)
		(width 0.254)
		(layer "F.Cu")
		(net "EXT1_LED_BLUE_D")
	)
	(segment
		(start 190.881 -13.77442)
		(end 190.881 -15.30096)
		(width 0.254)
		(layer "F.Cu")
		(net "EXT1_LED_BLUE_D")
	)
	(via
		(at 191.092074 -15.512034)
		(size 0.6604)
		(drill 0.3302)
		(layers "F.Cu" "B.Cu")
		(net "EXT1_LED_BLUE_D")
	)
	(segment
		(start 93.599 -150.3426)
		(end 93.599 -150.460964)
		(width 0.127)
		(layer "F.Cu")
		(net "CRFILT")
	)
	(segment
		(start 92.751656 -151.308308)
		(end 92.751656 -152.73528)
		(width 0.127)
		(layer "F.Cu")
		(net "CRFILT")
	)
	(segment
		(start 93.972126 -149.969474)
		(end 93.599 -150.3426)
		(width 0.127)
		(layer "F.Cu")
		(net "CRFILT")
	)
	(segment
		(start 93.599 -150.460964)
		(end 92.751656 -151.308308)
		(width 0.127)
		(layer "F.Cu")
		(net "CRFILT")
	)
	(segment
		(start 93.972126 -148.985732)
		(end 93.972126 -149.969474)
		(width 0.127)
		(layer "F.Cu")
		(net "CRFILT")
	)
	(segment
		(start 96.44253 -156.605478)
		(end 95.621856 -156.605478)
		(width 0.127)
		(layer "F.Cu")
		(net "CFG_SEL1")
	)
	(segment
		(start 97.491296 -156.96692)
		(end 98.03511 -156.96692)
		(width 0.127)
		(layer "F.Cu")
		(net "CFG_SEL1")
	)
	(segment
		(start 96.552766 -156.495242)
		(end 96.44253 -156.605478)
		(width 0.127)
		(layer "F.Cu")
		(net "CFG_SEL1")
	)
	(segment
		(start 98.03511 -156.96692)
		(end 98.472244 -157.404054)
		(width 0.127)
		(layer "F.Cu")
		(net "CFG_SEL1")
	)
	(segment
		(start 97.019618 -156.495242)
		(end 96.552766 -156.495242)
		(width 0.127)
		(layer "F.Cu")
		(net "CFG_SEL1")
	)
	(segment
		(start 97.019618 -156.495242)
		(end 97.491296 -156.96692)
		(width 0.127)
		(layer "F.Cu")
		(net "CFG_SEL1")
	)
	(via
		(at 97.019618 -156.495242)
		(size 0.508)
		(drill 0.254)
		(layers "F.Cu" "B.Cu")
		(net "CFG_SEL1")
	)
	(via
		(at 95.91929 -156.491178)
		(size 0.6096)
		(drill 0.3048)
		(layers "F.Cu" "B.Cu")
		(net "CFG_SEL1")
	)
	(segment
		(start 96.308164 -157.402784)
		(end 96.308164 -157.607762)
		(width 0.127)
		(layer "B.Cu")
		(net "CFG_SEL1")
	)
	(segment
		(start 95.91929 -156.491178)
		(end 95.91929 -157.01391)
		(width 0.127)
		(layer "B.Cu")
		(net "CFG_SEL1")
	)
	(segment
		(start 95.91929 -157.01391)
		(end 96.308164 -157.402784)
		(width 0.127)
		(layer "B.Cu")
		(net "CFG_SEL1")
	)
	(segment
		(start 95.91929 -156.491178)
		(end 97.015554 -156.491178)
		(width 0.127)
		(layer "B.Cu")
		(net "CFG_SEL1")
	)
	(segment
		(start 97.015554 -156.491178)
		(end 97.019618 -156.495242)
		(width 0.127)
		(layer "B.Cu")
		(net "CFG_SEL1")
	)
	(segment
		(start 96.711008 -155.976574)
		(end 96.581976 -156.105606)
		(width 0.127)
		(layer "F.Cu")
		(net "CFG_SEL0")
	)
	(segment
		(start 98.4631 -153.9748)
		(end 98.4631 -155.0162)
		(width 0.127)
		(layer "F.Cu")
		(net "CFG_SEL0")
	)
	(segment
		(start 98.4631 -155.73248)
		(end 98.00463 -156.19095)
		(width 0.127)
		(layer "F.Cu")
		(net "CFG_SEL0")
	)
	(segment
		(start 97.749868 -156.19095)
		(end 97.535492 -155.976574)
		(width 0.127)
		(layer "F.Cu")
		(net "CFG_SEL0")
	)
	(segment
		(start 98.00463 -156.19095)
		(end 97.749868 -156.19095)
		(width 0.127)
		(layer "F.Cu")
		(net "CFG_SEL0")
	)
	(segment
		(start 98.4631 -155.0162)
		(end 98.4631 -155.73248)
		(width 0.127)
		(layer "F.Cu")
		(net "CFG_SEL0")
	)
	(segment
		(start 97.535492 -155.976574)
		(end 96.711008 -155.976574)
		(width 0.127)
		(layer "F.Cu")
		(net "CFG_SEL0")
	)
	(segment
		(start 96.581976 -156.105606)
		(end 95.621856 -156.105606)
		(width 0.127)
		(layer "F.Cu")
		(net "CFG_SEL0")
	)
	(via
		(at 98.00463 -156.19095)
		(size 0.6604)
		(drill 0.3302)
		(layers "F.Cu" "B.Cu")
		(net "CFG_SEL0")
	)
	(segment
		(start 46.89983 -152.200102)
		(end 46.89983 -152.199848)
		(width 0.127)
		(layer "F.Cu")
		(net "BOARD_REV_2")
	)
	(segment
		(start 46.89983 -152.199848)
		(end 46.500034 -151.800052)
		(width 0.127)
		(layer "F.Cu")
		(net "BOARD_REV_2")
	)
	(via
		(at 45.24756 -160.10382)
		(size 0.508)
		(drill 0.254)
		(layers "F.Cu" "B.Cu")
		(net "BOARD_REV_2")
	)
	(via
		(at 45.054012 -161.901886)
		(size 0.6096)
		(drill 0.3048)
		(layers "F.Cu" "B.Cu")
		(net "BOARD_REV_2")
	)
	(via
		(at 46.89983 -152.200102)
		(size 0.4572)
		(drill 0.2032)
		(layers "F.Cu" "B.Cu")
		(net "BOARD_REV_2")
	)
	(segment
		(start 45.054012 -161.901886)
		(end 44.462446 -161.901886)
		(width 0.127)
		(layer "B.Cu")
		(net "BOARD_REV_2")
	)
	(segment
		(start 46.1899 -161.04616)
		(end 45.24756 -160.10382)
		(width 0.127)
		(layer "B.Cu")
		(net "BOARD_REV_2")
	)
	(segment
		(start 44.462446 -161.901886)
		(end 43.927522 -161.366962)
		(width 0.127)
		(layer "B.Cu")
		(net "BOARD_REV_2")
	)
	(segment
		(start 45.654214 -161.901886)
		(end 46.1899 -161.3662)
		(width 0.127)
		(layer "B.Cu")
		(net "BOARD_REV_2")
	)
	(segment
		(start 46.1899 -161.3662)
		(end 46.1899 -161.04616)
		(width 0.127)
		(layer "B.Cu")
		(net "BOARD_REV_2")
	)
	(segment
		(start 45.054012 -161.901886)
		(end 45.654214 -161.901886)
		(width 0.127)
		(layer "B.Cu")
		(net "BOARD_REV_2")
	)
	(segment
		(start 46.89983 -152.200102)
		(end 46.89983 -157.31871)
		(width 0.127)
		(layer "In2.Cu")
		(net "BOARD_REV_2")
	)
	(segment
		(start 45.548804 -159.802576)
		(end 45.24756 -160.10382)
		(width 0.127)
		(layer "In2.Cu")
		(net "BOARD_REV_2")
	)
	(segment
		(start 46.89983 -157.31871)
		(end 45.548804 -158.669736)
		(width 0.127)
		(layer "In2.Cu")
		(net "BOARD_REV_2")
	)
	(segment
		(start 45.548804 -158.669736)
		(end 45.548804 -159.802576)
		(width 0.127)
		(layer "In2.Cu")
		(net "BOARD_REV_2")
	)
	(segment
		(start 47.700184 -152.199848)
		(end 48.09998 -152.599644)
		(width 0.127)
		(layer "F.Cu")
		(net "BOARD_REV_1")
	)
	(segment
		(start 48.09998 -152.599644)
		(end 48.09998 -152.599898)
		(width 0.127)
		(layer "F.Cu")
		(net "BOARD_REV_1")
	)
	(via
		(at 47.700184 -152.199848)
		(size 0.4572)
		(drill 0.2032)
		(layers "F.Cu" "B.Cu")
		(net "BOARD_REV_1")
	)
	(via
		(at 50.313844 -158.67761)
		(size 0.6096)
		(drill 0.3048)
		(layers "F.Cu" "B.Cu")
		(net "BOARD_REV_1")
	)
	(segment
		(start 49.16424 -154.2542)
		(end 49.16424 -155.96108)
		(width 0.127)
		(layer "B.Cu")
		(net "BOARD_REV_1")
	)
	(segment
		(start 47.700184 -152.443434)
		(end 48.09363 -152.83688)
		(width 0.127)
		(layer "B.Cu")
		(net "BOARD_REV_1")
	)
	(segment
		(start 49.749964 -158.11373)
		(end 50.313844 -158.67761)
		(width 0.127)
		(layer "B.Cu")
		(net "BOARD_REV_1")
	)
	(segment
		(start 48.09363 -153.18359)
		(end 49.16424 -154.2542)
		(width 0.127)
		(layer "B.Cu")
		(net "BOARD_REV_1")
	)
	(segment
		(start 49.749964 -156.937964)
		(end 49.749964 -158.11373)
		(width 0.127)
		(layer "B.Cu")
		(net "BOARD_REV_1")
	)
	(segment
		(start 48.999394 -160.832292)
		(end 50.071274 -160.832292)
		(width 0.127)
		(layer "B.Cu")
		(net "BOARD_REV_1")
	)
	(segment
		(start 50.086514 -160.817052)
		(end 50.17135 -160.817052)
		(width 0.127)
		(layer "B.Cu")
		(net "BOARD_REV_1")
	)
	(segment
		(start 48.09363 -152.83688)
		(end 48.09363 -153.18359)
		(width 0.127)
		(layer "B.Cu")
		(net "BOARD_REV_1")
	)
	(segment
		(start 49.5554 -156.35224)
		(end 49.5554 -156.7434)
		(width 0.127)
		(layer "B.Cu")
		(net "BOARD_REV_1")
	)
	(segment
		(start 51.1175 -159.481266)
		(end 50.313844 -158.67761)
		(width 0.127)
		(layer "B.Cu")
		(net "BOARD_REV_1")
	)
	(segment
		(start 47.700184 -152.199848)
		(end 47.700184 -152.443434)
		(width 0.127)
		(layer "B.Cu")
		(net "BOARD_REV_1")
	)
	(segment
		(start 50.17135 -160.817052)
		(end 51.1175 -159.870902)
		(width 0.127)
		(layer "B.Cu")
		(net "BOARD_REV_1")
	)
	(segment
		(start 51.1175 -159.870902)
		(end 51.1175 -159.481266)
		(width 0.127)
		(layer "B.Cu")
		(net "BOARD_REV_1")
	)
	(segment
		(start 49.16424 -155.96108)
		(end 49.5554 -156.35224)
		(width 0.127)
		(layer "B.Cu")
		(net "BOARD_REV_1")
	)
	(segment
		(start 50.071274 -160.832292)
		(end 50.086514 -160.817052)
		(width 0.127)
		(layer "B.Cu")
		(net "BOARD_REV_1")
	)
	(segment
		(start 49.5554 -156.7434)
		(end 49.749964 -156.937964)
		(width 0.127)
		(layer "B.Cu")
		(net "BOARD_REV_1")
	)
	(segment
		(start 44.02074 -156.1084)
		(end 43.408346 -156.720794)
		(width 0.127)
		(layer "F.Cu")
		(net "BOARD_REV_0")
	)
	(segment
		(start 41.4782 -159.9692)
		(end 41.4782 -160.5407)
		(width 0.127)
		(layer "F.Cu")
		(net "BOARD_REV_0")
	)
	(segment
		(start 44.899834 -152.599898)
		(end 44.899834 -152.828498)
		(width 0.127)
		(layer "F.Cu")
		(net "BOARD_REV_0")
	)
	(segment
		(start 44.538392 -153.18994)
		(end 44.538392 -153.6954)
		(width 0.127)
		(layer "F.Cu")
		(net "BOARD_REV_0")
	)
	(segment
		(start 43.2943 -158.188914)
		(end 42.974514 -158.5087)
		(width 0.127)
		(layer "F.Cu")
		(net "BOARD_REV_0")
	)
	(segment
		(start 44.899834 -152.828498)
		(end 44.538392 -153.18994)
		(width 0.127)
		(layer "F.Cu")
		(net "BOARD_REV_0")
	)
	(segment
		(start 44.02074 -154.213052)
		(end 44.02074 -156.1084)
		(width 0.127)
		(layer "F.Cu")
		(net "BOARD_REV_0")
	)
	(segment
		(start 44.538392 -153.6954)
		(end 44.02074 -154.213052)
		(width 0.127)
		(layer "F.Cu")
		(net "BOARD_REV_0")
	)
	(segment
		(start 42.974514 -158.5087)
		(end 42.9387 -158.5087)
		(width 0.127)
		(layer "F.Cu")
		(net "BOARD_REV_0")
	)
	(segment
		(start 42.9387 -158.5087)
		(end 41.4782 -159.9692)
		(width 0.127)
		(layer "F.Cu")
		(net "BOARD_REV_0")
	)
	(segment
		(start 41.4782 -160.5407)
		(end 41.8592 -160.9217)
		(width 0.127)
		(layer "F.Cu")
		(net "BOARD_REV_0")
	)
	(segment
		(start 43.408346 -158.039054)
		(end 43.2943 -158.1531)
		(width 0.127)
		(layer "F.Cu")
		(net "BOARD_REV_0")
	)
	(segment
		(start 43.2943 -158.1531)
		(end 43.2943 -158.188914)
		(width 0.127)
		(layer "F.Cu")
		(net "BOARD_REV_0")
	)
	(segment
		(start 43.408346 -156.720794)
		(end 43.408346 -158.039054)
		(width 0.127)
		(layer "F.Cu")
		(net "BOARD_REV_0")
	)
	(segment
		(start 41.8592 -160.9217)
		(end 42.9006 -160.9217)
		(width 0.127)
		(layer "F.Cu")
		(net "BOARD_REV_0")
	)
	(via
		(at 41.4782 -159.9692)
		(size 0.6604)
		(drill 0.3302)
		(layers "F.Cu" "B.Cu")
		(net "BOARD_REV_0")
	)
	(segment
		(start 58.171588 -142.742412)
		(end 58.7248 -142.1892)
		(width 0.127)
		(layer "F.Cu")
		(net "BMC_SMB9_DAT")
	)
	(segment
		(start 59.570366 -142.188692)
		(end 59.744356 -142.188692)
		(width 0.127)
		(layer "F.Cu")
		(net "BMC_SMB9_DAT")
	)
	(segment
		(start 59.569858 -142.1892)
		(end 59.570366 -142.188692)
		(width 0.127)
		(layer "F.Cu")
		(net "BMC_SMB9_DAT")
	)
	(segment
		(start 57.353708 -143.800068)
		(end 58.171588 -142.982188)
		(width 0.127)
		(layer "F.Cu")
		(net "BMC_SMB9_DAT")
	)
	(segment
		(start 58.7248 -142.1892)
		(end 59.569858 -142.1892)
		(width 0.127)
		(layer "F.Cu")
		(net "BMC_SMB9_DAT")
	)
	(segment
		(start 58.171588 -142.982188)
		(end 58.171588 -142.742412)
		(width 0.127)
		(layer "F.Cu")
		(net "BMC_SMB9_DAT")
	)
	(segment
		(start 59.744356 -142.188692)
		(end 60.541916 -141.391132)
		(width 0.127)
		(layer "F.Cu")
		(net "BMC_SMB9_DAT")
	)
	(segment
		(start 56.099964 -143.800068)
		(end 57.353708 -143.800068)
		(width 0.127)
		(layer "F.Cu")
		(net "BMC_SMB9_DAT")
	)
	(segment
		(start 60.541916 -141.391132)
		(end 60.83808 -141.391132)
		(width 0.127)
		(layer "F.Cu")
		(net "BMC_SMB9_DAT")
	)
	(via
		(at 58.7248 -142.1892)
		(size 0.6604)
		(drill 0.3302)
		(layers "F.Cu" "B.Cu")
		(net "BMC_SMB9_DAT")
	)
	(segment
		(start 54.89956 -142.600426)
		(end 54.500018 -142.999968)
		(width 0.127)
		(layer "F.Cu")
		(net "BMC_SMB9_CLK")
	)
	(segment
		(start 54.899814 -142.600426)
		(end 54.89956 -142.600426)
		(width 0.127)
		(layer "F.Cu")
		(net "BMC_SMB9_CLK")
	)
	(via
		(at 54.899814 -142.600426)
		(size 0.4572)
		(drill 0.2032)
		(layers "F.Cu" "B.Cu")
		(net "BMC_SMB9_CLK")
	)
	(via
		(at 56.987186 -142.86865)
		(size 0.6096)
		(drill 0.3048)
		(layers "F.Cu" "B.Cu")
		(net "BMC_SMB9_CLK")
	)
	(segment
		(start 55.386478 -142.342108)
		(end 56.164226 -142.342108)
		(width 0.127)
		(layer "B.Cu")
		(net "BMC_SMB9_CLK")
	)
	(segment
		(start 55.304436 -142.42415)
		(end 55.386478 -142.342108)
		(width 0.127)
		(layer "B.Cu")
		(net "BMC_SMB9_CLK")
	)
	(segment
		(start 57.3024 -142.553436)
		(end 57.3024 -142.060676)
		(width 0.127)
		(layer "B.Cu")
		(net "BMC_SMB9_CLK")
	)
	(segment
		(start 56.690768 -142.86865)
		(end 56.987186 -142.86865)
		(width 0.127)
		(layer "B.Cu")
		(net "BMC_SMB9_CLK")
	)
	(segment
		(start 54.899814 -142.600426)
		(end 55.07609 -142.42415)
		(width 0.127)
		(layer "B.Cu")
		(net "BMC_SMB9_CLK")
	)
	(segment
		(start 56.987186 -142.86865)
		(end 57.3024 -142.553436)
		(width 0.127)
		(layer "B.Cu")
		(net "BMC_SMB9_CLK")
	)
	(segment
		(start 55.07609 -142.42415)
		(end 55.304436 -142.42415)
		(width 0.127)
		(layer "B.Cu")
		(net "BMC_SMB9_CLK")
	)
	(segment
		(start 57.3024 -142.060676)
		(end 56.987186 -141.745462)
		(width 0.127)
		(layer "B.Cu")
		(net "BMC_SMB9_CLK")
	)
	(segment
		(start 56.164226 -142.342108)
		(end 56.690768 -142.86865)
		(width 0.127)
		(layer "B.Cu")
		(net "BMC_SMB9_CLK")
	)
	(segment
		(start 43.9166 -157.4673)
		(end 43.9166 -157.01645)
		(width 0.127)
		(layer "F.Cu")
		(net "BMC_SMB8_DAT")
	)
	(segment
		(start 44.46016 -156.47289)
		(end 44.46016 -154.998674)
		(width 0.127)
		(layer "F.Cu")
		(net "BMC_SMB8_DAT")
	)
	(segment
		(start 44.899834 -154.559)
		(end 44.899834 -153.399998)
		(width 0.127)
		(layer "F.Cu")
		(net "BMC_SMB8_DAT")
	)
	(segment
		(start 44.46016 -154.998674)
		(end 44.899834 -154.559)
		(width 0.127)
		(layer "F.Cu")
		(net "BMC_SMB8_DAT")
	)
	(segment
		(start 43.9166 -157.01645)
		(end 44.46016 -156.47289)
		(width 0.127)
		(layer "F.Cu")
		(net "BMC_SMB8_DAT")
	)
	(via
		(at 44.46016 -156.47289)
		(size 0.6604)
		(drill 0.3302)
		(layers "F.Cu" "B.Cu")
		(net "BMC_SMB8_DAT")
	)
	(segment
		(start 45.4152 -155.5242)
		(end 45.4152 -155.9814)
		(width 0.127)
		(layer "F.Cu")
		(net "BMC_SMB8_CLK")
	)
	(segment
		(start 45.4152 -157.0101)
		(end 44.958 -157.4673)
		(width 0.127)
		(layer "F.Cu")
		(net "BMC_SMB8_CLK")
	)
	(segment
		(start 45.699934 -152.599898)
		(end 45.242734 -153.057098)
		(width 0.127)
		(layer "F.Cu")
		(net "BMC_SMB8_CLK")
	)
	(segment
		(start 45.242734 -155.351734)
		(end 45.4152 -155.5242)
		(width 0.127)
		(layer "F.Cu")
		(net "BMC_SMB8_CLK")
	)
	(segment
		(start 45.4152 -155.9814)
		(end 45.4152 -157.0101)
		(width 0.127)
		(layer "F.Cu")
		(net "BMC_SMB8_CLK")
	)
	(segment
		(start 45.242734 -153.057098)
		(end 45.242734 -155.351734)
		(width 0.127)
		(layer "F.Cu")
		(net "BMC_SMB8_CLK")
	)
	(via
		(at 45.4152 -155.9814)
		(size 0.6604)
		(drill 0.3302)
		(layers "F.Cu" "B.Cu")
		(net "BMC_SMB8_CLK")
	)
	(segment
		(start 46.2788 -156.7434)
		(end 46.2788 -157.46349)
		(width 0.127)
		(layer "F.Cu")
		(net "BMC_SMB7_DAT")
	)
	(segment
		(start 46.2788 -156.7434)
		(end 46.2788 -155.854654)
		(width 0.127)
		(layer "F.Cu")
		(net "BMC_SMB7_DAT")
	)
	(segment
		(start 45.699934 -155.275788)
		(end 45.699934 -153.399998)
		(width 0.127)
		(layer "F.Cu")
		(net "BMC_SMB7_DAT")
	)
	(segment
		(start 46.2788 -157.46349)
		(end 45.99559 -157.7467)
		(width 0.127)
		(layer "F.Cu")
		(net "BMC_SMB7_DAT")
	)
	(segment
		(start 46.2788 -155.854654)
		(end 45.699934 -155.275788)
		(width 0.127)
		(layer "F.Cu")
		(net "BMC_SMB7_DAT")
	)
	(via
		(at 46.2788 -156.7434)
		(size 0.6604)
		(drill 0.3302)
		(layers "F.Cu" "B.Cu")
		(net "BMC_SMB7_DAT")
	)
	(segment
		(start 47.01159 -157.7467)
		(end 47.01159 -155.8798)
		(width 0.127)
		(layer "F.Cu")
		(net "BMC_SMB7_CLK")
	)
	(segment
		(start 46.500034 -154.39898)
		(end 46.500034 -153.399998)
		(width 0.127)
		(layer "F.Cu")
		(net "BMC_SMB7_CLK")
	)
	(segment
		(start 47.01159 -155.8798)
		(end 47.01159 -154.910536)
		(width 0.127)
		(layer "F.Cu")
		(net "BMC_SMB7_CLK")
	)
	(segment
		(start 47.01159 -154.910536)
		(end 46.500034 -154.39898)
		(width 0.127)
		(layer "F.Cu")
		(net "BMC_SMB7_CLK")
	)
	(via
		(at 47.01159 -155.8798)
		(size 0.6604)
		(drill 0.3302)
		(layers "F.Cu" "B.Cu")
		(net "BMC_SMB7_CLK")
	)
	(segment
		(start 48.05299 -155.16479)
		(end 46.915578 -154.027378)
		(width 0.127)
		(layer "F.Cu")
		(net "BMC_SMB6_DAT")
	)
	(segment
		(start 48.05299 -157.7467)
		(end 48.05299 -156.8196)
		(width 0.127)
		(layer "F.Cu")
		(net "BMC_SMB6_DAT")
	)
	(segment
		(start 48.05299 -156.8196)
		(end 48.05299 -155.16479)
		(width 0.127)
		(layer "F.Cu")
		(net "BMC_SMB6_DAT")
	)
	(segment
		(start 46.915578 -153.015442)
		(end 46.500034 -152.599898)
		(width 0.127)
		(layer "F.Cu")
		(net "BMC_SMB6_DAT")
	)
	(segment
		(start 46.915578 -154.027378)
		(end 46.915578 -153.015442)
		(width 0.127)
		(layer "F.Cu")
		(net "BMC_SMB6_DAT")
	)
	(via
		(at 48.05299 -156.8196)
		(size 0.6604)
		(drill 0.3302)
		(layers "F.Cu" "B.Cu")
		(net "BMC_SMB6_DAT")
	)
	(segment
		(start 49.3268 -155.948634)
		(end 49.3268 -155.8798)
		(width 0.127)
		(layer "F.Cu")
		(net "BMC_SMB6_CLK")
	)
	(segment
		(start 49.3268 -155.8798)
		(end 49.3268 -154.606244)
		(width 0.127)
		(layer "F.Cu")
		(net "BMC_SMB6_CLK")
	)
	(segment
		(start 48.781716 -154.06116)
		(end 48.68164 -154.06116)
		(width 0.127)
		(layer "F.Cu")
		(net "BMC_SMB6_CLK")
	)
	(segment
		(start 48.68164 -154.06116)
		(end 48.09998 -153.4795)
		(width 0.127)
		(layer "F.Cu")
		(net "BMC_SMB6_CLK")
	)
	(segment
		(start 49.09439 -157.7467)
		(end 48.984154 -157.636464)
		(width 0.127)
		(layer "F.Cu")
		(net "BMC_SMB6_CLK")
	)
	(segment
		(start 48.984154 -157.636464)
		(end 48.984154 -156.29128)
		(width 0.127)
		(layer "F.Cu")
		(net "BMC_SMB6_CLK")
	)
	(segment
		(start 48.09998 -153.4795)
		(end 48.09998 -153.399998)
		(width 0.127)
		(layer "F.Cu")
		(net "BMC_SMB6_CLK")
	)
	(segment
		(start 48.984154 -156.29128)
		(end 49.3268 -155.948634)
		(width 0.127)
		(layer "F.Cu")
		(net "BMC_SMB6_CLK")
	)
	(segment
		(start 49.3268 -154.606244)
		(end 48.781716 -154.06116)
		(width 0.127)
		(layer "F.Cu")
		(net "BMC_SMB6_CLK")
	)
	(via
		(at 49.3268 -155.8798)
		(size 0.6604)
		(drill 0.3302)
		(layers "F.Cu" "B.Cu")
		(net "BMC_SMB6_CLK")
	)
	(segment
		(start 48.09998 -151.000206)
		(end 48.09998 -150.999952)
		(width 0.127)
		(layer "F.Cu")
		(net "BMC_SMB5_DAT")
	)
	(segment
		(start 48.499776 -151.400002)
		(end 48.09998 -151.000206)
		(width 0.127)
		(layer "F.Cu")
		(net "BMC_SMB5_DAT")
	)
	(via
		(at 50.1142 -156.4894)
		(size 0.6096)
		(drill 0.3048)
		(layers "F.Cu" "B.Cu")
		(net "BMC_SMB5_DAT")
	)
	(via
		(at 48.499776 -151.400002)
		(size 0.4572)
		(drill 0.2032)
		(layers "F.Cu" "B.Cu")
		(net "BMC_SMB5_DAT")
	)
	(segment
		(start 50.292254 -157.59557)
		(end 50.292254 -156.667454)
		(width 0.127)
		(layer "B.Cu")
		(net "BMC_SMB5_DAT")
	)
	(segment
		(start 49.4538 -155.829)
		(end 50.1142 -156.4894)
		(width 0.127)
		(layer "B.Cu")
		(net "BMC_SMB5_DAT")
	)
	(segment
		(start 48.09744 -152.517348)
		(end 48.32223 -152.742138)
		(width 0.127)
		(layer "B.Cu")
		(net "BMC_SMB5_DAT")
	)
	(segment
		(start 48.32223 -152.742138)
		(end 48.32223 -152.97785)
		(width 0.127)
		(layer "B.Cu")
		(net "BMC_SMB5_DAT")
	)
	(segment
		(start 49.4538 -154.0764)
		(end 49.4538 -155.829)
		(width 0.127)
		(layer "B.Cu")
		(net "BMC_SMB5_DAT")
	)
	(segment
		(start 48.68164 -153.33726)
		(end 48.71466 -153.33726)
		(width 0.127)
		(layer "B.Cu")
		(net "BMC_SMB5_DAT")
	)
	(segment
		(start 48.71466 -153.33726)
		(end 49.4538 -154.0764)
		(width 0.127)
		(layer "B.Cu")
		(net "BMC_SMB5_DAT")
	)
	(segment
		(start 48.09744 -151.88438)
		(end 48.09744 -152.517348)
		(width 0.127)
		(layer "B.Cu")
		(net "BMC_SMB5_DAT")
	)
	(segment
		(start 48.499776 -151.400002)
		(end 48.499776 -151.482044)
		(width 0.127)
		(layer "B.Cu")
		(net "BMC_SMB5_DAT")
	)
	(segment
		(start 50.257964 -157.62986)
		(end 50.292254 -157.59557)
		(width 0.127)
		(layer "B.Cu")
		(net "BMC_SMB5_DAT")
	)
	(segment
		(start 48.499776 -151.482044)
		(end 48.09744 -151.88438)
		(width 0.127)
		(layer "B.Cu")
		(net "BMC_SMB5_DAT")
	)
	(segment
		(start 50.292254 -156.667454)
		(end 50.1142 -156.4894)
		(width 0.127)
		(layer "B.Cu")
		(net "BMC_SMB5_DAT")
	)
	(segment
		(start 48.32223 -152.97785)
		(end 48.68164 -153.33726)
		(width 0.127)
		(layer "B.Cu")
		(net "BMC_SMB5_DAT")
	)
	(segment
		(start 48.50003 -152.200102)
		(end 48.09998 -151.800052)
		(width 0.127)
		(layer "F.Cu")
		(net "BMC_SMB5_CLK")
	)
	(via
		(at 49.911 -153.393648)
		(size 0.6096)
		(drill 0.3048)
		(layers "F.Cu" "B.Cu")
		(net "BMC_SMB5_CLK")
	)
	(via
		(at 48.50003 -152.200102)
		(size 0.4572)
		(drill 0.2032)
		(layers "F.Cu" "B.Cu")
		(net "BMC_SMB5_CLK")
	)
	(segment
		(start 48.906176 -152.606248)
		(end 48.50003 -152.200102)
		(width 0.127)
		(layer "B.Cu")
		(net "BMC_SMB5_CLK")
	)
	(segment
		(start 49.990248 -153.393648)
		(end 49.911 -153.393648)
		(width 0.127)
		(layer "B.Cu")
		(net "BMC_SMB5_CLK")
	)
	(segment
		(start 48.906176 -153.16327)
		(end 48.906176 -152.606248)
		(width 0.127)
		(layer "B.Cu")
		(net "BMC_SMB5_CLK")
	)
	(segment
		(start 49.911 -153.393648)
		(end 49.136554 -153.393648)
		(width 0.127)
		(layer "B.Cu")
		(net "BMC_SMB5_CLK")
	)
	(segment
		(start 49.136554 -153.393648)
		(end 48.906176 -153.16327)
		(width 0.127)
		(layer "B.Cu")
		(net "BMC_SMB5_CLK")
	)
	(segment
		(start 50.927 -154.3304)
		(end 49.990248 -153.393648)
		(width 0.127)
		(layer "B.Cu")
		(net "BMC_SMB5_CLK")
	)
	(segment
		(start 60.382404 -147.097496)
		(end 59.121802 -147.097496)
		(width 0.127)
		(layer "F.Cu")
		(net "BMC_SMB4_DAT")
	)
	(segment
		(start 59.121802 -147.097496)
		(end 58.174636 -147.097496)
		(width 0.127)
		(layer "F.Cu")
		(net "BMC_SMB4_DAT")
	)
	(segment
		(start 58.174636 -147.097496)
		(end 57.7342 -146.65706)
		(width 0.127)
		(layer "F.Cu")
		(net "BMC_SMB4_DAT")
	)
	(segment
		(start 60.9473 -146.5326)
		(end 60.382404 -147.097496)
		(width 0.127)
		(layer "F.Cu")
		(net "BMC_SMB4_DAT")
	)
	(segment
		(start 57.7342 -146.65706)
		(end 55.642764 -146.65706)
		(width 0.127)
		(layer "F.Cu")
		(net "BMC_SMB4_DAT")
	)
	(segment
		(start 55.642764 -146.65706)
		(end 55.299864 -146.99996)
		(width 0.127)
		(layer "F.Cu")
		(net "BMC_SMB4_DAT")
	)
	(via
		(at 59.121802 -147.097496)
		(size 0.6604)
		(drill 0.3302)
		(layers "F.Cu" "B.Cu")
		(net "BMC_SMB4_DAT")
	)
	(segment
		(start 56.91251 -146.99996)
		(end 58.162444 -148.249894)
		(width 0.127)
		(layer "F.Cu")
		(net "BMC_SMB4_CLK")
	)
	(segment
		(start 60.9219 -147.5994)
		(end 60.840366 -147.5994)
		(width 0.127)
		(layer "F.Cu")
		(net "BMC_SMB4_CLK")
	)
	(segment
		(start 58.162444 -148.249894)
		(end 58.876184 -148.249894)
		(width 0.127)
		(layer "F.Cu")
		(net "BMC_SMB4_CLK")
	)
	(segment
		(start 56.099964 -146.99996)
		(end 56.91251 -146.99996)
		(width 0.127)
		(layer "F.Cu")
		(net "BMC_SMB4_CLK")
	)
	(segment
		(start 58.876184 -148.249894)
		(end 59.068716 -148.442426)
		(width 0.127)
		(layer "F.Cu")
		(net "BMC_SMB4_CLK")
	)
	(segment
		(start 60.840366 -147.5994)
		(end 59.99734 -148.442426)
		(width 0.127)
		(layer "F.Cu")
		(net "BMC_SMB4_CLK")
	)
	(segment
		(start 59.068716 -148.442426)
		(end 59.99734 -148.442426)
		(width 0.127)
		(layer "F.Cu")
		(net "BMC_SMB4_CLK")
	)
	(via
		(at 59.99734 -148.442426)
		(size 0.6604)
		(drill 0.3302)
		(layers "F.Cu" "B.Cu")
		(net "BMC_SMB4_CLK")
	)
	(segment
		(start 56.23052 -146.069304)
		(end 56.099964 -146.19986)
		(width 0.127)
		(layer "F.Cu")
		(net "BMC_SMB3_DAT")
	)
	(segment
		(start 60.850272 -145.496534)
		(end 60.445904 -145.496534)
		(width 0.127)
		(layer "F.Cu")
		(net "BMC_SMB3_DAT")
	)
	(segment
		(start 59.873134 -146.069304)
		(end 56.23052 -146.069304)
		(width 0.127)
		(layer "F.Cu")
		(net "BMC_SMB3_DAT")
	)
	(segment
		(start 60.445904 -145.496534)
		(end 59.873134 -146.069304)
		(width 0.127)
		(layer "F.Cu")
		(net "BMC_SMB3_DAT")
	)
	(via
		(at 59.873134 -146.069304)
		(size 0.6604)
		(drill 0.3302)
		(layers "F.Cu" "B.Cu")
		(net "BMC_SMB3_DAT")
	)
	(segment
		(start 58.635646 -144.8435)
		(end 59.13628 -144.342866)
		(width 0.127)
		(layer "F.Cu")
		(net "BMC_SMB3_CLK")
	)
	(segment
		(start 59.13628 -144.342866)
		(end 59.776106 -144.342866)
		(width 0.127)
		(layer "F.Cu")
		(net "BMC_SMB3_CLK")
	)
	(segment
		(start 60.712604 -144.342866)
		(end 59.776106 -144.342866)
		(width 0.127)
		(layer "F.Cu")
		(net "BMC_SMB3_CLK")
	)
	(segment
		(start 56.099964 -145.400014)
		(end 56.328564 -145.171414)
		(width 0.127)
		(layer "F.Cu")
		(net "BMC_SMB3_CLK")
	)
	(segment
		(start 56.336946 -145.171414)
		(end 56.66486 -144.8435)
		(width 0.127)
		(layer "F.Cu")
		(net "BMC_SMB3_CLK")
	)
	(segment
		(start 56.66486 -144.8435)
		(end 58.635646 -144.8435)
		(width 0.127)
		(layer "F.Cu")
		(net "BMC_SMB3_CLK")
	)
	(segment
		(start 56.328564 -145.171414)
		(end 56.336946 -145.171414)
		(width 0.127)
		(layer "F.Cu")
		(net "BMC_SMB3_CLK")
	)
	(segment
		(start 60.850272 -144.480534)
		(end 60.712604 -144.342866)
		(width 0.127)
		(layer "F.Cu")
		(net "BMC_SMB3_CLK")
	)
	(via
		(at 59.776106 -144.342866)
		(size 0.6604)
		(drill 0.3302)
		(layers "F.Cu" "B.Cu")
		(net "BMC_SMB3_CLK")
	)
	(segment
		(start 44.962318 -133.843268)
		(end 44.962318 -133.50621)
		(width 0.127)
		(layer "F.Cu")
		(net "BMC_SMB2_DAT")
	)
	(segment
		(start 45.2501 -132.810504)
		(end 44.638976 -132.19938)
		(width 0.127)
		(layer "F.Cu")
		(net "BMC_SMB2_DAT")
	)
	(segment
		(start 45.242734 -135.453628)
		(end 45.242734 -137.742676)
		(width 0.127)
		(layer "F.Cu")
		(net "BMC_SMB2_DAT")
	)
	(segment
		(start 45.2501 -133.218428)
		(end 45.2501 -132.810504)
		(width 0.127)
		(layer "F.Cu")
		(net "BMC_SMB2_DAT")
	)
	(segment
		(start 45.242734 -137.742676)
		(end 45.699934 -138.199876)
		(width 0.127)
		(layer "F.Cu")
		(net "BMC_SMB2_DAT")
	)
	(segment
		(start 44.962318 -135.173212)
		(end 45.242734 -135.453628)
		(width 0.127)
		(layer "F.Cu")
		(net "BMC_SMB2_DAT")
	)
	(segment
		(start 44.962318 -133.843268)
		(end 44.962318 -135.173212)
		(width 0.127)
		(layer "F.Cu")
		(net "BMC_SMB2_DAT")
	)
	(segment
		(start 44.638976 -132.19938)
		(end 44.37761 -132.19938)
		(width 0.127)
		(layer "F.Cu")
		(net "BMC_SMB2_DAT")
	)
	(segment
		(start 44.962318 -133.50621)
		(end 45.2501 -133.218428)
		(width 0.127)
		(layer "F.Cu")
		(net "BMC_SMB2_DAT")
	)
	(via
		(at 44.962318 -133.843268)
		(size 0.6604)
		(drill 0.3302)
		(layers "F.Cu" "B.Cu")
		(net "BMC_SMB2_DAT")
	)
	(segment
		(start 46.89983 -137.799826)
		(end 47.29988 -138.199876)
		(width 0.127)
		(layer "F.Cu")
		(net "BMC_SMB2_CLK")
	)
	(via
		(at 47.6504 -137.7823)
		(size 0.6096)
		(drill 0.3048)
		(layers "F.Cu" "B.Cu")
		(net "BMC_SMB2_CLK")
	)
	(via
		(at 46.89983 -137.799826)
		(size 0.4572)
		(drill 0.2032)
		(layers "F.Cu" "B.Cu")
		(net "BMC_SMB2_CLK")
	)
	(segment
		(start 47.6504 -137.7823)
		(end 47.4853 -137.9474)
		(width 0.127)
		(layer "B.Cu")
		(net "BMC_SMB2_CLK")
	)
	(segment
		(start 46.627796 -136.1567)
		(end 46.3804 -136.1567)
		(width 0.127)
		(layer "B.Cu")
		(net "BMC_SMB2_CLK")
	)
	(segment
		(start 47.4853 -137.9474)
		(end 47.047404 -137.9474)
		(width 0.127)
		(layer "B.Cu")
		(net "BMC_SMB2_CLK")
	)
	(segment
		(start 47.047404 -137.9474)
		(end 46.89983 -137.799826)
		(width 0.127)
		(layer "B.Cu")
		(net "BMC_SMB2_CLK")
	)
	(segment
		(start 47.6504 -137.179304)
		(end 46.627796 -136.1567)
		(width 0.127)
		(layer "B.Cu")
		(net "BMC_SMB2_CLK")
	)
	(segment
		(start 47.6504 -137.7823)
		(end 47.6504 -137.179304)
		(width 0.127)
		(layer "B.Cu")
		(net "BMC_SMB2_CLK")
	)
	(segment
		(start 47.900336 -134.13867)
		(end 47.798482 -134.240524)
		(width 0.127)
		(layer "F.Cu")
		(net "BMC_SMB14_DAT")
	)
	(segment
		(start 48.0441 -132.5626)
		(end 48.0441 -133.994906)
		(width 0.127)
		(layer "F.Cu")
		(net "BMC_SMB14_DAT")
	)
	(segment
		(start 47.798482 -135.301482)
		(end 46.500034 -136.59993)
		(width 0.127)
		(layer "F.Cu")
		(net "BMC_SMB14_DAT")
	)
	(segment
		(start 47.798482 -134.240524)
		(end 47.798482 -135.301482)
		(width 0.127)
		(layer "F.Cu")
		(net "BMC_SMB14_DAT")
	)
	(segment
		(start 48.5394 -132.0673)
		(end 48.0441 -132.5626)
		(width 0.127)
		(layer "F.Cu")
		(net "BMC_SMB14_DAT")
	)
	(segment
		(start 48.0441 -133.994906)
		(end 47.900336 -134.13867)
		(width 0.127)
		(layer "F.Cu")
		(net "BMC_SMB14_DAT")
	)
	(via
		(at 47.900336 -134.13867)
		(size 0.6604)
		(drill 0.3302)
		(layers "F.Cu" "B.Cu")
		(net "BMC_SMB14_DAT")
	)
	(segment
		(start 47.498 -133.204204)
		(end 47.3583 -133.343904)
		(width 0.127)
		(layer "F.Cu")
		(net "BMC_SMB14_CLK")
	)
	(segment
		(start 46.500034 -137.157714)
		(end 46.500034 -137.40003)
		(width 0.127)
		(layer "F.Cu")
		(net "BMC_SMB14_CLK")
	)
	(segment
		(start 46.157134 -135.992362)
		(end 46.157134 -136.814814)
		(width 0.127)
		(layer "F.Cu")
		(net "BMC_SMB14_CLK")
	)
	(segment
		(start 46.157134 -136.814814)
		(end 46.500034 -137.157714)
		(width 0.127)
		(layer "F.Cu")
		(net "BMC_SMB14_CLK")
	)
	(segment
		(start 47.498 -133.150356)
		(end 47.498 -132.1943)
		(width 0.127)
		(layer "F.Cu")
		(net "BMC_SMB14_CLK")
	)
	(segment
		(start 47.3583 -133.343904)
		(end 47.3583 -134.428484)
		(width 0.127)
		(layer "F.Cu")
		(net "BMC_SMB14_CLK")
	)
	(segment
		(start 47.498 -133.150356)
		(end 47.498 -133.204204)
		(width 0.127)
		(layer "F.Cu")
		(net "BMC_SMB14_CLK")
	)
	(segment
		(start 47.36592 -134.783576)
		(end 46.157134 -135.992362)
		(width 0.127)
		(layer "F.Cu")
		(net "BMC_SMB14_CLK")
	)
	(segment
		(start 47.3583 -134.428484)
		(end 47.36592 -134.436104)
		(width 0.127)
		(layer "F.Cu")
		(net "BMC_SMB14_CLK")
	)
	(segment
		(start 47.36592 -134.436104)
		(end 47.36592 -134.783576)
		(width 0.127)
		(layer "F.Cu")
		(net "BMC_SMB14_CLK")
	)
	(via
		(at 47.498 -133.150356)
		(size 0.6604)
		(drill 0.3302)
		(layers "F.Cu" "B.Cu")
		(net "BMC_SMB14_CLK")
	)
	(segment
		(start 55.299864 -145.400014)
		(end 54.899814 -145.800064)
		(width 0.127)
		(layer "F.Cu")
		(net "BMC_SMB13_DAT")
	)
	(via
		(at 59.619388 -146.002756)
		(size 0.6096)
		(drill 0.3048)
		(layers "F.Cu" "B.Cu")
		(net "BMC_SMB13_DAT")
	)
	(via
		(at 54.899814 -145.800064)
		(size 0.4572)
		(drill 0.2032)
		(layers "F.Cu" "B.Cu")
		(net "BMC_SMB13_DAT")
	)
	(segment
		(start 60.5917 -145.034)
		(end 60.5917 -145.301716)
		(width 0.127)
		(layer "B.Cu")
		(net "BMC_SMB13_DAT")
	)
	(segment
		(start 54.899814 -145.800064)
		(end 54.967124 -145.732754)
		(width 0.127)
		(layer "B.Cu")
		(net "BMC_SMB13_DAT")
	)
	(segment
		(start 60.5917 -145.301716)
		(end 59.89066 -146.002756)
		(width 0.127)
		(layer "B.Cu")
		(net "BMC_SMB13_DAT")
	)
	(segment
		(start 59.349386 -145.732754)
		(end 59.619388 -146.002756)
		(width 0.127)
		(layer "B.Cu")
		(net "BMC_SMB13_DAT")
	)
	(segment
		(start 54.967124 -145.732754)
		(end 59.349386 -145.732754)
		(width 0.127)
		(layer "B.Cu")
		(net "BMC_SMB13_DAT")
	)
	(segment
		(start 59.89066 -146.002756)
		(end 59.619388 -146.002756)
		(width 0.127)
		(layer "B.Cu")
		(net "BMC_SMB13_DAT")
	)
	(segment
		(start 54.099714 -145.800064)
		(end 54.499764 -145.400014)
		(width 0.127)
		(layer "F.Cu")
		(net "BMC_SMB13_CLK")
	)
	(segment
		(start 54.499764 -145.400014)
		(end 54.500018 -145.400014)
		(width 0.127)
		(layer "F.Cu")
		(net "BMC_SMB13_CLK")
	)
	(via
		(at 54.099714 -145.800064)
		(size 0.4572)
		(drill 0.2032)
		(layers "F.Cu" "B.Cu")
		(net "BMC_SMB13_CLK")
	)
	(via
		(at 59.2836 -147.1422)
		(size 0.6096)
		(drill 0.3048)
		(layers "F.Cu" "B.Cu")
		(net "BMC_SMB13_CLK")
	)
	(segment
		(start 60.285122 -147.1422)
		(end 60.5917 -146.835622)
		(width 0.127)
		(layer "B.Cu")
		(net "BMC_SMB13_CLK")
	)
	(segment
		(start 59.2836 -147.1422)
		(end 60.285122 -147.1422)
		(width 0.127)
		(layer "B.Cu")
		(net "BMC_SMB13_CLK")
	)
	(segment
		(start 59.2836 -146.4056)
		(end 58.839354 -145.961354)
		(width 0.127)
		(layer "B.Cu")
		(net "BMC_SMB13_CLK")
	)
	(segment
		(start 55.333392 -145.961354)
		(end 55.100982 -146.193764)
		(width 0.127)
		(layer "B.Cu")
		(net "BMC_SMB13_CLK")
	)
	(segment
		(start 54.493414 -146.193764)
		(end 54.099714 -145.800064)
		(width 0.127)
		(layer "B.Cu")
		(net "BMC_SMB13_CLK")
	)
	(segment
		(start 55.100982 -146.193764)
		(end 54.493414 -146.193764)
		(width 0.127)
		(layer "B.Cu")
		(net "BMC_SMB13_CLK")
	)
	(segment
		(start 60.5917 -146.835622)
		(end 60.5917 -146.0754)
		(width 0.127)
		(layer "B.Cu")
		(net "BMC_SMB13_CLK")
	)
	(segment
		(start 59.2836 -147.1422)
		(end 59.2836 -146.4056)
		(width 0.127)
		(layer "B.Cu")
		(net "BMC_SMB13_CLK")
	)
	(segment
		(start 58.839354 -145.961354)
		(end 55.333392 -145.961354)
		(width 0.127)
		(layer "B.Cu")
		(net "BMC_SMB13_CLK")
	)
	(segment
		(start 53.299868 -144.200118)
		(end 53.299614 -144.200118)
		(width 0.127)
		(layer "F.Cu")
		(net "BMC_SMB12_DAT")
	)
	(segment
		(start 53.299614 -144.200118)
		(end 52.899818 -144.599914)
		(width 0.127)
		(layer "F.Cu")
		(net "BMC_SMB12_DAT")
	)
	(via
		(at 53.299868 -144.200118)
		(size 0.4572)
		(drill 0.2032)
		(layers "F.Cu" "B.Cu")
		(net "BMC_SMB12_DAT")
	)
	(via
		(at 66.225674 -142.561056)
		(size 0.508)
		(drill 0.254)
		(layers "F.Cu" "B.Cu")
		(net "BMC_SMB12_DAT")
	)
	(via
		(at 66.701162 -143.342868)
		(size 0.6096)
		(drill 0.3048)
		(layers "F.Cu" "B.Cu")
		(net "BMC_SMB12_DAT")
	)
	(segment
		(start 66.763392 -143.405098)
		(end 66.701162 -143.342868)
		(width 0.127)
		(layer "B.Cu")
		(net "BMC_SMB12_DAT")
	)
	(segment
		(start 66.225674 -142.561056)
		(end 66.225674 -142.86738)
		(width 0.127)
		(layer "B.Cu")
		(net "BMC_SMB12_DAT")
	)
	(segment
		(start 66.225674 -142.86738)
		(end 66.701162 -143.342868)
		(width 0.127)
		(layer "B.Cu")
		(net "BMC_SMB12_DAT")
	)
	(segment
		(start 67.771264 -143.405098)
		(end 66.763392 -143.405098)
		(width 0.127)
		(layer "B.Cu")
		(net "BMC_SMB12_DAT")
	)
	(segment
		(start 66.225674 -142.561056)
		(end 66.095372 -142.691358)
		(width 0.127)
		(layer "In5.Cu")
		(net "BMC_SMB12_DAT")
	)
	(segment
		(start 59.172348 -142.691358)
		(end 59.024266 -142.543276)
		(width 0.127)
		(layer "In5.Cu")
		(net "BMC_SMB12_DAT")
	)
	(segment
		(start 59.024266 -142.543276)
		(end 58.237628 -142.543276)
		(width 0.127)
		(layer "In5.Cu")
		(net "BMC_SMB12_DAT")
	)
	(segment
		(start 66.095372 -142.691358)
		(end 59.172348 -142.691358)
		(width 0.127)
		(layer "In5.Cu")
		(net "BMC_SMB12_DAT")
	)
	(segment
		(start 56.186832 -144.594072)
		(end 53.693822 -144.594072)
		(width 0.127)
		(layer "In5.Cu")
		(net "BMC_SMB12_DAT")
	)
	(segment
		(start 53.693822 -144.594072)
		(end 53.299868 -144.200118)
		(width 0.127)
		(layer "In5.Cu")
		(net "BMC_SMB12_DAT")
	)
	(segment
		(start 58.237628 -142.543276)
		(end 56.186832 -144.594072)
		(width 0.127)
		(layer "In5.Cu")
		(net "BMC_SMB12_DAT")
	)
	(segment
		(start 54.099714 -146.599656)
		(end 53.699918 -146.19986)
		(width 0.127)
		(layer "F.Cu")
		(net "BMC_SMB12_CLK")
	)
	(segment
		(start 54.099714 -146.59991)
		(end 54.099714 -146.599656)
		(width 0.127)
		(layer "F.Cu")
		(net "BMC_SMB12_CLK")
	)
	(via
		(at 66.779394 -144.356074)
		(size 0.6096)
		(drill 0.3048)
		(layers "F.Cu" "B.Cu")
		(net "BMC_SMB12_CLK")
	)
	(via
		(at 64.6684 -144.1958)
		(size 0.508)
		(drill 0.254)
		(layers "F.Cu" "B.Cu")
		(net "BMC_SMB12_CLK")
	)
	(via
		(at 54.099714 -146.59991)
		(size 0.4572)
		(drill 0.2032)
		(layers "F.Cu" "B.Cu")
		(net "BMC_SMB12_CLK")
	)
	(segment
		(start 65.5574 -143.7132)
		(end 66.04 -143.7132)
		(width 0.127)
		(layer "B.Cu")
		(net "BMC_SMB12_CLK")
	)
	(segment
		(start 64.6684 -144.1958)
		(end 65.0748 -144.1958)
		(width 0.127)
		(layer "B.Cu")
		(net "BMC_SMB12_CLK")
	)
	(segment
		(start 65.0748 -144.1958)
		(end 65.5574 -143.7132)
		(width 0.127)
		(layer "B.Cu")
		(net "BMC_SMB12_CLK")
	)
	(segment
		(start 66.74612 -144.3228)
		(end 66.779394 -144.356074)
		(width 0.127)
		(layer "B.Cu")
		(net "BMC_SMB12_CLK")
	)
	(segment
		(start 67.7672 -145.1991)
		(end 67.62242 -145.1991)
		(width 0.127)
		(layer "B.Cu")
		(net "BMC_SMB12_CLK")
	)
	(segment
		(start 66.04 -143.7132)
		(end 66.6496 -144.3228)
		(width 0.127)
		(layer "B.Cu")
		(net "BMC_SMB12_CLK")
	)
	(segment
		(start 67.62242 -145.1991)
		(end 66.779394 -144.356074)
		(width 0.127)
		(layer "B.Cu")
		(net "BMC_SMB12_CLK")
	)
	(segment
		(start 66.6496 -144.3228)
		(end 66.74612 -144.3228)
		(width 0.127)
		(layer "B.Cu")
		(net "BMC_SMB12_CLK")
	)
	(segment
		(start 54.12867 -146.59991)
		(end 54.099714 -146.59991)
		(width 0.127)
		(layer "In5.Cu")
		(net "BMC_SMB12_CLK")
	)
	(segment
		(start 54.52237 -146.99361)
		(end 54.12867 -146.59991)
		(width 0.127)
		(layer "In5.Cu")
		(net "BMC_SMB12_CLK")
	)
	(segment
		(start 60.292234 -144.63268)
		(end 60.271914 -144.653)
		(width 0.127)
		(layer "In5.Cu")
		(net "BMC_SMB12_CLK")
	)
	(segment
		(start 64.6684 -144.1958)
		(end 64.23152 -144.63268)
		(width 0.127)
		(layer "In5.Cu")
		(net "BMC_SMB12_CLK")
	)
	(segment
		(start 64.23152 -144.63268)
		(end 60.292234 -144.63268)
		(width 0.127)
		(layer "In5.Cu")
		(net "BMC_SMB12_CLK")
	)
	(segment
		(start 60.271914 -144.653)
		(end 58.690764 -144.653)
		(width 0.127)
		(layer "In5.Cu")
		(net "BMC_SMB12_CLK")
	)
	(segment
		(start 58.690764 -144.653)
		(end 56.350154 -146.99361)
		(width 0.127)
		(layer "In5.Cu")
		(net "BMC_SMB12_CLK")
	)
	(segment
		(start 56.350154 -146.99361)
		(end 54.52237 -146.99361)
		(width 0.127)
		(layer "In5.Cu")
		(net "BMC_SMB12_CLK")
	)
	(segment
		(start 60.591192 -142.9512)
		(end 60.1218 -142.9512)
		(width 0.127)
		(layer "F.Cu")
		(net "BMC_SMB11_DAT")
	)
	(segment
		(start 61.098684 -143.458692)
		(end 60.591192 -142.9512)
		(width 0.127)
		(layer "F.Cu")
		(net "BMC_SMB11_DAT")
	)
	(segment
		(start 60.1218 -142.9512)
		(end 59.944 -142.9512)
		(width 0.127)
		(layer "F.Cu")
		(net "BMC_SMB11_DAT")
	)
	(segment
		(start 59.944 -142.9512)
		(end 59.675522 -143.219678)
		(width 0.127)
		(layer "F.Cu")
		(net "BMC_SMB11_DAT")
	)
	(segment
		(start 53.699918 -146.99996)
		(end 54.099968 -147.40001)
		(width 0.127)
		(layer "F.Cu")
		(net "BMC_SMB11_DAT")
	)
	(segment
		(start 59.675522 -143.219678)
		(end 59.675522 -143.560546)
		(width 0.127)
		(layer "F.Cu")
		(net "BMC_SMB11_DAT")
	)
	(via
		(at 54.099968 -147.40001)
		(size 0.4572)
		(drill 0.2032)
		(layers "F.Cu" "B.Cu")
		(net "BMC_SMB11_DAT")
	)
	(via
		(at 60.1218 -142.9512)
		(size 0.6604)
		(drill 0.3302)
		(layers "F.Cu" "B.Cu")
		(net "BMC_SMB11_DAT")
	)
	(via
		(at 59.675522 -143.560546)
		(size 0.508)
		(drill 0.254)
		(layers "F.Cu" "B.Cu")
		(net "BMC_SMB11_DAT")
	)
	(segment
		(start 53.706014 -146.436588)
		(end 53.706014 -147.006056)
		(width 0.127)
		(layer "In5.Cu")
		(net "BMC_SMB11_DAT")
	)
	(segment
		(start 58.281824 -144.13103)
		(end 56.206644 -146.20621)
		(width 0.127)
		(layer "In5.Cu")
		(net "BMC_SMB11_DAT")
	)
	(segment
		(start 53.706014 -147.006056)
		(end 54.099968 -147.40001)
		(width 0.127)
		(layer "In5.Cu")
		(net "BMC_SMB11_DAT")
	)
	(segment
		(start 59.675522 -143.560546)
		(end 59.675522 -143.9418)
		(width 0.127)
		(layer "In5.Cu")
		(net "BMC_SMB11_DAT")
	)
	(segment
		(start 53.936392 -146.20621)
		(end 53.706014 -146.436588)
		(width 0.127)
		(layer "In5.Cu")
		(net "BMC_SMB11_DAT")
	)
	(segment
		(start 59.675522 -143.9418)
		(end 59.486292 -144.13103)
		(width 0.127)
		(layer "In5.Cu")
		(net "BMC_SMB11_DAT")
	)
	(segment
		(start 59.486292 -144.13103)
		(end 58.281824 -144.13103)
		(width 0.127)
		(layer "In5.Cu")
		(net "BMC_SMB11_DAT")
	)
	(segment
		(start 56.206644 -146.20621)
		(end 53.936392 -146.20621)
		(width 0.127)
		(layer "In5.Cu")
		(net "BMC_SMB11_DAT")
	)
	(segment
		(start 55.957724 -144.942814)
		(end 56.242204 -144.942814)
		(width 0.127)
		(layer "F.Cu")
		(net "BMC_SMB11_CLK")
	)
	(segment
		(start 59.2074 -143.190214)
		(end 59.2074 -142.875)
		(width 0.127)
		(layer "F.Cu")
		(net "BMC_SMB11_CLK")
	)
	(segment
		(start 59.665108 -142.417292)
		(end 61.098684 -142.417292)
		(width 0.127)
		(layer "F.Cu")
		(net "BMC_SMB11_CLK")
	)
	(segment
		(start 55.299864 -144.599914)
		(end 55.614824 -144.599914)
		(width 0.127)
		(layer "F.Cu")
		(net "BMC_SMB11_CLK")
	)
	(segment
		(start 56.242204 -144.942814)
		(end 56.809386 -144.375632)
		(width 0.127)
		(layer "F.Cu")
		(net "BMC_SMB11_CLK")
	)
	(segment
		(start 58.65876 -143.738854)
		(end 59.2074 -143.190214)
		(width 0.127)
		(layer "F.Cu")
		(net "BMC_SMB11_CLK")
	)
	(segment
		(start 58.021982 -144.375632)
		(end 58.65876 -143.738854)
		(width 0.127)
		(layer "F.Cu")
		(net "BMC_SMB11_CLK")
	)
	(segment
		(start 56.809386 -144.375632)
		(end 58.021982 -144.375632)
		(width 0.127)
		(layer "F.Cu")
		(net "BMC_SMB11_CLK")
	)
	(segment
		(start 55.614824 -144.599914)
		(end 55.957724 -144.942814)
		(width 0.127)
		(layer "F.Cu")
		(net "BMC_SMB11_CLK")
	)
	(segment
		(start 59.2074 -142.875)
		(end 59.665108 -142.417292)
		(width 0.127)
		(layer "F.Cu")
		(net "BMC_SMB11_CLK")
	)
	(via
		(at 58.65876 -143.738854)
		(size 0.6604)
		(drill 0.3302)
		(layers "F.Cu" "B.Cu")
		(net "BMC_SMB11_CLK")
	)
	(segment
		(start 55.700422 -144.200118)
		(end 56.099964 -144.59966)
		(width 0.127)
		(layer "F.Cu")
		(net "BMC_SMB10_DAT")
	)
	(segment
		(start 56.099964 -144.59966)
		(end 56.099964 -144.599914)
		(width 0.127)
		(layer "F.Cu")
		(net "BMC_SMB10_DAT")
	)
	(via
		(at 59.2074 -144.7546)
		(size 0.6096)
		(drill 0.3048)
		(layers "F.Cu" "B.Cu")
		(net "BMC_SMB10_DAT")
	)
	(via
		(at 55.700422 -144.200118)
		(size 0.4572)
		(drill 0.2032)
		(layers "F.Cu" "B.Cu")
		(net "BMC_SMB10_DAT")
	)
	(segment
		(start 55.700422 -144.200118)
		(end 56.254904 -144.7546)
		(width 0.127)
		(layer "B.Cu")
		(net "BMC_SMB10_DAT")
	)
	(segment
		(start 59.2074 -144.7546)
		(end 59.313826 -144.7546)
		(width 0.127)
		(layer "B.Cu")
		(net "BMC_SMB10_DAT")
	)
	(segment
		(start 60.126626 -143.9418)
		(end 60.5155 -143.9418)
		(width 0.127)
		(layer "B.Cu")
		(net "BMC_SMB10_DAT")
	)
	(segment
		(start 59.313826 -144.7546)
		(end 60.126626 -143.9418)
		(width 0.127)
		(layer "B.Cu")
		(net "BMC_SMB10_DAT")
	)
	(segment
		(start 56.254904 -144.7546)
		(end 59.2074 -144.7546)
		(width 0.127)
		(layer "B.Cu")
		(net "BMC_SMB10_DAT")
	)
	(segment
		(start 54.899814 -144.200372)
		(end 54.500272 -144.599914)
		(width 0.127)
		(layer "F.Cu")
		(net "BMC_SMB10_CLK")
	)
	(segment
		(start 54.500272 -144.599914)
		(end 54.500018 -144.599914)
		(width 0.127)
		(layer "F.Cu")
		(net "BMC_SMB10_CLK")
	)
	(via
		(at 59.2836 -142.3924)
		(size 0.6096)
		(drill 0.3048)
		(layers "F.Cu" "B.Cu")
		(net "BMC_SMB10_CLK")
	)
	(via
		(at 54.899814 -144.200372)
		(size 0.4572)
		(drill 0.2032)
		(layers "F.Cu" "B.Cu")
		(net "BMC_SMB10_CLK")
	)
	(segment
		(start 60.5155 -142.9004)
		(end 59.7916 -142.9004)
		(width 0.127)
		(layer "B.Cu")
		(net "BMC_SMB10_CLK")
	)
	(segment
		(start 59.2836 -142.3924)
		(end 58.166 -142.3924)
		(width 0.127)
		(layer "B.Cu")
		(net "BMC_SMB10_CLK")
	)
	(segment
		(start 54.899814 -144.120362)
		(end 54.899814 -144.200372)
		(width 0.127)
		(layer "B.Cu")
		(net "BMC_SMB10_CLK")
	)
	(segment
		(start 59.7916 -142.9004)
		(end 59.2836 -142.3924)
		(width 0.127)
		(layer "B.Cu")
		(net "BMC_SMB10_CLK")
	)
	(segment
		(start 57.0865 -143.4719)
		(end 56.464454 -143.4719)
		(width 0.127)
		(layer "B.Cu")
		(net "BMC_SMB10_CLK")
	)
	(segment
		(start 56.375554 -143.5608)
		(end 55.459376 -143.5608)
		(width 0.127)
		(layer "B.Cu")
		(net "BMC_SMB10_CLK")
	)
	(segment
		(start 55.459376 -143.5608)
		(end 54.899814 -144.120362)
		(width 0.127)
		(layer "B.Cu")
		(net "BMC_SMB10_CLK")
	)
	(segment
		(start 56.464454 -143.4719)
		(end 56.375554 -143.5608)
		(width 0.127)
		(layer "B.Cu")
		(net "BMC_SMB10_CLK")
	)
	(segment
		(start 58.166 -142.3924)
		(end 57.0865 -143.4719)
		(width 0.127)
		(layer "B.Cu")
		(net "BMC_SMB10_CLK")
	)
	(segment
		(start 46.900338 -138.600434)
		(end 47.29988 -138.999976)
		(width 0.127)
		(layer "F.Cu")
		(net "BMC_SMB1_DAT")
	)
	(segment
		(start 46.900084 -138.600434)
		(end 46.900338 -138.600434)
		(width 0.127)
		(layer "F.Cu")
		(net "BMC_SMB1_DAT")
	)
	(via
		(at 45.85716 -137.145014)
		(size 0.6096)
		(drill 0.3048)
		(layers "F.Cu" "B.Cu")
		(net "BMC_SMB1_DAT")
	)
	(via
		(at 46.900084 -138.600434)
		(size 0.4572)
		(drill 0.2032)
		(layers "F.Cu" "B.Cu")
		(net "BMC_SMB1_DAT")
	)
	(segment
		(start 46.493684 -138.194034)
		(end 46.493684 -137.636758)
		(width 0.127)
		(layer "B.Cu")
		(net "BMC_SMB1_DAT")
	)
	(segment
		(start 46.493684 -137.636758)
		(end 46.49343 -137.636504)
		(width 0.127)
		(layer "B.Cu")
		(net "BMC_SMB1_DAT")
	)
	(segment
		(start 46.07052 -137.358374)
		(end 45.85716 -137.145014)
		(width 0.127)
		(layer "B.Cu")
		(net "BMC_SMB1_DAT")
	)
	(segment
		(start 46.23943 -137.358374)
		(end 46.07052 -137.358374)
		(width 0.127)
		(layer "B.Cu")
		(net "BMC_SMB1_DAT")
	)
	(segment
		(start 45.3644 -136.1059)
		(end 45.3644 -136.652254)
		(width 0.127)
		(layer "B.Cu")
		(net "BMC_SMB1_DAT")
	)
	(segment
		(start 46.49343 -137.612374)
		(end 46.23943 -137.358374)
		(width 0.127)
		(layer "B.Cu")
		(net "BMC_SMB1_DAT")
	)
	(segment
		(start 46.49343 -137.636504)
		(end 46.49343 -137.612374)
		(width 0.127)
		(layer "B.Cu")
		(net "BMC_SMB1_DAT")
	)
	(segment
		(start 45.3644 -136.652254)
		(end 45.85716 -137.145014)
		(width 0.127)
		(layer "B.Cu")
		(net "BMC_SMB1_DAT")
	)
	(segment
		(start 46.900084 -138.600434)
		(end 46.493684 -138.194034)
		(width 0.127)
		(layer "B.Cu")
		(net "BMC_SMB1_DAT")
	)
	(segment
		(start 46.900084 -139.400534)
		(end 46.900338 -139.400534)
		(width 0.127)
		(layer "F.Cu")
		(net "BMC_SMB1_CLK")
	)
	(segment
		(start 46.900338 -139.400534)
		(end 47.29988 -139.800076)
		(width 0.127)
		(layer "F.Cu")
		(net "BMC_SMB1_CLK")
	)
	(via
		(at 47.498 -126.873)
		(size 0.508)
		(drill 0.254)
		(layers "F.Cu" "B.Cu")
		(net "BMC_SMB1_CLK")
	)
	(via
		(at 46.900084 -139.400534)
		(size 0.4572)
		(drill 0.2032)
		(layers "F.Cu" "B.Cu")
		(net "BMC_SMB1_CLK")
	)
	(via
		(at 48.365664 -126.583694)
		(size 0.6096)
		(drill 0.3048)
		(layers "F.Cu" "B.Cu")
		(net "BMC_SMB1_CLK")
	)
	(segment
		(start 48.365664 -126.583694)
		(end 48.289464 -126.507494)
		(width 0.127)
		(layer "B.Cu")
		(net "BMC_SMB1_CLK")
	)
	(segment
		(start 48.365664 -126.957836)
		(end 47.5742 -127.7493)
		(width 0.127)
		(layer "B.Cu")
		(net "BMC_SMB1_CLK")
	)
	(segment
		(start 48.289464 -126.507494)
		(end 47.863506 -126.507494)
		(width 0.127)
		(layer "B.Cu")
		(net "BMC_SMB1_CLK")
	)
	(segment
		(start 48.365664 -126.583694)
		(end 48.365664 -126.957836)
		(width 0.127)
		(layer "B.Cu")
		(net "BMC_SMB1_CLK")
	)
	(segment
		(start 47.863506 -126.507494)
		(end 47.498 -126.873)
		(width 0.127)
		(layer "B.Cu")
		(net "BMC_SMB1_CLK")
	)
	(segment
		(start 46.957996 -128.600454)
		(end 46.957996 -129.50317)
		(width 0.127)
		(layer "In2.Cu")
		(net "BMC_SMB1_CLK")
	)
	(segment
		(start 45.94479 -138.17473)
		(end 46.204378 -138.17473)
		(width 0.0889)
		(layer "In2.Cu")
		(net "BMC_SMB1_CLK")
	)
	(segment
		(start 46.474888 -138.880088)
		(end 46.900084 -139.305284)
		(width 0.0889)
		(layer "In2.Cu")
		(net "BMC_SMB1_CLK")
	)
	(segment
		(start 46.290992 -129.9464)
		(end 45.980096 -130.257296)
		(width 0.127)
		(layer "In2.Cu")
		(net "BMC_SMB1_CLK")
	)
	(segment
		(start 45.8724 -137.241534)
		(end 45.725334 -137.3886)
		(width 0.127)
		(layer "In2.Cu")
		(net "BMC_SMB1_CLK")
	)
	(segment
		(start 46.900084 -139.305284)
		(end 46.900084 -139.400534)
		(width 0.0889)
		(layer "In2.Cu")
		(net "BMC_SMB1_CLK")
	)
	(segment
		(start 45.725334 -137.955274)
		(end 45.94479 -138.17473)
		(width 0.0889)
		(layer "In2.Cu")
		(net "BMC_SMB1_CLK")
	)
	(segment
		(start 46.514766 -129.9464)
		(end 46.290992 -129.9464)
		(width 0.127)
		(layer "In2.Cu")
		(net "BMC_SMB1_CLK")
	)
	(segment
		(start 45.980096 -130.257296)
		(end 45.980096 -131.642104)
		(width 0.127)
		(layer "In2.Cu")
		(net "BMC_SMB1_CLK")
	)
	(segment
		(start 47.498 -128.06045)
		(end 46.957996 -128.600454)
		(width 0.127)
		(layer "In2.Cu")
		(net "BMC_SMB1_CLK")
	)
	(segment
		(start 47.498 -126.873)
		(end 47.498 -128.06045)
		(width 0.127)
		(layer "In2.Cu")
		(net "BMC_SMB1_CLK")
	)
	(segment
		(start 46.204378 -138.17473)
		(end 46.474888 -138.44524)
		(width 0.0889)
		(layer "In2.Cu")
		(net "BMC_SMB1_CLK")
	)
	(segment
		(start 45.725334 -137.3886)
		(end 45.725334 -137.955274)
		(width 0.0889)
		(layer "In2.Cu")
		(net "BMC_SMB1_CLK")
	)
	(segment
		(start 46.957996 -129.50317)
		(end 46.514766 -129.9464)
		(width 0.127)
		(layer "In2.Cu")
		(net "BMC_SMB1_CLK")
	)
	(segment
		(start 45.980096 -131.642104)
		(end 45.8724 -131.7498)
		(width 0.127)
		(layer "In2.Cu")
		(net "BMC_SMB1_CLK")
	)
	(segment
		(start 45.8724 -131.7498)
		(end 45.8724 -137.241534)
		(width 0.127)
		(layer "In2.Cu")
		(net "BMC_SMB1_CLK")
	)
	(segment
		(start 46.474888 -138.44524)
		(end 46.474888 -138.880088)
		(width 0.0889)
		(layer "In2.Cu")
		(net "BMC_SMB1_CLK")
	)
	(segment
		(start 178.43881 -151.654256)
		(end 178.43881 -149.159468)
		(width 0.254)
		(layer "F.Cu")
		(net "AGND_P5V")
	)
	(via
		(at 178.43881 -151.654256)
		(size 0.508)
		(drill 0.254)
		(layers "F.Cu" "B.Cu")
		(net "AGND_P5V")
	)
	(via
		(at 184.15 -146.3294)
		(size 0.508)
		(drill 0.254)
		(layers "F.Cu" "B.Cu")
		(net "AGND_P5V")
	)
	(via
		(at 185.253884 -145.761964)
		(size 0.6604)
		(drill 0.3302)
		(layers "F.Cu" "B.Cu")
		(net "AGND_P5V")
	)
	(segment
		(start 184.15 -146.3294)
		(end 184.15 -146.647154)
		(width 0.254)
		(layer "In2.Cu")
		(net "AGND_P5V")
	)
	(segment
		(start 184.15 -146.647154)
		(end 179.142898 -151.654256)
		(width 0.254)
		(layer "In2.Cu")
		(net "AGND_P5V")
	)
	(segment
		(start 179.142898 -151.654256)
		(end 178.43881 -151.654256)
		(width 0.254)
		(layer "In2.Cu")
		(net "AGND_P5V")
	)
	(segment
		(start 40.284146 -180.64861)
		(end 41.1734 -180.64861)
		(width 0.508)
		(layer "F.Cu")
		(net "AGND_P3V3_STBY")
	)
	(via
		(at 41.1734 -180.64861)
		(size 0.508)
		(drill 0.254)
		(layers "F.Cu" "B.Cu")
		(net "AGND_P3V3_STBY")
	)
	(via
		(at 32.409638 -176.080674)
		(size 0.6604)
		(drill 0.3302)
		(layers "F.Cu" "B.Cu")
		(net "AGND_P3V3_STBY")
	)
	(via
		(at 34.092642 -175.520858)
		(size 0.7112)
		(drill 0.4064)
		(layers "F.Cu" "B.Cu")
		(net "AGND_P3V3_STBY")
	)
	(segment
		(start 39.310056 -178.015392)
		(end 39.310056 -179.466748)
		(width 0.254)
		(layer "In2.Cu")
		(net "AGND_P3V3_STBY")
	)
	(segment
		(start 34.092642 -175.520858)
		(end 35.886136 -177.314352)
		(width 0.254)
		(layer "In2.Cu")
		(net "AGND_P3V3_STBY")
	)
	(segment
		(start 38.609016 -177.314352)
		(end 39.310056 -178.015392)
		(width 0.254)
		(layer "In2.Cu")
		(net "AGND_P3V3_STBY")
	)
	(segment
		(start 35.886136 -177.314352)
		(end 38.609016 -177.314352)
		(width 0.254)
		(layer "In2.Cu")
		(net "AGND_P3V3_STBY")
	)
	(segment
		(start 39.310056 -179.466748)
		(end 40.491918 -180.64861)
		(width 0.254)
		(layer "In2.Cu")
		(net "AGND_P3V3_STBY")
	)
	(segment
		(start 40.491918 -180.64861)
		(end 41.1734 -180.64861)
		(width 0.254)
		(layer "In2.Cu")
		(net "AGND_P3V3_STBY")
	)
	(segment
		(start 66.9544 -153.797)
		(end 66.675 -153.5176)
		(width 0.127)
		(layer "F.Cu")
		(net "50M_CLK_OUT_R")
	)
	(segment
		(start 67.4624 -151.638)
		(end 67.9704 -151.638)
		(width 0.127)
		(layer "F.Cu")
		(net "50M_CLK_OUT_R")
	)
	(segment
		(start 67.9577 -153.797)
		(end 66.9544 -153.797)
		(width 0.127)
		(layer "F.Cu")
		(net "50M_CLK_OUT_R")
	)
	(segment
		(start 66.675 -152.4254)
		(end 67.4624 -151.638)
		(width 0.127)
		(layer "F.Cu")
		(net "50M_CLK_OUT_R")
	)
	(segment
		(start 66.675 -153.5176)
		(end 66.675 -152.4254)
		(width 0.127)
		(layer "F.Cu")
		(net "50M_CLK_OUT_R")
	)
	(segment
		(start 68.712334 -154.650186)
		(end 68.8467 -154.51582)
		(width 0.127)
		(layer "F.Cu")
		(net "50M_CLK_OUT")
	)
	(segment
		(start 68.8467 -154.51582)
		(end 68.8467 -153.797)
		(width 0.127)
		(layer "F.Cu")
		(net "50M_CLK_OUT")
	)
	(segment
		(start 68.712334 -155.452826)
		(end 68.712334 -154.650186)
		(width 0.127)
		(layer "F.Cu")
		(net "50M_CLK_OUT")
	)
	(segment
		(start 75.0951 -151.7396)
		(end 74.9935 -151.638)
		(width 0.127)
		(layer "F.Cu")
		(net "50M_CLK_OE")
	)
	(segment
		(start 76.2508 -151.4856)
		(end 75.9968 -151.7396)
		(width 0.127)
		(layer "F.Cu")
		(net "50M_CLK_OE")
	)
	(segment
		(start 75.9968 -151.7396)
		(end 75.0951 -151.7396)
		(width 0.127)
		(layer "F.Cu")
		(net "50M_CLK_OE")
	)
	(segment
		(start 76.2508 -150.7871)
		(end 76.2508 -151.4856)
		(width 0.127)
		(layer "F.Cu")
		(net "50M_CLK_OE")
	)
	(segment
		(start 74.9935 -151.638)
		(end 73.0504 -151.638)
		(width 0.127)
		(layer "F.Cu")
		(net "50M_CLK_OE")
	)
	(via
		(at 75.9968 -151.7396)
		(size 0.6604)
		(drill 0.3302)
		(layers "F.Cu" "B.Cu")
		(net "50M_CLK_OE")
	)
	(segment
		(start 176.4411 -30.268418)
		(end 177.6095 -29.100018)
		(width 0.127)
		(layer "F.Cu")
		(net "ZDEF_EXTA_TP_D2")
	)
	(segment
		(start 176.4411 -36.4617)
		(end 176.4411 -30.268418)
		(width 0.127)
		(layer "F.Cu")
		(net "ZDEF_EXTA_TP_D2")
	)
	(segment
		(start 178.0794 -38.1)
		(end 176.4411 -36.4617)
		(width 0.127)
		(layer "F.Cu")
		(net "ZDEF_EXTA_TP_D2")
	)
	(segment
		(start 178.0794 -38.5064)
		(end 178.0794 -38.1)
		(width 0.127)
		(layer "F.Cu")
		(net "ZDEF_EXTA_TP_D2")
	)
	(segment
		(start 177.6095 -29.100018)
		(end 177.749962 -29.100018)
		(width 0.127)
		(layer "F.Cu")
		(net "ZDEF_EXTA_TP_D2")
	)
	(segment
		(start 176.9999 -35.9029)
		(end 176.9999 -30.500066)
		(width 0.127)
		(layer "F.Cu")
		(net "ZDEF_EXTA_TP_D1")
	)
	(segment
		(start 179.1462 -39.3954)
		(end 179.1462 -38.0492)
		(width 0.127)
		(layer "F.Cu")
		(net "ZDEF_EXTA_TP_D1")
	)
	(segment
		(start 179.1462 -38.0492)
		(end 176.9999 -35.9029)
		(width 0.127)
		(layer "F.Cu")
		(net "ZDEF_EXTA_TP_D1")
	)
	(segment
		(start 176.42078 -25.299924)
		(end 177.749962 -25.299924)
		(width 0.127)
		(layer "F.Cu")
		(net "ZDEF_EXTA_TP_C2")
	)
	(segment
		(start 176.1236 -38.5318)
		(end 176.1236 -38.0238)
		(width 0.127)
		(layer "F.Cu")
		(net "ZDEF_EXTA_TP_C2")
	)
	(segment
		(start 176.1236 -38.0238)
		(end 175.202342 -37.102542)
		(width 0.127)
		(layer "F.Cu")
		(net "ZDEF_EXTA_TP_C2")
	)
	(segment
		(start 175.202342 -37.102542)
		(end 175.202342 -26.518362)
		(width 0.127)
		(layer "F.Cu")
		(net "ZDEF_EXTA_TP_C2")
	)
	(segment
		(start 175.202342 -26.518362)
		(end 176.42078 -25.299924)
		(width 0.127)
		(layer "F.Cu")
		(net "ZDEF_EXTA_TP_C2")
	)
	(segment
		(start 175.804322 -27.89555)
		(end 176.9999 -26.699972)
		(width 0.127)
		(layer "F.Cu")
		(net "ZDEF_EXTA_TP_C1")
	)
	(segment
		(start 175.804322 -36.840922)
		(end 175.804322 -27.89555)
		(width 0.127)
		(layer "F.Cu")
		(net "ZDEF_EXTA_TP_C1")
	)
	(segment
		(start 177.1396 -39.497)
		(end 177.1396 -38.1762)
		(width 0.127)
		(layer "F.Cu")
		(net "ZDEF_EXTA_TP_C1")
	)
	(segment
		(start 177.1396 -38.1762)
		(end 175.804322 -36.840922)
		(width 0.127)
		(layer "F.Cu")
		(net "ZDEF_EXTA_TP_C1")
	)
	(segment
		(start 173.886876 -38.200076)
		(end 174.1424 -38.4556)
		(width 0.127)
		(layer "F.Cu")
		(net "ZDEF_EXTA_TP_B2")
	)
	(segment
		(start 177.749962 -21.500084)
		(end 176.296574 -21.500084)
		(width 0.127)
		(layer "F.Cu")
		(net "ZDEF_EXTA_TP_B2")
	)
	(segment
		(start 176.296574 -21.500084)
		(end 173.886876 -23.909782)
		(width 0.127)
		(layer "F.Cu")
		(net "ZDEF_EXTA_TP_B2")
	)
	(segment
		(start 173.886876 -23.909782)
		(end 173.886876 -38.200076)
		(width 0.127)
		(layer "F.Cu")
		(net "ZDEF_EXTA_TP_B2")
	)
	(segment
		(start 175.1076 -37.846)
		(end 174.555658 -37.294058)
		(width 0.127)
		(layer "F.Cu")
		(net "ZDEF_EXTA_TP_B1")
	)
	(segment
		(start 174.555658 -25.34412)
		(end 176.9999 -22.899878)
		(width 0.127)
		(layer "F.Cu")
		(net "ZDEF_EXTA_TP_B1")
	)
	(segment
		(start 174.555658 -37.294058)
		(end 174.555658 -25.34412)
		(width 0.127)
		(layer "F.Cu")
		(net "ZDEF_EXTA_TP_B1")
	)
	(segment
		(start 175.1076 -39.497)
		(end 175.1076 -37.846)
		(width 0.127)
		(layer "F.Cu")
		(net "ZDEF_EXTA_TP_B1")
	)
	(segment
		(start 177.6095 -17.69999)
		(end 177.749962 -17.69999)
		(width 0.127)
		(layer "F.Cu")
		(net "ZDEF_EXTA_TP_A2")
	)
	(segment
		(start 172.2374 -23.07209)
		(end 177.6095 -17.69999)
		(width 0.127)
		(layer "F.Cu")
		(net "ZDEF_EXTA_TP_A2")
	)
	(segment
		(start 172.2374 -38.481)
		(end 172.2374 -23.07209)
		(width 0.127)
		(layer "F.Cu")
		(net "ZDEF_EXTA_TP_A2")
	)
	(segment
		(start 173.151038 -22.9489)
		(end 173.151038 -39.521638)
		(width 0.127)
		(layer "F.Cu")
		(net "ZDEF_EXTA_TP_A1")
	)
	(segment
		(start 176.9999 -19.100038)
		(end 173.151038 -22.9489)
		(width 0.127)
		(layer "F.Cu")
		(net "ZDEF_EXTA_TP_A1")
	)
	(segment
		(start 173.151038 -39.521638)
		(end 173.1518 -39.5224)
		(width 0.127)
		(layer "F.Cu")
		(net "ZDEF_EXTA_TP_A1")
	)
	(segment
		(start 185.200036 -53.102764)
		(end 185.200036 -53.50002)
		(width 0.127)
		(layer "F.Cu")
		(net "XM_WP")
	)
	(segment
		(start 185.3692 -52.9336)
		(end 185.200036 -53.102764)
		(width 0.127)
		(layer "F.Cu")
		(net "XM_WP")
	)
	(via
		(at 185.3692 -52.9336)
		(size 0.508)
		(drill 0.254)
		(layers "F.Cu" "B.Cu")
		(net "XM_WP")
	)
	(segment
		(start 185.0009 -53.3019)
		(end 185.3692 -52.9336)
		(width 0.127)
		(layer "B.Cu")
		(net "XM_WP")
	)
	(segment
		(start 183.69534 -53.3019)
		(end 185.0009 -53.3019)
		(width 0.127)
		(layer "B.Cu")
		(net "XM_WP")
	)
	(segment
		(start 185.999882 -53.50002)
		(end 186.400186 -53.900324)
		(width 0.127)
		(layer "F.Cu")
		(net "XM_WE_N")
	)
	(via
		(at 163.9316 -67.0687)
		(size 0.508)
		(drill 0.254)
		(layers "F.Cu" "B.Cu")
		(net "XM_WE_N")
	)
	(via
		(at 186.400186 -53.900324)
		(size 0.508)
		(drill 0.254)
		(layers "F.Cu" "B.Cu")
		(net "XM_WE_N")
	)
	(via
		(at 165.72611 -74.86269)
		(size 0.6096)
		(drill 0.3048)
		(layers "F.Cu" "B.Cu")
		(net "XM_WE_N")
	)
	(segment
		(start 165.72611 -74.86269)
		(end 165.72611 -75.823064)
		(width 0.127)
		(layer "B.Cu")
		(net "XM_WE_N")
	)
	(segment
		(start 164.846 -67.0687)
		(end 165.3159 -67.5386)
		(width 0.127)
		(layer "B.Cu")
		(net "XM_WE_N")
	)
	(segment
		(start 163.99383 -71.12762)
		(end 163.99383 -72.8853)
		(width 0.127)
		(layer "B.Cu")
		(net "XM_WE_N")
	)
	(segment
		(start 165.72611 -74.71537)
		(end 165.72611 -74.86269)
		(width 0.127)
		(layer "B.Cu")
		(net "XM_WE_N")
	)
	(segment
		(start 165.3159 -69.80555)
		(end 163.99383 -71.12762)
		(width 0.127)
		(layer "B.Cu")
		(net "XM_WE_N")
	)
	(segment
		(start 164.92474 -73.914)
		(end 165.72611 -74.71537)
		(width 0.127)
		(layer "B.Cu")
		(net "XM_WE_N")
	)
	(segment
		(start 163.99383 -73.73112)
		(end 164.17671 -73.914)
		(width 0.127)
		(layer "B.Cu")
		(net "XM_WE_N")
	)
	(segment
		(start 163.9316 -67.0687)
		(end 164.846 -67.0687)
		(width 0.127)
		(layer "B.Cu")
		(net "XM_WE_N")
	)
	(segment
		(start 164.17671 -73.914)
		(end 164.92474 -73.914)
		(width 0.127)
		(layer "B.Cu")
		(net "XM_WE_N")
	)
	(segment
		(start 163.99383 -72.8853)
		(end 163.99383 -73.73112)
		(width 0.127)
		(layer "B.Cu")
		(net "XM_WE_N")
	)
	(segment
		(start 165.3159 -67.5386)
		(end 165.3159 -69.80555)
		(width 0.127)
		(layer "B.Cu")
		(net "XM_WE_N")
	)
	(segment
		(start 176.45888 -53.7972)
		(end 176.7713 -53.7972)
		(width 0.127)
		(layer "In2.Cu")
		(net "XM_WE_N")
	)
	(segment
		(start 164.410136 -53.69052)
		(end 164.972238 -54.252622)
		(width 0.127)
		(layer "In2.Cu")
		(net "XM_WE_N")
	)
	(segment
		(start 163.9316 -67.0687)
		(end 163.9316 -66.149982)
		(width 0.127)
		(layer "In2.Cu")
		(net "XM_WE_N")
	)
	(segment
		(start 158.790386 -63.34252)
		(end 158.4198 -62.971934)
		(width 0.127)
		(layer "In2.Cu")
		(net "XM_WE_N")
	)
	(segment
		(start 159.180022 -63.34252)
		(end 158.790386 -63.34252)
		(width 0.127)
		(layer "In2.Cu")
		(net "XM_WE_N")
	)
	(segment
		(start 159.530542 -62.992)
		(end 159.180022 -63.34252)
		(width 0.127)
		(layer "In2.Cu")
		(net "XM_WE_N")
	)
	(segment
		(start 160.773618 -62.992)
		(end 159.530542 -62.992)
		(width 0.127)
		(layer "In2.Cu")
		(net "XM_WE_N")
	)
	(segment
		(start 176.003458 -54.252622)
		(end 176.45888 -53.7972)
		(width 0.127)
		(layer "In2.Cu")
		(net "XM_WE_N")
	)
	(segment
		(start 163.9316 -66.149982)
		(end 160.773618 -62.992)
		(width 0.127)
		(layer "In2.Cu")
		(net "XM_WE_N")
	)
	(segment
		(start 158.4198 -62.971934)
		(end 158.4198 -55.977282)
		(width 0.127)
		(layer "In2.Cu")
		(net "XM_WE_N")
	)
	(segment
		(start 158.4198 -55.977282)
		(end 160.706562 -53.69052)
		(width 0.127)
		(layer "In2.Cu")
		(net "XM_WE_N")
	)
	(segment
		(start 164.972238 -54.252622)
		(end 176.003458 -54.252622)
		(width 0.127)
		(layer "In2.Cu")
		(net "XM_WE_N")
	)
	(segment
		(start 180.627782 -53.900324)
		(end 186.400186 -53.900324)
		(width 0.127)
		(layer "In2.Cu")
		(net "XM_WE_N")
	)
	(segment
		(start 177.1015 -53.467)
		(end 180.194458 -53.467)
		(width 0.127)
		(layer "In2.Cu")
		(net "XM_WE_N")
	)
	(segment
		(start 160.706562 -53.69052)
		(end 164.410136 -53.69052)
		(width 0.127)
		(layer "In2.Cu")
		(net "XM_WE_N")
	)
	(segment
		(start 176.7713 -53.7972)
		(end 177.1015 -53.467)
		(width 0.127)
		(layer "In2.Cu")
		(net "XM_WE_N")
	)
	(segment
		(start 180.194458 -53.467)
		(end 180.627782 -53.900324)
		(width 0.127)
		(layer "In2.Cu")
		(net "XM_WE_N")
	)
	(segment
		(start 186.817 -49.9872)
		(end 186.817 -50.70856)
		(width 0.127)
		(layer "F.Cu")
		(net "XM_RB")
	)
	(segment
		(start 187.600082 -51.491642)
		(end 187.600082 -53.50002)
		(width 0.127)
		(layer "F.Cu")
		(net "XM_RB")
	)
	(segment
		(start 186.817 -50.70856)
		(end 187.600082 -51.491642)
		(width 0.127)
		(layer "F.Cu")
		(net "XM_RB")
	)
	(segment
		(start 186.817 -49.9872)
		(end 186.817 -49.7713)
		(width 0.127)
		(layer "F.Cu")
		(net "XM_RB")
	)
	(segment
		(start 186.817 -49.7713)
		(end 185.928 -48.8823)
		(width 0.127)
		(layer "F.Cu")
		(net "XM_RB")
	)
	(segment
		(start 177.6984 -51.70424)
		(end 178.55692 -51.70424)
		(width 0.127)
		(layer "F.Cu")
		(net "XM_OE_N")
	)
	(segment
		(start 187.215018 -52.887118)
		(end 187.215018 -53.914802)
		(width 0.127)
		(layer "F.Cu")
		(net "XM_OE_N")
	)
	(segment
		(start 187.215018 -53.914802)
		(end 187.600082 -54.299866)
		(width 0.127)
		(layer "F.Cu")
		(net "XM_OE_N")
	)
	(segment
		(start 178.55692 -51.70424)
		(end 178.64328 -51.7906)
		(width 0.127)
		(layer "F.Cu")
		(net "XM_OE_N")
	)
	(segment
		(start 186.223148 -51.895248)
		(end 187.215018 -52.887118)
		(width 0.127)
		(layer "F.Cu")
		(net "XM_OE_N")
	)
	(segment
		(start 185.995056 -51.895248)
		(end 186.223148 -51.895248)
		(width 0.127)
		(layer "F.Cu")
		(net "XM_OE_N")
	)
	(via
		(at 178.64328 -51.7906)
		(size 0.508)
		(drill 0.254)
		(layers "F.Cu" "B.Cu")
		(net "XM_OE_N")
	)
	(via
		(at 168.3766 -52.1462)
		(size 0.508)
		(drill 0.254)
		(layers "F.Cu" "B.Cu")
		(net "XM_OE_N")
	)
	(via
		(at 185.995056 -51.895248)
		(size 0.508)
		(drill 0.254)
		(layers "F.Cu" "B.Cu")
		(net "XM_OE_N")
	)
	(segment
		(start 168.99382 -52.76342)
		(end 168.99382 -53.6575)
		(width 0.127)
		(layer "B.Cu")
		(net "XM_OE_N")
	)
	(segment
		(start 168.3766 -52.1462)
		(end 168.99382 -52.76342)
		(width 0.127)
		(layer "B.Cu")
		(net "XM_OE_N")
	)
	(segment
		(start 171.297346 -50.9905)
		(end 169.5958 -52.6923)
		(width 0.127)
		(layer "In2.Cu")
		(net "XM_OE_N")
	)
	(segment
		(start 183.9468 -52.1716)
		(end 179.9336 -52.1716)
		(width 0.127)
		(layer "In2.Cu")
		(net "XM_OE_N")
	)
	(segment
		(start 179.9336 -52.1716)
		(end 179.5526 -51.7906)
		(width 0.127)
		(layer "In2.Cu")
		(net "XM_OE_N")
	)
	(segment
		(start 185.994548 -51.895756)
		(end 185.994548 -51.914298)
		(width 0.127)
		(layer "In2.Cu")
		(net "XM_OE_N")
	)
	(segment
		(start 172.62856 -50.9905)
		(end 171.297346 -50.9905)
		(width 0.127)
		(layer "In2.Cu")
		(net "XM_OE_N")
	)
	(segment
		(start 177.30978 -50.4571)
		(end 173.16196 -50.4571)
		(width 0.127)
		(layer "In2.Cu")
		(net "XM_OE_N")
	)
	(segment
		(start 168.9227 -52.6923)
		(end 168.3766 -52.1462)
		(width 0.127)
		(layer "In2.Cu")
		(net "XM_OE_N")
	)
	(segment
		(start 185.994548 -51.914298)
		(end 185.432446 -52.4764)
		(width 0.127)
		(layer "In2.Cu")
		(net "XM_OE_N")
	)
	(segment
		(start 178.64328 -51.7906)
		(end 177.30978 -50.4571)
		(width 0.127)
		(layer "In2.Cu")
		(net "XM_OE_N")
	)
	(segment
		(start 185.995056 -51.895248)
		(end 185.994548 -51.895756)
		(width 0.127)
		(layer "In2.Cu")
		(net "XM_OE_N")
	)
	(segment
		(start 184.2516 -52.4764)
		(end 183.9468 -52.1716)
		(width 0.127)
		(layer "In2.Cu")
		(net "XM_OE_N")
	)
	(segment
		(start 185.432446 -52.4764)
		(end 184.2516 -52.4764)
		(width 0.127)
		(layer "In2.Cu")
		(net "XM_OE_N")
	)
	(segment
		(start 173.16196 -50.4571)
		(end 172.62856 -50.9905)
		(width 0.127)
		(layer "In2.Cu")
		(net "XM_OE_N")
	)
	(segment
		(start 179.5526 -51.7906)
		(end 178.64328 -51.7906)
		(width 0.127)
		(layer "In2.Cu")
		(net "XM_OE_N")
	)
	(segment
		(start 169.5958 -52.6923)
		(end 168.9227 -52.6923)
		(width 0.127)
		(layer "In2.Cu")
		(net "XM_OE_N")
	)
	(segment
		(start 188.792358 -52.407312)
		(end 188.792358 -53.10759)
		(width 0.127)
		(layer "F.Cu")
		(net "XM_NOR_CS_N")
	)
	(segment
		(start 188.724032 -52.338986)
		(end 188.792358 -52.407312)
		(width 0.127)
		(layer "F.Cu")
		(net "XM_NOR_CS_N")
	)
	(segment
		(start 188.792358 -53.10759)
		(end 188.399928 -53.50002)
		(width 0.127)
		(layer "F.Cu")
		(net "XM_NOR_CS_N")
	)
	(via
		(at 188.724032 -52.338986)
		(size 0.508)
		(drill 0.254)
		(layers "F.Cu" "B.Cu")
		(net "XM_NOR_CS_N")
	)
	(via
		(at 169.037 -51.2826)
		(size 0.6604)
		(drill 0.254)
		(layers "F.Cu" "B.Cu")
		(net "XM_NOR_CS_N")
	)
	(segment
		(start 170.2308 -51.6509)
		(end 170.13174 -51.6509)
		(width 0.127)
		(layer "B.Cu")
		(net "XM_NOR_CS_N")
	)
	(segment
		(start 169.99458 -52.385214)
		(end 169.99458 -53.6575)
		(width 0.127)
		(layer "B.Cu")
		(net "XM_NOR_CS_N")
	)
	(segment
		(start 170.2308 -51.6509)
		(end 170.2308 -52.148994)
		(width 0.127)
		(layer "B.Cu")
		(net "XM_NOR_CS_N")
	)
	(segment
		(start 170.2308 -52.148994)
		(end 169.99458 -52.385214)
		(width 0.127)
		(layer "B.Cu")
		(net "XM_NOR_CS_N")
	)
	(segment
		(start 169.76344 -51.2826)
		(end 169.037 -51.2826)
		(width 0.127)
		(layer "B.Cu")
		(net "XM_NOR_CS_N")
	)
	(segment
		(start 170.13174 -51.6509)
		(end 169.76344 -51.2826)
		(width 0.127)
		(layer "B.Cu")
		(net "XM_NOR_CS_N")
	)
	(segment
		(start 169.037 -51.2826)
		(end 170.9928 -49.3268)
		(width 0.127)
		(layer "In2.Cu")
		(net "XM_NOR_CS_N")
	)
	(segment
		(start 188.206126 -52.338986)
		(end 188.724032 -52.338986)
		(width 0.127)
		(layer "In2.Cu")
		(net "XM_NOR_CS_N")
	)
	(segment
		(start 170.9928 -49.3268)
		(end 185.19394 -49.3268)
		(width 0.127)
		(layer "In2.Cu")
		(net "XM_NOR_CS_N")
	)
	(segment
		(start 185.19394 -49.3268)
		(end 188.206126 -52.338986)
		(width 0.127)
		(layer "In2.Cu")
		(net "XM_NOR_CS_N")
	)
	(segment
		(start 187.999116 -53.191156)
		(end 187.999116 -53.899054)
		(width 0.127)
		(layer "F.Cu")
		(net "XM_NAND_CS_N")
	)
	(segment
		(start 188.288676 -52.901596)
		(end 187.999116 -53.191156)
		(width 0.127)
		(layer "F.Cu")
		(net "XM_NAND_CS_N")
	)
	(segment
		(start 187.999116 -53.899054)
		(end 188.399928 -54.299866)
		(width 0.127)
		(layer "F.Cu")
		(net "XM_NAND_CS_N")
	)
	(via
		(at 189.098428 -51.33594)
		(size 0.6096)
		(drill 0.3048)
		(layers "F.Cu" "B.Cu")
		(net "XM_NAND_CS_N")
	)
	(via
		(at 188.288676 -52.901596)
		(size 0.508)
		(drill 0.254)
		(layers "F.Cu" "B.Cu")
		(net "XM_NAND_CS_N")
	)
	(segment
		(start 188.260482 -52.873402)
		(end 188.260482 -51.607466)
		(width 0.127)
		(layer "B.Cu")
		(net "XM_NAND_CS_N")
	)
	(segment
		(start 188.260482 -51.607466)
		(end 188.532008 -51.33594)
		(width 0.127)
		(layer "B.Cu")
		(net "XM_NAND_CS_N")
	)
	(segment
		(start 188.532008 -51.33594)
		(end 189.098428 -51.33594)
		(width 0.127)
		(layer "B.Cu")
		(net "XM_NAND_CS_N")
	)
	(segment
		(start 188.288676 -52.901596)
		(end 188.260482 -52.873402)
		(width 0.127)
		(layer "B.Cu")
		(net "XM_NAND_CS_N")
	)
	(segment
		(start 189.3951 -52.959)
		(end 189.3951 -51.632612)
		(width 0.127)
		(layer "B.Cu")
		(net "XM_NAND_CS_N")
	)
	(segment
		(start 189.3951 -51.632612)
		(end 189.098428 -51.33594)
		(width 0.127)
		(layer "B.Cu")
		(net "XM_NAND_CS_N")
	)
	(segment
		(start 188.792866 -53.897784)
		(end 189.194948 -54.299866)
		(width 0.127)
		(layer "F.Cu")
		(net "XM_F_RST_N")
	)
	(segment
		(start 189.194948 -54.299866)
		(end 189.200028 -54.299866)
		(width 0.127)
		(layer "F.Cu")
		(net "XM_F_RST_N")
	)
	(via
		(at 164.592 -71.4502)
		(size 0.6604)
		(drill 0.254)
		(layers "F.Cu" "B.Cu")
		(net "XM_F_RST_N")
	)
	(via
		(at 188.792866 -53.897784)
		(size 0.508)
		(drill 0.254)
		(layers "F.Cu" "B.Cu")
		(net "XM_F_RST_N")
	)
	(segment
		(start 164.49421 -71.54799)
		(end 164.49421 -72.8853)
		(width 0.127)
		(layer "B.Cu")
		(net "XM_F_RST_N")
	)
	(segment
		(start 164.592 -71.4502)
		(end 164.49421 -71.54799)
		(width 0.127)
		(layer "B.Cu")
		(net "XM_F_RST_N")
	)
	(segment
		(start 167.177212 -73.698354)
		(end 166.756588 -73.698354)
		(width 0.127)
		(layer "In5.Cu")
		(net "XM_F_RST_N")
	)
	(segment
		(start 181.5592 -62.730126)
		(end 181.5592 -65.925446)
		(width 0.127)
		(layer "In5.Cu")
		(net "XM_F_RST_N")
	)
	(segment
		(start 181.99354 -62.295786)
		(end 181.5592 -62.730126)
		(width 0.127)
		(layer "In5.Cu")
		(net "XM_F_RST_N")
	)
	(segment
		(start 177.262028 -69.634354)
		(end 175.115982 -71.7804)
		(width 0.127)
		(layer "In5.Cu")
		(net "XM_F_RST_N")
	)
	(segment
		(start 170.020234 -74.2569)
		(end 169.461434 -73.6981)
		(width 0.127)
		(layer "In5.Cu")
		(net "XM_F_RST_N")
	)
	(segment
		(start 165.167056 -72.108822)
		(end 165.167056 -72.025256)
		(width 0.127)
		(layer "In5.Cu")
		(net "XM_F_RST_N")
	)
	(segment
		(start 182.79999 -54.38775)
		(end 182.800244 -54.388004)
		(width 0.0889)
		(layer "In5.Cu")
		(net "XM_F_RST_N")
	)
	(segment
		(start 182.79999 -59.66587)
		(end 182.800244 -59.666124)
		(width 0.0889)
		(layer "In5.Cu")
		(net "XM_F_RST_N")
	)
	(segment
		(start 169.461434 -73.6981)
		(end 167.177466 -73.6981)
		(width 0.127)
		(layer "In5.Cu")
		(net "XM_F_RST_N")
	)
	(segment
		(start 182.800244 -59.666124)
		(end 182.800244 -62.05601)
		(width 0.0889)
		(layer "In5.Cu")
		(net "XM_F_RST_N")
	)
	(segment
		(start 165.167056 -72.025256)
		(end 164.592 -71.4502)
		(width 0.127)
		(layer "In5.Cu")
		(net "XM_F_RST_N")
	)
	(segment
		(start 183.706516 -53.481224)
		(end 182.79999 -54.38775)
		(width 0.127)
		(layer "In5.Cu")
		(net "XM_F_RST_N")
	)
	(segment
		(start 182.560468 -62.295786)
		(end 181.99354 -62.295786)
		(width 0.0889)
		(layer "In5.Cu")
		(net "XM_F_RST_N")
	)
	(segment
		(start 182.800244 -59.333892)
		(end 182.79999 -59.334146)
		(width 0.0889)
		(layer "In5.Cu")
		(net "XM_F_RST_N")
	)
	(segment
		(start 175.115982 -71.7804)
		(end 175.115982 -72.579484)
		(width 0.127)
		(layer "In5.Cu")
		(net "XM_F_RST_N")
	)
	(segment
		(start 173.438566 -74.2569)
		(end 170.020234 -74.2569)
		(width 0.127)
		(layer "In5.Cu")
		(net "XM_F_RST_N")
	)
	(segment
		(start 177.850292 -69.634354)
		(end 177.262028 -69.634354)
		(width 0.127)
		(layer "In5.Cu")
		(net "XM_F_RST_N")
	)
	(segment
		(start 182.800244 -54.388004)
		(end 182.800244 -59.333892)
		(width 0.0889)
		(layer "In5.Cu")
		(net "XM_F_RST_N")
	)
	(segment
		(start 181.5592 -65.925446)
		(end 177.850292 -69.634354)
		(width 0.127)
		(layer "In5.Cu")
		(net "XM_F_RST_N")
	)
	(segment
		(start 188.792866 -53.897784)
		(end 187.828682 -53.897784)
		(width 0.127)
		(layer "In5.Cu")
		(net "XM_F_RST_N")
	)
	(segment
		(start 175.115982 -72.579484)
		(end 173.438566 -74.2569)
		(width 0.127)
		(layer "In5.Cu")
		(net "XM_F_RST_N")
	)
	(segment
		(start 167.177466 -73.6981)
		(end 167.177212 -73.698354)
		(width 0.127)
		(layer "In5.Cu")
		(net "XM_F_RST_N")
	)
	(segment
		(start 187.412122 -53.481224)
		(end 183.706516 -53.481224)
		(width 0.127)
		(layer "In5.Cu")
		(net "XM_F_RST_N")
	)
	(segment
		(start 166.756588 -73.698354)
		(end 165.167056 -72.108822)
		(width 0.127)
		(layer "In5.Cu")
		(net "XM_F_RST_N")
	)
	(segment
		(start 182.800244 -62.05601)
		(end 182.560468 -62.295786)
		(width 0.0889)
		(layer "In5.Cu")
		(net "XM_F_RST_N")
	)
	(segment
		(start 182.79999 -59.334146)
		(end 182.79999 -59.66587)
		(width 0.0889)
		(layer "In5.Cu")
		(net "XM_F_RST_N")
	)
	(segment
		(start 187.828682 -53.897784)
		(end 187.412122 -53.481224)
		(width 0.127)
		(layer "In5.Cu")
		(net "XM_F_RST_N")
	)
	(segment
		(start 184.399936 -55.099966)
		(end 184.00014 -54.70017)
		(width 0.127)
		(layer "F.Cu")
		(net "XM_DATA_9")
	)
	(via
		(at 184.00014 -54.70017)
		(size 0.508)
		(drill 0.254)
		(layers "F.Cu" "B.Cu")
		(net "XM_DATA_9")
	)
	(segment
		(start 170.26255 -49.34458)
		(end 172.39488 -49.34458)
		(width 0.127)
		(layer "B.Cu")
		(net "XM_DATA_9")
	)
	(segment
		(start 178.344576 -54.7624)
		(end 178.344576 -55.1815)
		(width 0.127)
		(layer "B.Cu")
		(net "XM_DATA_9")
	)
	(segment
		(start 182.93461 -54.3941)
		(end 183.18861 -54.3941)
		(width 0.127)
		(layer "B.Cu")
		(net "XM_DATA_9")
	)
	(segment
		(start 177.836576 -54.7624)
		(end 177.963576 -54.6354)
		(width 0.127)
		(layer "B.Cu")
		(net "XM_DATA_9")
	)
	(segment
		(start 178.217576 -54.6354)
		(end 178.344576 -54.7624)
		(width 0.127)
		(layer "B.Cu")
		(net "XM_DATA_9")
	)
	(segment
		(start 176.186338 -54.73827)
		(end 175.99152 -54.933088)
		(width 0.127)
		(layer "B.Cu")
		(net "XM_DATA_9")
	)
	(segment
		(start 176.186338 -54.558438)
		(end 176.186338 -54.73827)
		(width 0.127)
		(layer "B.Cu")
		(net "XM_DATA_9")
	)
	(segment
		(start 183.31561 -54.5211)
		(end 183.31561 -55.1815)
		(width 0.127)
		(layer "B.Cu")
		(net "XM_DATA_9")
	)
	(segment
		(start 175.99152 -54.933088)
		(end 175.99152 -55.11292)
		(width 0.127)
		(layer "B.Cu")
		(net "XM_DATA_9")
	)
	(segment
		(start 174.921418 -51.88585)
		(end 173.93285 -52.874418)
		(width 0.127)
		(layer "B.Cu")
		(net "XM_DATA_9")
	)
	(segment
		(start 167.231568 -51.61534)
		(end 167.99179 -51.61534)
		(width 0.127)
		(layer "B.Cu")
		(net "XM_DATA_9")
	)
	(segment
		(start 178.852576 -55.1815)
		(end 178.852576 -54.7624)
		(width 0.127)
		(layer "B.Cu")
		(net "XM_DATA_9")
	)
	(segment
		(start 167.99179 -51.61534)
		(end 170.26255 -49.34458)
		(width 0.127)
		(layer "B.Cu")
		(net "XM_DATA_9")
	)
	(segment
		(start 183.44261 -55.3085)
		(end 183.872886 -55.3085)
		(width 0.127)
		(layer "B.Cu")
		(net "XM_DATA_9")
	)
	(segment
		(start 180.77561 -54.5211)
		(end 180.90261 -54.3941)
		(width 0.127)
		(layer "B.Cu")
		(net "XM_DATA_9")
	)
	(segment
		(start 172.7454 -51.8668)
		(end 173.393608 -52.515008)
		(width 0.127)
		(layer "B.Cu")
		(net "XM_DATA_9")
	)
	(segment
		(start 182.29961 -55.1815)
		(end 182.42661 -55.3085)
		(width 0.127)
		(layer "B.Cu")
		(net "XM_DATA_9")
	)
	(segment
		(start 178.725576 -55.3085)
		(end 178.852576 -55.1815)
		(width 0.127)
		(layer "B.Cu")
		(net "XM_DATA_9")
	)
	(segment
		(start 181.28361 -54.5211)
		(end 181.28361 -55.1815)
		(width 0.127)
		(layer "B.Cu")
		(net "XM_DATA_9")
	)
	(segment
		(start 174.92726 -52.77866)
		(end 175.106838 -52.958238)
		(width 0.127)
		(layer "B.Cu")
		(net "XM_DATA_9")
	)
	(segment
		(start 172.39488 -49.34458)
		(end 172.7454 -49.6951)
		(width 0.127)
		(layer "B.Cu")
		(net "XM_DATA_9")
	)
	(segment
		(start 184.00014 -55.181246)
		(end 184.00014 -54.70017)
		(width 0.127)
		(layer "B.Cu")
		(net "XM_DATA_9")
	)
	(segment
		(start 172.7454 -49.6951)
		(end 172.7454 -51.8668)
		(width 0.127)
		(layer "B.Cu")
		(net "XM_DATA_9")
	)
	(segment
		(start 179.360576 -55.1815)
		(end 179.487576 -55.3085)
		(width 0.127)
		(layer "B.Cu")
		(net "XM_DATA_9")
	)
	(segment
		(start 174.747428 -52.77866)
		(end 174.92726 -52.77866)
		(width 0.127)
		(layer "B.Cu")
		(net "XM_DATA_9")
	)
	(segment
		(start 181.15661 -54.3941)
		(end 181.28361 -54.5211)
		(width 0.127)
		(layer "B.Cu")
		(net "XM_DATA_9")
	)
	(segment
		(start 180.77561 -55.1815)
		(end 180.77561 -54.5211)
		(width 0.127)
		(layer "B.Cu")
		(net "XM_DATA_9")
	)
	(segment
		(start 182.80761 -54.5211)
		(end 182.93461 -54.3941)
		(width 0.127)
		(layer "B.Cu")
		(net "XM_DATA_9")
	)
	(segment
		(start 181.66461 -55.3085)
		(end 181.79161 -55.1815)
		(width 0.127)
		(layer "B.Cu")
		(net "XM_DATA_9")
	)
	(segment
		(start 181.28361 -55.1815)
		(end 181.41061 -55.3085)
		(width 0.127)
		(layer "B.Cu")
		(net "XM_DATA_9")
	)
	(segment
		(start 178.471576 -55.3085)
		(end 178.725576 -55.3085)
		(width 0.127)
		(layer "B.Cu")
		(net "XM_DATA_9")
	)
	(segment
		(start 173.57344 -52.515008)
		(end 174.562008 -51.52644)
		(width 0.127)
		(layer "B.Cu")
		(net "XM_DATA_9")
	)
	(segment
		(start 176.1871 -55.3085)
		(end 177.709576 -55.3085)
		(width 0.127)
		(layer "B.Cu")
		(net "XM_DATA_9")
	)
	(segment
		(start 183.18861 -54.3941)
		(end 183.31561 -54.5211)
		(width 0.127)
		(layer "B.Cu")
		(net "XM_DATA_9")
	)
	(segment
		(start 183.872886 -55.3085)
		(end 184.00014 -55.181246)
		(width 0.127)
		(layer "B.Cu")
		(net "XM_DATA_9")
	)
	(segment
		(start 178.979576 -54.6354)
		(end 179.233576 -54.6354)
		(width 0.127)
		(layer "B.Cu")
		(net "XM_DATA_9")
	)
	(segment
		(start 175.106838 -53.13807)
		(end 174.65167 -53.593238)
		(width 0.127)
		(layer "B.Cu")
		(net "XM_DATA_9")
	)
	(segment
		(start 181.91861 -54.3941)
		(end 182.17261 -54.3941)
		(width 0.127)
		(layer "B.Cu")
		(net "XM_DATA_9")
	)
	(segment
		(start 175.63211 -54.573678)
		(end 175.826928 -54.37886)
		(width 0.127)
		(layer "B.Cu")
		(net "XM_DATA_9")
	)
	(segment
		(start 174.921418 -51.706018)
		(end 174.921418 -51.88585)
		(width 0.127)
		(layer "B.Cu")
		(net "XM_DATA_9")
	)
	(segment
		(start 174.29226 -53.233828)
		(end 174.747428 -52.77866)
		(width 0.127)
		(layer "B.Cu")
		(net "XM_DATA_9")
	)
	(segment
		(start 175.99152 -55.11292)
		(end 176.1871 -55.3085)
		(width 0.127)
		(layer "B.Cu")
		(net "XM_DATA_9")
	)
	(segment
		(start 175.826928 -54.37886)
		(end 176.00676 -54.37886)
		(width 0.127)
		(layer "B.Cu")
		(net "XM_DATA_9")
	)
	(segment
		(start 174.74184 -51.52644)
		(end 174.921418 -51.706018)
		(width 0.127)
		(layer "B.Cu")
		(net "XM_DATA_9")
	)
	(segment
		(start 178.344576 -55.1815)
		(end 178.471576 -55.3085)
		(width 0.127)
		(layer "B.Cu")
		(net "XM_DATA_9")
	)
	(segment
		(start 175.452278 -54.573678)
		(end 175.63211 -54.573678)
		(width 0.127)
		(layer "B.Cu")
		(net "XM_DATA_9")
	)
	(segment
		(start 176.00676 -54.37886)
		(end 176.186338 -54.558438)
		(width 0.127)
		(layer "B.Cu")
		(net "XM_DATA_9")
	)
	(segment
		(start 173.93285 -52.874418)
		(end 173.93285 -53.05425)
		(width 0.127)
		(layer "B.Cu")
		(net "XM_DATA_9")
	)
	(segment
		(start 178.852576 -54.7624)
		(end 178.979576 -54.6354)
		(width 0.127)
		(layer "B.Cu")
		(net "XM_DATA_9")
	)
	(segment
		(start 179.487576 -55.3085)
		(end 180.64861 -55.3085)
		(width 0.127)
		(layer "B.Cu")
		(net "XM_DATA_9")
	)
	(segment
		(start 173.393608 -52.515008)
		(end 173.57344 -52.515008)
		(width 0.127)
		(layer "B.Cu")
		(net "XM_DATA_9")
	)
	(segment
		(start 166.99484 -51.852068)
		(end 167.231568 -51.61534)
		(width 0.127)
		(layer "B.Cu")
		(net "XM_DATA_9")
	)
	(segment
		(start 179.360576 -54.7624)
		(end 179.360576 -55.1815)
		(width 0.127)
		(layer "B.Cu")
		(net "XM_DATA_9")
	)
	(segment
		(start 180.64861 -55.3085)
		(end 180.77561 -55.1815)
		(width 0.127)
		(layer "B.Cu")
		(net "XM_DATA_9")
	)
	(segment
		(start 181.79161 -54.5211)
		(end 181.91861 -54.3941)
		(width 0.127)
		(layer "B.Cu")
		(net "XM_DATA_9")
	)
	(segment
		(start 182.29961 -54.5211)
		(end 182.29961 -55.1815)
		(width 0.127)
		(layer "B.Cu")
		(net "XM_DATA_9")
	)
	(segment
		(start 183.31561 -55.1815)
		(end 183.44261 -55.3085)
		(width 0.127)
		(layer "B.Cu")
		(net "XM_DATA_9")
	)
	(segment
		(start 177.709576 -55.3085)
		(end 177.836576 -55.1815)
		(width 0.127)
		(layer "B.Cu")
		(net "XM_DATA_9")
	)
	(segment
		(start 174.562008 -51.52644)
		(end 174.74184 -51.52644)
		(width 0.127)
		(layer "B.Cu")
		(net "XM_DATA_9")
	)
	(segment
		(start 181.41061 -55.3085)
		(end 181.66461 -55.3085)
		(width 0.127)
		(layer "B.Cu")
		(net "XM_DATA_9")
	)
	(segment
		(start 177.836576 -55.1815)
		(end 177.836576 -54.7624)
		(width 0.127)
		(layer "B.Cu")
		(net "XM_DATA_9")
	)
	(segment
		(start 182.42661 -55.3085)
		(end 182.68061 -55.3085)
		(width 0.127)
		(layer "B.Cu")
		(net "XM_DATA_9")
	)
	(segment
		(start 180.90261 -54.3941)
		(end 181.15661 -54.3941)
		(width 0.127)
		(layer "B.Cu")
		(net "XM_DATA_9")
	)
	(segment
		(start 182.17261 -54.3941)
		(end 182.29961 -54.5211)
		(width 0.127)
		(layer "B.Cu")
		(net "XM_DATA_9")
	)
	(segment
		(start 174.112428 -53.233828)
		(end 174.29226 -53.233828)
		(width 0.127)
		(layer "B.Cu")
		(net "XM_DATA_9")
	)
	(segment
		(start 174.65167 -53.77307)
		(end 175.452278 -54.573678)
		(width 0.127)
		(layer "B.Cu")
		(net "XM_DATA_9")
	)
	(segment
		(start 182.80761 -55.1815)
		(end 182.80761 -54.5211)
		(width 0.127)
		(layer "B.Cu")
		(net "XM_DATA_9")
	)
	(segment
		(start 177.963576 -54.6354)
		(end 178.217576 -54.6354)
		(width 0.127)
		(layer "B.Cu")
		(net "XM_DATA_9")
	)
	(segment
		(start 175.106838 -52.958238)
		(end 175.106838 -53.13807)
		(width 0.127)
		(layer "B.Cu")
		(net "XM_DATA_9")
	)
	(segment
		(start 166.99484 -53.6575)
		(end 166.99484 -51.852068)
		(width 0.127)
		(layer "B.Cu")
		(net "XM_DATA_9")
	)
	(segment
		(start 182.68061 -55.3085)
		(end 182.80761 -55.1815)
		(width 0.127)
		(layer "B.Cu")
		(net "XM_DATA_9")
	)
	(segment
		(start 179.233576 -54.6354)
		(end 179.360576 -54.7624)
		(width 0.127)
		(layer "B.Cu")
		(net "XM_DATA_9")
	)
	(segment
		(start 174.65167 -53.593238)
		(end 174.65167 -53.77307)
		(width 0.127)
		(layer "B.Cu")
		(net "XM_DATA_9")
	)
	(segment
		(start 181.79161 -55.1815)
		(end 181.79161 -54.5211)
		(width 0.127)
		(layer "B.Cu")
		(net "XM_DATA_9")
	)
	(segment
		(start 173.93285 -53.05425)
		(end 174.112428 -53.233828)
		(width 0.127)
		(layer "B.Cu")
		(net "XM_DATA_9")
	)
	(segment
		(start 188.399928 -55.099966)
		(end 188.000132 -54.70017)
		(width 0.127)
		(layer "F.Cu")
		(net "XM_DATA_8")
	)
	(via
		(at 188.000132 -54.70017)
		(size 0.508)
		(drill 0.254)
		(layers "F.Cu" "B.Cu")
		(net "XM_DATA_8")
	)
	(via
		(at 167.513 -52.1462)
		(size 0.508)
		(drill 0.254)
		(layers "F.Cu" "B.Cu")
		(net "XM_DATA_8")
	)
	(segment
		(start 167.513 -52.1462)
		(end 167.99433 -52.62753)
		(width 0.127)
		(layer "B.Cu")
		(net "XM_DATA_8")
	)
	(segment
		(start 167.99433 -52.62753)
		(end 167.99433 -53.6575)
		(width 0.127)
		(layer "B.Cu")
		(net "XM_DATA_8")
	)
	(segment
		(start 172.385736 -51.7652)
		(end 172.258736 -51.6382)
		(width 0.127)
		(layer "In2.Cu")
		(net "XM_DATA_8")
	)
	(segment
		(start 180.0098 -52.959)
		(end 176.890934 -52.959)
		(width 0.127)
		(layer "In2.Cu")
		(net "XM_DATA_8")
	)
	(segment
		(start 173.782736 -53.2003)
		(end 173.528736 -53.2003)
		(width 0.127)
		(layer "In2.Cu")
		(net "XM_DATA_8")
	)
	(segment
		(start 188.000132 -54.70017)
		(end 186.781186 -53.481224)
		(width 0.127)
		(layer "In2.Cu")
		(net "XM_DATA_8")
	)
	(segment
		(start 171.750736 -53.2003)
		(end 171.496736 -53.2003)
		(width 0.127)
		(layer "In2.Cu")
		(net "XM_DATA_8")
	)
	(segment
		(start 173.055026 -51.2826)
		(end 172.893736 -51.44389)
		(width 0.127)
		(layer "In2.Cu")
		(net "XM_DATA_8")
	)
	(segment
		(start 171.369736 -53.0733)
		(end 171.369736 -52.2351)
		(width 0.127)
		(layer "In2.Cu")
		(net "XM_DATA_8")
	)
	(segment
		(start 174.417736 -53.0733)
		(end 174.417736 -51.0921)
		(width 0.127)
		(layer "In2.Cu")
		(net "XM_DATA_8")
	)
	(segment
		(start 171.242736 -52.1081)
		(end 170.988736 -52.1081)
		(width 0.127)
		(layer "In2.Cu")
		(net "XM_DATA_8")
	)
	(segment
		(start 173.401736 -53.0733)
		(end 173.401736 -51.40706)
		(width 0.127)
		(layer "In2.Cu")
		(net "XM_DATA_8")
	)
	(segment
		(start 186.781186 -53.481224)
		(end 180.532024 -53.481224)
		(width 0.127)
		(layer "In2.Cu")
		(net "XM_DATA_8")
	)
	(segment
		(start 180.532024 -53.481224)
		(end 180.0098 -52.959)
		(width 0.127)
		(layer "In2.Cu")
		(net "XM_DATA_8")
	)
	(segment
		(start 171.877736 -53.0733)
		(end 171.750736 -53.2003)
		(width 0.127)
		(layer "In2.Cu")
		(net "XM_DATA_8")
	)
	(segment
		(start 172.004736 -51.6382)
		(end 171.877736 -51.7652)
		(width 0.127)
		(layer "In2.Cu")
		(net "XM_DATA_8")
	)
	(segment
		(start 176.890934 -52.959)
		(end 176.649634 -53.2003)
		(width 0.127)
		(layer "In2.Cu")
		(net "XM_DATA_8")
	)
	(segment
		(start 172.893736 -51.44389)
		(end 172.893736 -53.0733)
		(width 0.127)
		(layer "In2.Cu")
		(net "XM_DATA_8")
	)
	(segment
		(start 174.417736 -51.0921)
		(end 174.290736 -50.9651)
		(width 0.127)
		(layer "In2.Cu")
		(net "XM_DATA_8")
	)
	(segment
		(start 170.861736 -52.2351)
		(end 170.861736 -53.0733)
		(width 0.127)
		(layer "In2.Cu")
		(net "XM_DATA_8")
	)
	(segment
		(start 171.496736 -53.2003)
		(end 171.369736 -53.0733)
		(width 0.127)
		(layer "In2.Cu")
		(net "XM_DATA_8")
	)
	(segment
		(start 172.258736 -51.6382)
		(end 172.004736 -51.6382)
		(width 0.127)
		(layer "In2.Cu")
		(net "XM_DATA_8")
	)
	(segment
		(start 174.544736 -53.2003)
		(end 174.417736 -53.0733)
		(width 0.127)
		(layer "In2.Cu")
		(net "XM_DATA_8")
	)
	(segment
		(start 173.909736 -51.0921)
		(end 173.909736 -53.0733)
		(width 0.127)
		(layer "In2.Cu")
		(net "XM_DATA_8")
	)
	(segment
		(start 174.290736 -50.9651)
		(end 174.036736 -50.9651)
		(width 0.127)
		(layer "In2.Cu")
		(net "XM_DATA_8")
	)
	(segment
		(start 173.277276 -51.2826)
		(end 173.055026 -51.2826)
		(width 0.127)
		(layer "In2.Cu")
		(net "XM_DATA_8")
	)
	(segment
		(start 173.528736 -53.2003)
		(end 173.401736 -53.0733)
		(width 0.127)
		(layer "In2.Cu")
		(net "XM_DATA_8")
	)
	(segment
		(start 172.766736 -53.2003)
		(end 172.512736 -53.2003)
		(width 0.127)
		(layer "In2.Cu")
		(net "XM_DATA_8")
	)
	(segment
		(start 168.5671 -53.2003)
		(end 167.513 -52.1462)
		(width 0.127)
		(layer "In2.Cu")
		(net "XM_DATA_8")
	)
	(segment
		(start 171.369736 -52.2351)
		(end 171.242736 -52.1081)
		(width 0.127)
		(layer "In2.Cu")
		(net "XM_DATA_8")
	)
	(segment
		(start 173.401736 -51.40706)
		(end 173.277276 -51.2826)
		(width 0.127)
		(layer "In2.Cu")
		(net "XM_DATA_8")
	)
	(segment
		(start 170.988736 -52.1081)
		(end 170.861736 -52.2351)
		(width 0.127)
		(layer "In2.Cu")
		(net "XM_DATA_8")
	)
	(segment
		(start 173.909736 -53.0733)
		(end 173.782736 -53.2003)
		(width 0.127)
		(layer "In2.Cu")
		(net "XM_DATA_8")
	)
	(segment
		(start 172.385736 -53.0733)
		(end 172.385736 -51.7652)
		(width 0.127)
		(layer "In2.Cu")
		(net "XM_DATA_8")
	)
	(segment
		(start 170.734736 -53.2003)
		(end 168.5671 -53.2003)
		(width 0.127)
		(layer "In2.Cu")
		(net "XM_DATA_8")
	)
	(segment
		(start 176.649634 -53.2003)
		(end 174.544736 -53.2003)
		(width 0.127)
		(layer "In2.Cu")
		(net "XM_DATA_8")
	)
	(segment
		(start 174.036736 -50.9651)
		(end 173.909736 -51.0921)
		(width 0.127)
		(layer "In2.Cu")
		(net "XM_DATA_8")
	)
	(segment
		(start 171.877736 -51.7652)
		(end 171.877736 -53.0733)
		(width 0.127)
		(layer "In2.Cu")
		(net "XM_DATA_8")
	)
	(segment
		(start 170.861736 -53.0733)
		(end 170.734736 -53.2003)
		(width 0.127)
		(layer "In2.Cu")
		(net "XM_DATA_8")
	)
	(segment
		(start 172.893736 -53.0733)
		(end 172.766736 -53.2003)
		(width 0.127)
		(layer "In2.Cu")
		(net "XM_DATA_8")
	)
	(segment
		(start 172.512736 -53.2003)
		(end 172.385736 -53.0733)
		(width 0.127)
		(layer "In2.Cu")
		(net "XM_DATA_8")
	)
	(segment
		(start 185.999882 -55.099966)
		(end 185.600086 -54.70017)
		(width 0.127)
		(layer "F.Cu")
		(net "XM_DATA_7")
	)
	(via
		(at 185.600086 -54.70017)
		(size 0.508)
		(drill 0.254)
		(layers "F.Cu" "B.Cu")
		(net "XM_DATA_7")
	)
	(via
		(at 160.805368 -55.243984)
		(size 0.508)
		(drill 0.254)
		(layers "F.Cu" "B.Cu")
		(net "XM_DATA_7")
	)
	(segment
		(start 160.99409 -55.055262)
		(end 160.99409 -53.6575)
		(width 0.127)
		(layer "B.Cu")
		(net "XM_DATA_7")
	)
	(segment
		(start 160.805368 -55.243984)
		(end 160.99409 -55.055262)
		(width 0.127)
		(layer "B.Cu")
		(net "XM_DATA_7")
	)
	(segment
		(start 178.497992 -55.1815)
		(end 178.624992 -55.3085)
		(width 0.127)
		(layer "In2.Cu")
		(net "XM_DATA_7")
	)
	(segment
		(start 177.989992 -55.1815)
		(end 177.989992 -54.6227)
		(width 0.127)
		(layer "In2.Cu")
		(net "XM_DATA_7")
	)
	(segment
		(start 180.785008 -55.1815)
		(end 180.785008 -54.4576)
		(width 0.127)
		(layer "In2.Cu")
		(net "XM_DATA_7")
	)
	(segment
		(start 178.116992 -54.4957)
		(end 178.370992 -54.4957)
		(width 0.127)
		(layer "In2.Cu")
		(net "XM_DATA_7")
	)
	(segment
		(start 181.801008 -55.1815)
		(end 181.801008 -54.4576)
		(width 0.127)
		(layer "In2.Cu")
		(net "XM_DATA_7")
	)
	(segment
		(start 160.805368 -55.243984)
		(end 161.850832 -54.19852)
		(width 0.127)
		(layer "In2.Cu")
		(net "XM_DATA_7")
	)
	(segment
		(start 182.817008 -55.1815)
		(end 182.817008 -54.4576)
		(width 0.127)
		(layer "In2.Cu")
		(net "XM_DATA_7")
	)
	(segment
		(start 182.182008 -54.3306)
		(end 182.309008 -54.4576)
		(width 0.127)
		(layer "In2.Cu")
		(net "XM_DATA_7")
	)
	(segment
		(start 178.370992 -54.4957)
		(end 178.497992 -54.6227)
		(width 0.127)
		(layer "In2.Cu")
		(net "XM_DATA_7")
	)
	(segment
		(start 178.497992 -54.6227)
		(end 178.497992 -55.1815)
		(width 0.127)
		(layer "In2.Cu")
		(net "XM_DATA_7")
	)
	(segment
		(start 182.309008 -55.1815)
		(end 182.436008 -55.3085)
		(width 0.127)
		(layer "In2.Cu")
		(net "XM_DATA_7")
	)
	(segment
		(start 179.005992 -55.1815)
		(end 179.005992 -54.6227)
		(width 0.127)
		(layer "In2.Cu")
		(net "XM_DATA_7")
	)
	(segment
		(start 161.850832 -54.19852)
		(end 163.576 -54.19852)
		(width 0.127)
		(layer "In2.Cu")
		(net "XM_DATA_7")
	)
	(segment
		(start 178.878992 -55.3085)
		(end 179.005992 -55.1815)
		(width 0.127)
		(layer "In2.Cu")
		(net "XM_DATA_7")
	)
	(segment
		(start 164.68598 -55.3085)
		(end 177.862992 -55.3085)
		(width 0.127)
		(layer "In2.Cu")
		(net "XM_DATA_7")
	)
	(segment
		(start 183.198008 -54.3306)
		(end 183.325008 -54.4576)
		(width 0.127)
		(layer "In2.Cu")
		(net "XM_DATA_7")
	)
	(segment
		(start 181.801008 -54.4576)
		(end 181.928008 -54.3306)
		(width 0.127)
		(layer "In2.Cu")
		(net "XM_DATA_7")
	)
	(segment
		(start 182.817008 -54.4576)
		(end 182.944008 -54.3306)
		(width 0.127)
		(layer "In2.Cu")
		(net "XM_DATA_7")
	)
	(segment
		(start 181.293008 -55.1815)
		(end 181.420008 -55.3085)
		(width 0.127)
		(layer "In2.Cu")
		(net "XM_DATA_7")
	)
	(segment
		(start 179.640992 -55.3085)
		(end 180.658008 -55.3085)
		(width 0.127)
		(layer "In2.Cu")
		(net "XM_DATA_7")
	)
	(segment
		(start 177.862992 -55.3085)
		(end 177.989992 -55.1815)
		(width 0.127)
		(layer "In2.Cu")
		(net "XM_DATA_7")
	)
	(segment
		(start 181.166008 -54.3306)
		(end 181.293008 -54.4576)
		(width 0.127)
		(layer "In2.Cu")
		(net "XM_DATA_7")
	)
	(segment
		(start 180.785008 -54.4576)
		(end 180.912008 -54.3306)
		(width 0.127)
		(layer "In2.Cu")
		(net "XM_DATA_7")
	)
	(segment
		(start 180.912008 -54.3306)
		(end 181.166008 -54.3306)
		(width 0.127)
		(layer "In2.Cu")
		(net "XM_DATA_7")
	)
	(segment
		(start 183.325008 -54.4576)
		(end 183.325008 -55.1815)
		(width 0.127)
		(layer "In2.Cu")
		(net "XM_DATA_7")
	)
	(segment
		(start 184.991756 -55.3085)
		(end 185.600086 -54.70017)
		(width 0.127)
		(layer "In2.Cu")
		(net "XM_DATA_7")
	)
	(segment
		(start 183.452008 -55.3085)
		(end 184.991756 -55.3085)
		(width 0.127)
		(layer "In2.Cu")
		(net "XM_DATA_7")
	)
	(segment
		(start 182.944008 -54.3306)
		(end 183.198008 -54.3306)
		(width 0.127)
		(layer "In2.Cu")
		(net "XM_DATA_7")
	)
	(segment
		(start 182.436008 -55.3085)
		(end 182.690008 -55.3085)
		(width 0.127)
		(layer "In2.Cu")
		(net "XM_DATA_7")
	)
	(segment
		(start 181.928008 -54.3306)
		(end 182.182008 -54.3306)
		(width 0.127)
		(layer "In2.Cu")
		(net "XM_DATA_7")
	)
	(segment
		(start 182.690008 -55.3085)
		(end 182.817008 -55.1815)
		(width 0.127)
		(layer "In2.Cu")
		(net "XM_DATA_7")
	)
	(segment
		(start 179.513992 -55.1815)
		(end 179.640992 -55.3085)
		(width 0.127)
		(layer "In2.Cu")
		(net "XM_DATA_7")
	)
	(segment
		(start 180.658008 -55.3085)
		(end 180.785008 -55.1815)
		(width 0.127)
		(layer "In2.Cu")
		(net "XM_DATA_7")
	)
	(segment
		(start 183.325008 -55.1815)
		(end 183.452008 -55.3085)
		(width 0.127)
		(layer "In2.Cu")
		(net "XM_DATA_7")
	)
	(segment
		(start 181.420008 -55.3085)
		(end 181.674008 -55.3085)
		(width 0.127)
		(layer "In2.Cu")
		(net "XM_DATA_7")
	)
	(segment
		(start 182.309008 -54.4576)
		(end 182.309008 -55.1815)
		(width 0.127)
		(layer "In2.Cu")
		(net "XM_DATA_7")
	)
	(segment
		(start 178.624992 -55.3085)
		(end 178.878992 -55.3085)
		(width 0.127)
		(layer "In2.Cu")
		(net "XM_DATA_7")
	)
	(segment
		(start 181.293008 -54.4576)
		(end 181.293008 -55.1815)
		(width 0.127)
		(layer "In2.Cu")
		(net "XM_DATA_7")
	)
	(segment
		(start 179.132992 -54.4957)
		(end 179.386992 -54.4957)
		(width 0.127)
		(layer "In2.Cu")
		(net "XM_DATA_7")
	)
	(segment
		(start 181.674008 -55.3085)
		(end 181.801008 -55.1815)
		(width 0.127)
		(layer "In2.Cu")
		(net "XM_DATA_7")
	)
	(segment
		(start 163.576 -54.19852)
		(end 164.68598 -55.3085)
		(width 0.127)
		(layer "In2.Cu")
		(net "XM_DATA_7")
	)
	(segment
		(start 177.989992 -54.6227)
		(end 178.116992 -54.4957)
		(width 0.127)
		(layer "In2.Cu")
		(net "XM_DATA_7")
	)
	(segment
		(start 179.005992 -54.6227)
		(end 179.132992 -54.4957)
		(width 0.127)
		(layer "In2.Cu")
		(net "XM_DATA_7")
	)
	(segment
		(start 179.386992 -54.4957)
		(end 179.513992 -54.6227)
		(width 0.127)
		(layer "In2.Cu")
		(net "XM_DATA_7")
	)
	(segment
		(start 179.513992 -54.6227)
		(end 179.513992 -55.1815)
		(width 0.127)
		(layer "In2.Cu")
		(net "XM_DATA_7")
	)
	(segment
		(start 189.190376 -55.099966)
		(end 189.200028 -55.099966)
		(width 0.127)
		(layer "F.Cu")
		(net "XM_DATA_6")
	)
	(segment
		(start 188.792866 -54.702456)
		(end 189.190376 -55.099966)
		(width 0.127)
		(layer "F.Cu")
		(net "XM_DATA_6")
	)
	(via
		(at 188.792866 -54.702456)
		(size 0.508)
		(drill 0.254)
		(layers "F.Cu" "B.Cu")
		(net "XM_DATA_6")
	)
	(segment
		(start 167.177466 -49.5554)
		(end 169.420286 -47.31258)
		(width 0.127)
		(layer "B.Cu")
		(net "XM_DATA_6")
	)
	(segment
		(start 161.3027 -51.894486)
		(end 161.3027 -51.640486)
		(width 0.127)
		(layer "B.Cu")
		(net "XM_DATA_6")
	)
	(segment
		(start 161.86785 -52.021486)
		(end 161.4297 -52.021486)
		(width 0.127)
		(layer "B.Cu")
		(net "XM_DATA_6")
	)
	(segment
		(start 161.99485 -50.80635)
		(end 163.2458 -49.5554)
		(width 0.127)
		(layer "B.Cu")
		(net "XM_DATA_6")
	)
	(segment
		(start 161.86785 -51.513486)
		(end 161.99485 -51.386486)
		(width 0.127)
		(layer "B.Cu")
		(net "XM_DATA_6")
	)
	(segment
		(start 177.258726 -47.31258)
		(end 181.6735 -51.727354)
		(width 0.127)
		(layer "B.Cu")
		(net "XM_DATA_6")
	)
	(segment
		(start 183.571896 -52.314348)
		(end 184.828688 -52.314348)
		(width 0.127)
		(layer "B.Cu")
		(net "XM_DATA_6")
	)
	(segment
		(start 185.792872 -52.2859)
		(end 185.82132 -52.314348)
		(width 0.127)
		(layer "B.Cu")
		(net "XM_DATA_6")
	)
	(segment
		(start 186.019948 -52.314348)
		(end 187.843668 -54.138068)
		(width 0.127)
		(layer "B.Cu")
		(net "XM_DATA_6")
	)
	(segment
		(start 161.4297 -51.513486)
		(end 161.86785 -51.513486)
		(width 0.127)
		(layer "B.Cu")
		(net "XM_DATA_6")
	)
	(segment
		(start 169.420286 -47.31258)
		(end 177.258726 -47.31258)
		(width 0.127)
		(layer "B.Cu")
		(net "XM_DATA_6")
	)
	(segment
		(start 161.3027 -51.640486)
		(end 161.4297 -51.513486)
		(width 0.127)
		(layer "B.Cu")
		(net "XM_DATA_6")
	)
	(segment
		(start 184.828688 -52.314348)
		(end 184.857136 -52.2859)
		(width 0.127)
		(layer "B.Cu")
		(net "XM_DATA_6")
	)
	(segment
		(start 161.99485 -53.6575)
		(end 161.99485 -52.148486)
		(width 0.127)
		(layer "B.Cu")
		(net "XM_DATA_6")
	)
	(segment
		(start 188.228478 -54.138068)
		(end 188.792866 -54.702456)
		(width 0.127)
		(layer "B.Cu")
		(net "XM_DATA_6")
	)
	(segment
		(start 161.99485 -51.386486)
		(end 161.99485 -50.80635)
		(width 0.127)
		(layer "B.Cu")
		(net "XM_DATA_6")
	)
	(segment
		(start 181.6735 -51.727354)
		(end 182.984902 -51.727354)
		(width 0.127)
		(layer "B.Cu")
		(net "XM_DATA_6")
	)
	(segment
		(start 182.984902 -51.727354)
		(end 183.571896 -52.314348)
		(width 0.127)
		(layer "B.Cu")
		(net "XM_DATA_6")
	)
	(segment
		(start 161.99485 -52.148486)
		(end 161.86785 -52.021486)
		(width 0.127)
		(layer "B.Cu")
		(net "XM_DATA_6")
	)
	(segment
		(start 163.2458 -49.5554)
		(end 167.177466 -49.5554)
		(width 0.127)
		(layer "B.Cu")
		(net "XM_DATA_6")
	)
	(segment
		(start 184.857136 -52.2859)
		(end 185.792872 -52.2859)
		(width 0.127)
		(layer "B.Cu")
		(net "XM_DATA_6")
	)
	(segment
		(start 185.82132 -52.314348)
		(end 186.019948 -52.314348)
		(width 0.127)
		(layer "B.Cu")
		(net "XM_DATA_6")
	)
	(segment
		(start 187.843668 -54.138068)
		(end 188.228478 -54.138068)
		(width 0.127)
		(layer "B.Cu")
		(net "XM_DATA_6")
	)
	(segment
		(start 161.4297 -52.021486)
		(end 161.3027 -51.894486)
		(width 0.127)
		(layer "B.Cu")
		(net "XM_DATA_6")
	)
	(segment
		(start 187.205366 -54.70525)
		(end 187.600082 -55.099966)
		(width 0.127)
		(layer "F.Cu")
		(net "XM_DATA_5")
	)
	(segment
		(start 187.205366 -54.695598)
		(end 187.205366 -54.70525)
		(width 0.127)
		(layer "F.Cu")
		(net "XM_DATA_5")
	)
	(via
		(at 187.205366 -54.695598)
		(size 0.508)
		(drill 0.254)
		(layers "F.Cu" "B.Cu")
		(net "XM_DATA_5")
	)
	(segment
		(start 165.623748 -50.6222)
		(end 165.877748 -50.6222)
		(width 0.127)
		(layer "B.Cu")
		(net "XM_DATA_5")
	)
	(segment
		(start 179.32019 -50.175922)
		(end 179.32019 -50.355754)
		(width 0.127)
		(layer "B.Cu")
		(net "XM_DATA_5")
	)
	(segment
		(start 165.496748 -50.1904)
		(end 165.496748 -50.4952)
		(width 0.127)
		(layer "B.Cu")
		(net "XM_DATA_5")
	)
	(segment
		(start 163.520882 -50.0634)
		(end 165.369748 -50.0634)
		(width 0.127)
		(layer "B.Cu")
		(net "XM_DATA_5")
	)
	(segment
		(start 179.183538 -50.672238)
		(end 179.363116 -50.851816)
		(width 0.127)
		(layer "B.Cu")
		(net "XM_DATA_5")
	)
	(segment
		(start 162.99434 -50.589942)
		(end 163.520882 -50.0634)
		(width 0.127)
		(layer "B.Cu")
		(net "XM_DATA_5")
	)
	(segment
		(start 179.363116 -50.851816)
		(end 179.542948 -50.851816)
		(width 0.127)
		(layer "B.Cu")
		(net "XM_DATA_5")
	)
	(segment
		(start 177.88255 -48.918114)
		(end 177.745898 -49.054766)
		(width 0.127)
		(layer "B.Cu")
		(net "XM_DATA_5")
	)
	(segment
		(start 162.99434 -53.6575)
		(end 162.99434 -52.136802)
		(width 0.127)
		(layer "B.Cu")
		(net "XM_DATA_5")
	)
	(segment
		(start 179.859432 -50.715164)
		(end 180.216302 -51.072034)
		(width 0.127)
		(layer "B.Cu")
		(net "XM_DATA_5")
	)
	(segment
		(start 181.267862 -51.956462)
		(end 181.68493 -51.955954)
		(width 0.127)
		(layer "B.Cu")
		(net "XM_DATA_5")
	)
	(segment
		(start 162.4584 -51.882802)
		(end 162.4584 -51.628802)
		(width 0.127)
		(layer "B.Cu")
		(net "XM_DATA_5")
	)
	(segment
		(start 178.644296 -50.132996)
		(end 178.824128 -50.132996)
		(width 0.127)
		(layer "B.Cu")
		(net "XM_DATA_5")
	)
	(segment
		(start 178.60137 -49.457102)
		(end 178.60137 -49.636934)
		(width 0.127)
		(layer "B.Cu")
		(net "XM_DATA_5")
	)
	(segment
		(start 182.556404 -51.955954)
		(end 183.143398 -52.542948)
		(width 0.127)
		(layer "B.Cu")
		(net "XM_DATA_5")
	)
	(segment
		(start 183.143398 -52.542948)
		(end 184.92343 -52.542948)
		(width 0.127)
		(layer "B.Cu")
		(net "XM_DATA_5")
	)
	(segment
		(start 180.216302 -51.072034)
		(end 180.383434 -51.072034)
		(width 0.127)
		(layer "B.Cu")
		(net "XM_DATA_5")
	)
	(segment
		(start 179.6796 -50.715164)
		(end 179.859432 -50.715164)
		(width 0.127)
		(layer "B.Cu")
		(net "XM_DATA_5")
	)
	(segment
		(start 178.464718 -49.773586)
		(end 178.464718 -49.953418)
		(width 0.127)
		(layer "B.Cu")
		(net "XM_DATA_5")
	)
	(segment
		(start 178.105308 -49.414176)
		(end 178.24196 -49.277524)
		(width 0.127)
		(layer "B.Cu")
		(net "XM_DATA_5")
	)
	(segment
		(start 178.464718 -49.953418)
		(end 178.644296 -50.132996)
		(width 0.127)
		(layer "B.Cu")
		(net "XM_DATA_5")
	)
	(segment
		(start 187.205366 -53.88102)
		(end 187.205366 -54.695598)
		(width 0.127)
		(layer "B.Cu")
		(net "XM_DATA_5")
	)
	(segment
		(start 179.183538 -50.492406)
		(end 179.183538 -50.672238)
		(width 0.127)
		(layer "B.Cu")
		(net "XM_DATA_5")
	)
	(segment
		(start 166.004748 -50.1904)
		(end 166.131748 -50.0634)
		(width 0.127)
		(layer "B.Cu")
		(net "XM_DATA_5")
	)
	(segment
		(start 181.68493 -51.955954)
		(end 182.556404 -51.955954)
		(width 0.127)
		(layer "B.Cu")
		(net "XM_DATA_5")
	)
	(segment
		(start 165.877748 -50.6222)
		(end 166.004748 -50.4952)
		(width 0.127)
		(layer "B.Cu")
		(net "XM_DATA_5")
	)
	(segment
		(start 165.369748 -50.0634)
		(end 165.496748 -50.1904)
		(width 0.127)
		(layer "B.Cu")
		(net "XM_DATA_5")
	)
	(segment
		(start 166.131748 -50.0634)
		(end 167.388032 -50.0634)
		(width 0.127)
		(layer "B.Cu")
		(net "XM_DATA_5")
	)
	(segment
		(start 179.542948 -50.851816)
		(end 179.6796 -50.715164)
		(width 0.127)
		(layer "B.Cu")
		(net "XM_DATA_5")
	)
	(segment
		(start 185.726578 -52.542948)
		(end 185.867294 -52.542948)
		(width 0.127)
		(layer "B.Cu")
		(net "XM_DATA_5")
	)
	(segment
		(start 162.86734 -51.501802)
		(end 162.99434 -51.374802)
		(width 0.127)
		(layer "B.Cu")
		(net "XM_DATA_5")
	)
	(segment
		(start 184.92343 -52.542948)
		(end 184.951878 -52.5145)
		(width 0.127)
		(layer "B.Cu")
		(net "XM_DATA_5")
	)
	(segment
		(start 184.951878 -52.5145)
		(end 185.69813 -52.5145)
		(width 0.127)
		(layer "B.Cu")
		(net "XM_DATA_5")
	)
	(segment
		(start 162.5854 -51.501802)
		(end 162.86734 -51.501802)
		(width 0.127)
		(layer "B.Cu")
		(net "XM_DATA_5")
	)
	(segment
		(start 162.5854 -52.009802)
		(end 162.4584 -51.882802)
		(width 0.127)
		(layer "B.Cu")
		(net "XM_DATA_5")
	)
	(segment
		(start 180.383434 -51.072034)
		(end 181.267862 -51.956462)
		(width 0.127)
		(layer "B.Cu")
		(net "XM_DATA_5")
	)
	(segment
		(start 176.964848 -47.82058)
		(end 177.88255 -48.738282)
		(width 0.127)
		(layer "B.Cu")
		(net "XM_DATA_5")
	)
	(segment
		(start 179.32019 -50.355754)
		(end 179.183538 -50.492406)
		(width 0.127)
		(layer "B.Cu")
		(net "XM_DATA_5")
	)
	(segment
		(start 185.867294 -52.542948)
		(end 187.205366 -53.88102)
		(width 0.127)
		(layer "B.Cu")
		(net "XM_DATA_5")
	)
	(segment
		(start 162.99434 -52.136802)
		(end 162.86734 -52.009802)
		(width 0.127)
		(layer "B.Cu")
		(net "XM_DATA_5")
	)
	(segment
		(start 178.96078 -49.996344)
		(end 179.140612 -49.996344)
		(width 0.127)
		(layer "B.Cu")
		(net "XM_DATA_5")
	)
	(segment
		(start 167.388032 -50.0634)
		(end 169.630852 -47.82058)
		(width 0.127)
		(layer "B.Cu")
		(net "XM_DATA_5")
	)
	(segment
		(start 166.004748 -50.4952)
		(end 166.004748 -50.1904)
		(width 0.127)
		(layer "B.Cu")
		(net "XM_DATA_5")
	)
	(segment
		(start 177.745898 -49.234598)
		(end 177.925476 -49.414176)
		(width 0.127)
		(layer "B.Cu")
		(net "XM_DATA_5")
	)
	(segment
		(start 177.745898 -49.054766)
		(end 177.745898 -49.234598)
		(width 0.127)
		(layer "B.Cu")
		(net "XM_DATA_5")
	)
	(segment
		(start 169.630852 -47.82058)
		(end 176.964848 -47.82058)
		(width 0.127)
		(layer "B.Cu")
		(net "XM_DATA_5")
	)
	(segment
		(start 162.99434 -51.374802)
		(end 162.99434 -50.589942)
		(width 0.127)
		(layer "B.Cu")
		(net "XM_DATA_5")
	)
	(segment
		(start 179.140612 -49.996344)
		(end 179.32019 -50.175922)
		(width 0.127)
		(layer "B.Cu")
		(net "XM_DATA_5")
	)
	(segment
		(start 185.69813 -52.5145)
		(end 185.726578 -52.542948)
		(width 0.127)
		(layer "B.Cu")
		(net "XM_DATA_5")
	)
	(segment
		(start 178.421792 -49.277524)
		(end 178.60137 -49.457102)
		(width 0.127)
		(layer "B.Cu")
		(net "XM_DATA_5")
	)
	(segment
		(start 178.824128 -50.132996)
		(end 178.96078 -49.996344)
		(width 0.127)
		(layer "B.Cu")
		(net "XM_DATA_5")
	)
	(segment
		(start 165.496748 -50.4952)
		(end 165.623748 -50.6222)
		(width 0.127)
		(layer "B.Cu")
		(net "XM_DATA_5")
	)
	(segment
		(start 178.24196 -49.277524)
		(end 178.421792 -49.277524)
		(width 0.127)
		(layer "B.Cu")
		(net "XM_DATA_5")
	)
	(segment
		(start 177.925476 -49.414176)
		(end 178.105308 -49.414176)
		(width 0.127)
		(layer "B.Cu")
		(net "XM_DATA_5")
	)
	(segment
		(start 178.60137 -49.636934)
		(end 178.464718 -49.773586)
		(width 0.127)
		(layer "B.Cu")
		(net "XM_DATA_5")
	)
	(segment
		(start 162.86734 -52.009802)
		(end 162.5854 -52.009802)
		(width 0.127)
		(layer "B.Cu")
		(net "XM_DATA_5")
	)
	(segment
		(start 162.4584 -51.628802)
		(end 162.5854 -51.501802)
		(width 0.127)
		(layer "B.Cu")
		(net "XM_DATA_5")
	)
	(segment
		(start 177.88255 -48.738282)
		(end 177.88255 -48.918114)
		(width 0.127)
		(layer "B.Cu")
		(net "XM_DATA_5")
	)
	(segment
		(start 181.99989 -61.500004)
		(end 181.600094 -61.8998)
		(width 0.127)
		(layer "F.Cu")
		(net "XM_DATA_4")
	)
	(via
		(at 181.600094 -61.8998)
		(size 0.508)
		(drill 0.254)
		(layers "F.Cu" "B.Cu")
		(net "XM_DATA_4")
	)
	(segment
		(start 176.8856 -62.4459)
		(end 176.7586 -62.3189)
		(width 0.127)
		(layer "B.Cu")
		(net "XM_DATA_4")
	)
	(segment
		(start 163.99383 -55.332376)
		(end 163.99383 -53.6575)
		(width 0.127)
		(layer "B.Cu")
		(net "XM_DATA_4")
	)
	(segment
		(start 171.0309 -62.9539)
		(end 171.1579 -62.8269)
		(width 0.127)
		(layer "B.Cu")
		(net "XM_DATA_4")
	)
	(segment
		(start 177.063654 -63.3349)
		(end 171.1579 -63.3349)
		(width 0.127)
		(layer "B.Cu")
		(net "XM_DATA_4")
	)
	(segment
		(start 181.600094 -61.8998)
		(end 181.180994 -62.3189)
		(width 0.127)
		(layer "B.Cu")
		(net "XM_DATA_4")
	)
	(segment
		(start 181.180994 -62.3189)
		(end 178.079654 -62.3189)
		(width 0.127)
		(layer "B.Cu")
		(net "XM_DATA_4")
	)
	(segment
		(start 170.980354 -62.3189)
		(end 163.99383 -55.332376)
		(width 0.127)
		(layer "B.Cu")
		(net "XM_DATA_4")
	)
	(segment
		(start 178.079654 -62.3189)
		(end 177.063654 -63.3349)
		(width 0.127)
		(layer "B.Cu")
		(net "XM_DATA_4")
	)
	(segment
		(start 171.1579 -63.3349)
		(end 171.0309 -63.2079)
		(width 0.127)
		(layer "B.Cu")
		(net "XM_DATA_4")
	)
	(segment
		(start 176.7586 -62.3189)
		(end 170.980354 -62.3189)
		(width 0.127)
		(layer "B.Cu")
		(net "XM_DATA_4")
	)
	(segment
		(start 171.0309 -63.2079)
		(end 171.0309 -62.9539)
		(width 0.127)
		(layer "B.Cu")
		(net "XM_DATA_4")
	)
	(segment
		(start 176.8856 -62.6999)
		(end 176.8856 -62.4459)
		(width 0.127)
		(layer "B.Cu")
		(net "XM_DATA_4")
	)
	(segment
		(start 176.7586 -62.8269)
		(end 176.8856 -62.6999)
		(width 0.127)
		(layer "B.Cu")
		(net "XM_DATA_4")
	)
	(segment
		(start 171.1579 -62.8269)
		(end 176.7586 -62.8269)
		(width 0.127)
		(layer "B.Cu")
		(net "XM_DATA_4")
	)
	(segment
		(start 181.200044 -61.500004)
		(end 180.800248 -61.8998)
		(width 0.127)
		(layer "F.Cu")
		(net "XM_DATA_3")
	)
	(via
		(at 180.800248 -61.8998)
		(size 0.508)
		(drill 0.254)
		(layers "F.Cu" "B.Cu")
		(net "XM_DATA_3")
	)
	(segment
		(start 170.015154 -60.424822)
		(end 170.015154 -60.604654)
		(width 0.127)
		(layer "B.Cu")
		(net "XM_DATA_3")
	)
	(segment
		(start 169.563288 -59.259216)
		(end 169.563288 -59.439048)
		(width 0.127)
		(layer "B.Cu")
		(net "XM_DATA_3")
	)
	(segment
		(start 175.637698 -61.160914)
		(end 175.510698 -61.287914)
		(width 0.127)
		(layer "B.Cu")
		(net "XM_DATA_3")
	)
	(segment
		(start 175.510698 -61.287914)
		(end 171.5516 -61.287914)
		(width 0.127)
		(layer "B.Cu")
		(net "XM_DATA_3")
	)
	(segment
		(start 166.421054 -57.010554)
		(end 166.600632 -57.190132)
		(width 0.127)
		(layer "B.Cu")
		(net "XM_DATA_3")
	)
	(segment
		(start 171.4246 -61.414914)
		(end 171.4246 -61.668914)
		(width 0.127)
		(layer "B.Cu")
		(net "XM_DATA_3")
	)
	(segment
		(start 175.637698 -60.906914)
		(end 175.637698 -61.160914)
		(width 0.127)
		(layer "B.Cu")
		(net "XM_DATA_3")
	)
	(segment
		(start 167.858694 -58.268362)
		(end 167.858694 -58.448194)
		(width 0.127)
		(layer "B.Cu")
		(net "XM_DATA_3")
	)
	(segment
		(start 169.563288 -59.439048)
		(end 169.296334 -59.706002)
		(width 0.127)
		(layer "B.Cu")
		(net "XM_DATA_3")
	)
	(segment
		(start 178.115214 -60.779914)
		(end 179.2351 -61.8998)
		(width 0.127)
		(layer "B.Cu")
		(net "XM_DATA_3")
	)
	(segment
		(start 168.485058 -58.360818)
		(end 168.66489 -58.360818)
		(width 0.127)
		(layer "B.Cu")
		(net "XM_DATA_3")
	)
	(segment
		(start 167.499284 -57.908952)
		(end 167.766238 -57.641998)
		(width 0.127)
		(layer "B.Cu")
		(net "XM_DATA_3")
	)
	(segment
		(start 167.94607 -57.641998)
		(end 168.125648 -57.821576)
		(width 0.127)
		(layer "B.Cu")
		(net "XM_DATA_3")
	)
	(segment
		(start 176.145698 -61.668914)
		(end 176.145698 -60.906914)
		(width 0.127)
		(layer "B.Cu")
		(net "XM_DATA_3")
	)
	(segment
		(start 170.282108 -60.157868)
		(end 170.015154 -60.424822)
		(width 0.127)
		(layer "B.Cu")
		(net "XM_DATA_3")
	)
	(segment
		(start 168.125648 -58.001408)
		(end 167.858694 -58.268362)
		(width 0.127)
		(layer "B.Cu")
		(net "XM_DATA_3")
	)
	(segment
		(start 171.5516 -61.287914)
		(end 171.4246 -61.414914)
		(width 0.127)
		(layer "B.Cu")
		(net "XM_DATA_3")
	)
	(segment
		(start 169.922698 -59.798458)
		(end 170.10253 -59.798458)
		(width 0.127)
		(layer "B.Cu")
		(net "XM_DATA_3")
	)
	(segment
		(start 169.655744 -60.065412)
		(end 169.922698 -59.798458)
		(width 0.127)
		(layer "B.Cu")
		(net "XM_DATA_3")
	)
	(segment
		(start 170.641518 -60.517278)
		(end 170.82135 -60.517278)
		(width 0.127)
		(layer "B.Cu")
		(net "XM_DATA_3")
	)
	(segment
		(start 167.858694 -58.448194)
		(end 168.038272 -58.627772)
		(width 0.127)
		(layer "B.Cu")
		(net "XM_DATA_3")
	)
	(segment
		(start 167.406828 -57.282588)
		(end 167.139874 -57.549542)
		(width 0.127)
		(layer "B.Cu")
		(net "XM_DATA_3")
	)
	(segment
		(start 168.844468 -58.540396)
		(end 168.844468 -58.720228)
		(width 0.127)
		(layer "B.Cu")
		(net "XM_DATA_3")
	)
	(segment
		(start 169.296334 -59.885834)
		(end 169.475912 -60.065412)
		(width 0.127)
		(layer "B.Cu")
		(net "XM_DATA_3")
	)
	(segment
		(start 170.194732 -60.784232)
		(end 170.374564 -60.784232)
		(width 0.127)
		(layer "B.Cu")
		(net "XM_DATA_3")
	)
	(segment
		(start 168.577514 -59.167014)
		(end 168.757092 -59.346592)
		(width 0.127)
		(layer "B.Cu")
		(net "XM_DATA_3")
	)
	(segment
		(start 176.018698 -61.795914)
		(end 176.145698 -61.668914)
		(width 0.127)
		(layer "B.Cu")
		(net "XM_DATA_3")
	)
	(segment
		(start 167.319452 -57.908952)
		(end 167.499284 -57.908952)
		(width 0.127)
		(layer "B.Cu")
		(net "XM_DATA_3")
	)
	(segment
		(start 170.82135 -60.517278)
		(end 171.083986 -60.779914)
		(width 0.127)
		(layer "B.Cu")
		(net "XM_DATA_3")
	)
	(segment
		(start 166.600632 -57.190132)
		(end 166.780464 -57.190132)
		(width 0.127)
		(layer "B.Cu")
		(net "XM_DATA_3")
	)
	(segment
		(start 171.5516 -61.795914)
		(end 176.018698 -61.795914)
		(width 0.127)
		(layer "B.Cu")
		(net "XM_DATA_3")
	)
	(segment
		(start 168.66489 -58.360818)
		(end 168.844468 -58.540396)
		(width 0.127)
		(layer "B.Cu")
		(net "XM_DATA_3")
	)
	(segment
		(start 167.139874 -57.729374)
		(end 167.319452 -57.908952)
		(width 0.127)
		(layer "B.Cu")
		(net "XM_DATA_3")
	)
	(segment
		(start 167.766238 -57.641998)
		(end 167.94607 -57.641998)
		(width 0.127)
		(layer "B.Cu")
		(net "XM_DATA_3")
	)
	(segment
		(start 167.047418 -56.923178)
		(end 167.22725 -56.923178)
		(width 0.127)
		(layer "B.Cu")
		(net "XM_DATA_3")
	)
	(segment
		(start 166.780464 -57.190132)
		(end 167.047418 -56.923178)
		(width 0.127)
		(layer "B.Cu")
		(net "XM_DATA_3")
	)
	(segment
		(start 168.844468 -58.720228)
		(end 168.577514 -58.987182)
		(width 0.127)
		(layer "B.Cu")
		(net "XM_DATA_3")
	)
	(segment
		(start 167.406828 -57.102756)
		(end 167.406828 -57.282588)
		(width 0.127)
		(layer "B.Cu")
		(net "XM_DATA_3")
	)
	(segment
		(start 169.38371 -59.079638)
		(end 169.563288 -59.259216)
		(width 0.127)
		(layer "B.Cu")
		(net "XM_DATA_3")
	)
	(segment
		(start 165.49497 -55.190898)
		(end 166.688008 -56.383936)
		(width 0.127)
		(layer "B.Cu")
		(net "XM_DATA_3")
	)
	(segment
		(start 168.757092 -59.346592)
		(end 168.936924 -59.346592)
		(width 0.127)
		(layer "B.Cu")
		(net "XM_DATA_3")
	)
	(segment
		(start 169.296334 -59.706002)
		(end 169.296334 -59.885834)
		(width 0.127)
		(layer "B.Cu")
		(net "XM_DATA_3")
	)
	(segment
		(start 165.49497 -53.6575)
		(end 165.49497 -55.190898)
		(width 0.127)
		(layer "B.Cu")
		(net "XM_DATA_3")
	)
	(segment
		(start 176.145698 -60.906914)
		(end 176.272698 -60.779914)
		(width 0.127)
		(layer "B.Cu")
		(net "XM_DATA_3")
	)
	(segment
		(start 170.374564 -60.784232)
		(end 170.641518 -60.517278)
		(width 0.127)
		(layer "B.Cu")
		(net "XM_DATA_3")
	)
	(segment
		(start 166.688008 -56.563768)
		(end 166.421054 -56.830722)
		(width 0.127)
		(layer "B.Cu")
		(net "XM_DATA_3")
	)
	(segment
		(start 171.083986 -60.779914)
		(end 175.510698 -60.779914)
		(width 0.127)
		(layer "B.Cu")
		(net "XM_DATA_3")
	)
	(segment
		(start 176.272698 -60.779914)
		(end 178.115214 -60.779914)
		(width 0.127)
		(layer "B.Cu")
		(net "XM_DATA_3")
	)
	(segment
		(start 169.203878 -59.079638)
		(end 169.38371 -59.079638)
		(width 0.127)
		(layer "B.Cu")
		(net "XM_DATA_3")
	)
	(segment
		(start 168.218104 -58.627772)
		(end 168.485058 -58.360818)
		(width 0.127)
		(layer "B.Cu")
		(net "XM_DATA_3")
	)
	(segment
		(start 170.282108 -59.978036)
		(end 170.282108 -60.157868)
		(width 0.127)
		(layer "B.Cu")
		(net "XM_DATA_3")
	)
	(segment
		(start 170.10253 -59.798458)
		(end 170.282108 -59.978036)
		(width 0.127)
		(layer "B.Cu")
		(net "XM_DATA_3")
	)
	(segment
		(start 166.688008 -56.383936)
		(end 166.688008 -56.563768)
		(width 0.127)
		(layer "B.Cu")
		(net "XM_DATA_3")
	)
	(segment
		(start 169.475912 -60.065412)
		(end 169.655744 -60.065412)
		(width 0.127)
		(layer "B.Cu")
		(net "XM_DATA_3")
	)
	(segment
		(start 167.22725 -56.923178)
		(end 167.406828 -57.102756)
		(width 0.127)
		(layer "B.Cu")
		(net "XM_DATA_3")
	)
	(segment
		(start 179.2351 -61.8998)
		(end 180.800248 -61.8998)
		(width 0.127)
		(layer "B.Cu")
		(net "XM_DATA_3")
	)
	(segment
		(start 168.577514 -58.987182)
		(end 168.577514 -59.167014)
		(width 0.127)
		(layer "B.Cu")
		(net "XM_DATA_3")
	)
	(segment
		(start 166.421054 -56.830722)
		(end 166.421054 -57.010554)
		(width 0.127)
		(layer "B.Cu")
		(net "XM_DATA_3")
	)
	(segment
		(start 170.015154 -60.604654)
		(end 170.194732 -60.784232)
		(width 0.127)
		(layer "B.Cu")
		(net "XM_DATA_3")
	)
	(segment
		(start 168.125648 -57.821576)
		(end 168.125648 -58.001408)
		(width 0.127)
		(layer "B.Cu")
		(net "XM_DATA_3")
	)
	(segment
		(start 175.510698 -60.779914)
		(end 175.637698 -60.906914)
		(width 0.127)
		(layer "B.Cu")
		(net "XM_DATA_3")
	)
	(segment
		(start 168.936924 -59.346592)
		(end 169.203878 -59.079638)
		(width 0.127)
		(layer "B.Cu")
		(net "XM_DATA_3")
	)
	(segment
		(start 171.4246 -61.668914)
		(end 171.5516 -61.795914)
		(width 0.127)
		(layer "B.Cu")
		(net "XM_DATA_3")
	)
	(segment
		(start 167.139874 -57.549542)
		(end 167.139874 -57.729374)
		(width 0.127)
		(layer "B.Cu")
		(net "XM_DATA_3")
	)
	(segment
		(start 168.038272 -58.627772)
		(end 168.218104 -58.627772)
		(width 0.127)
		(layer "B.Cu")
		(net "XM_DATA_3")
	)
	(segment
		(start 182.79999 -60.699904)
		(end 182.400194 -61.0997)
		(width 0.127)
		(layer "F.Cu")
		(net "XM_DATA_2")
	)
	(via
		(at 182.400194 -61.0997)
		(size 0.508)
		(drill 0.254)
		(layers "F.Cu" "B.Cu")
		(net "XM_DATA_2")
	)
	(segment
		(start 170.765216 -59.2201)
		(end 166.49446 -54.949344)
		(width 0.127)
		(layer "B.Cu")
		(net "XM_DATA_2")
	)
	(segment
		(start 179.535582 -60.624466)
		(end 179.128166 -60.624466)
		(width 0.127)
		(layer "B.Cu")
		(net "XM_DATA_2")
	)
	(segment
		(start 178.4858 -59.6011)
		(end 178.4858 -59.3471)
		(width 0.127)
		(layer "B.Cu")
		(net "XM_DATA_2")
	)
	(segment
		(start 181.9275 -61.0997)
		(end 181.61 -61.4172)
		(width 0.127)
		(layer "B.Cu")
		(net "XM_DATA_2")
	)
	(segment
		(start 178.3588 -59.7281)
		(end 178.4858 -59.6011)
		(width 0.127)
		(layer "B.Cu")
		(net "XM_DATA_2")
	)
	(segment
		(start 178.3588 -59.2201)
		(end 170.765216 -59.2201)
		(width 0.127)
		(layer "B.Cu")
		(net "XM_DATA_2")
	)
	(segment
		(start 171.2849 -60.2361)
		(end 171.1579 -60.1091)
		(width 0.127)
		(layer "B.Cu")
		(net "XM_DATA_2")
	)
	(segment
		(start 178.7398 -60.2361)
		(end 171.2849 -60.2361)
		(width 0.127)
		(layer "B.Cu")
		(net "XM_DATA_2")
	)
	(segment
		(start 182.400194 -61.0997)
		(end 181.9275 -61.0997)
		(width 0.127)
		(layer "B.Cu")
		(net "XM_DATA_2")
	)
	(segment
		(start 180.328316 -61.4172)
		(end 179.535582 -60.624466)
		(width 0.127)
		(layer "B.Cu")
		(net "XM_DATA_2")
	)
	(segment
		(start 166.49446 -54.949344)
		(end 166.49446 -53.6575)
		(width 0.127)
		(layer "B.Cu")
		(net "XM_DATA_2")
	)
	(segment
		(start 171.2849 -59.7281)
		(end 178.3588 -59.7281)
		(width 0.127)
		(layer "B.Cu")
		(net "XM_DATA_2")
	)
	(segment
		(start 171.1579 -59.8551)
		(end 171.2849 -59.7281)
		(width 0.127)
		(layer "B.Cu")
		(net "XM_DATA_2")
	)
	(segment
		(start 178.4858 -59.3471)
		(end 178.3588 -59.2201)
		(width 0.127)
		(layer "B.Cu")
		(net "XM_DATA_2")
	)
	(segment
		(start 171.1579 -60.1091)
		(end 171.1579 -59.8551)
		(width 0.127)
		(layer "B.Cu")
		(net "XM_DATA_2")
	)
	(segment
		(start 179.128166 -60.624466)
		(end 178.7398 -60.2361)
		(width 0.127)
		(layer "B.Cu")
		(net "XM_DATA_2")
	)
	(segment
		(start 181.61 -61.4172)
		(end 180.328316 -61.4172)
		(width 0.127)
		(layer "B.Cu")
		(net "XM_DATA_2")
	)
	(segment
		(start 189.999874 -55.099966)
		(end 189.600078 -54.70017)
		(width 0.127)
		(layer "F.Cu")
		(net "XM_DATA_15")
	)
	(via
		(at 189.600078 -54.70017)
		(size 0.508)
		(drill 0.254)
		(layers "F.Cu" "B.Cu")
		(net "XM_DATA_15")
	)
	(segment
		(start 169.20972 -46.80458)
		(end 177.535332 -46.80458)
		(width 0.127)
		(layer "B.Cu")
		(net "XM_DATA_15")
	)
	(segment
		(start 177.535332 -46.80458)
		(end 182.229506 -51.498754)
		(width 0.127)
		(layer "B.Cu")
		(net "XM_DATA_15")
	)
	(segment
		(start 184.45861 -51.498754)
		(end 184.481216 -51.476148)
		(width 0.127)
		(layer "B.Cu")
		(net "XM_DATA_15")
	)
	(segment
		(start 184.481216 -51.476148)
		(end 186.185048 -51.476148)
		(width 0.127)
		(layer "B.Cu")
		(net "XM_DATA_15")
	)
	(segment
		(start 188.0616 -53.3527)
		(end 188.840618 -53.3527)
		(width 0.127)
		(layer "B.Cu")
		(net "XM_DATA_15")
	)
	(segment
		(start 166.9669 -49.0474)
		(end 169.20972 -46.80458)
		(width 0.127)
		(layer "B.Cu")
		(net "XM_DATA_15")
	)
	(segment
		(start 182.229506 -51.498754)
		(end 184.45861 -51.498754)
		(width 0.127)
		(layer "B.Cu")
		(net "XM_DATA_15")
	)
	(segment
		(start 188.840618 -53.3527)
		(end 189.600078 -54.11216)
		(width 0.127)
		(layer "B.Cu")
		(net "XM_DATA_15")
	)
	(segment
		(start 160.49498 -51.55692)
		(end 163.0045 -49.0474)
		(width 0.127)
		(layer "B.Cu")
		(net "XM_DATA_15")
	)
	(segment
		(start 186.185048 -51.476148)
		(end 188.0616 -53.3527)
		(width 0.127)
		(layer "B.Cu")
		(net "XM_DATA_15")
	)
	(segment
		(start 189.600078 -54.11216)
		(end 189.600078 -54.70017)
		(width 0.127)
		(layer "B.Cu")
		(net "XM_DATA_15")
	)
	(segment
		(start 160.49498 -53.6575)
		(end 160.49498 -51.55692)
		(width 0.127)
		(layer "B.Cu")
		(net "XM_DATA_15")
	)
	(segment
		(start 163.0045 -49.0474)
		(end 166.9669 -49.0474)
		(width 0.127)
		(layer "B.Cu")
		(net "XM_DATA_15")
	)
	(segment
		(start 180.060854 -57.128918)
		(end 181.570884 -57.128918)
		(width 0.127)
		(layer "F.Cu")
		(net "XM_DATA_14")
	)
	(segment
		(start 178.810666 -55.87873)
		(end 180.060854 -57.128918)
		(width 0.127)
		(layer "F.Cu")
		(net "XM_DATA_14")
	)
	(segment
		(start 181.570884 -57.128918)
		(end 181.99989 -56.699912)
		(width 0.127)
		(layer "F.Cu")
		(net "XM_DATA_14")
	)
	(via
		(at 161.668714 -55.268368)
		(size 0.508)
		(drill 0.254)
		(layers "F.Cu" "B.Cu")
		(net "XM_DATA_14")
	)
	(via
		(at 178.810666 -55.87873)
		(size 0.508)
		(drill 0.254)
		(layers "F.Cu" "B.Cu")
		(net "XM_DATA_14")
	)
	(segment
		(start 161.668714 -55.268368)
		(end 161.49447 -55.094124)
		(width 0.127)
		(layer "B.Cu")
		(net "XM_DATA_14")
	)
	(segment
		(start 161.49447 -55.094124)
		(end 161.49447 -53.6575)
		(width 0.127)
		(layer "B.Cu")
		(net "XM_DATA_14")
	)
	(segment
		(start 173.170088 -56.00573)
		(end 173.170088 -56.6293)
		(width 0.127)
		(layer "In2.Cu")
		(net "XM_DATA_14")
	)
	(segment
		(start 172.281088 -55.87873)
		(end 172.154088 -56.00573)
		(width 0.127)
		(layer "In2.Cu")
		(net "XM_DATA_14")
	)
	(segment
		(start 170.503088 -55.87873)
		(end 170.249088 -55.87873)
		(width 0.127)
		(layer "In2.Cu")
		(net "XM_DATA_14")
	)
	(segment
		(start 171.646088 -56.00573)
		(end 171.519088 -55.87873)
		(width 0.127)
		(layer "In2.Cu")
		(net "XM_DATA_14")
	)
	(segment
		(start 173.043088 -56.7563)
		(end 172.789088 -56.7563)
		(width 0.127)
		(layer "In2.Cu")
		(net "XM_DATA_14")
	)
	(segment
		(start 176.853088 -56.7563)
		(end 176.726088 -56.6293)
		(width 0.127)
		(layer "In2.Cu")
		(net "XM_DATA_14")
	)
	(segment
		(start 177.615088 -55.87873)
		(end 177.361088 -55.87873)
		(width 0.127)
		(layer "In2.Cu")
		(net "XM_DATA_14")
	)
	(segment
		(start 173.170088 -56.6293)
		(end 173.043088 -56.7563)
		(width 0.127)
		(layer "In2.Cu")
		(net "XM_DATA_14")
	)
	(segment
		(start 177.361088 -55.87873)
		(end 177.234088 -56.00573)
		(width 0.127)
		(layer "In2.Cu")
		(net "XM_DATA_14")
	)
	(segment
		(start 169.614088 -56.6293)
		(end 169.614088 -56.00573)
		(width 0.127)
		(layer "In2.Cu")
		(net "XM_DATA_14")
	)
	(segment
		(start 173.297088 -55.87873)
		(end 173.170088 -56.00573)
		(width 0.127)
		(layer "In2.Cu")
		(net "XM_DATA_14")
	)
	(segment
		(start 178.123088 -56.7563)
		(end 177.869088 -56.7563)
		(width 0.127)
		(layer "In2.Cu")
		(net "XM_DATA_14")
	)
	(segment
		(start 171.011088 -56.7563)
		(end 170.757088 -56.7563)
		(width 0.127)
		(layer "In2.Cu")
		(net "XM_DATA_14")
	)
	(segment
		(start 170.757088 -56.7563)
		(end 170.630088 -56.6293)
		(width 0.127)
		(layer "In2.Cu")
		(net "XM_DATA_14")
	)
	(segment
		(start 177.742088 -56.6293)
		(end 177.742088 -56.00573)
		(width 0.127)
		(layer "In2.Cu")
		(net "XM_DATA_14")
	)
	(segment
		(start 176.218088 -56.00573)
		(end 176.218088 -56.6293)
		(width 0.127)
		(layer "In2.Cu")
		(net "XM_DATA_14")
	)
	(segment
		(start 175.329088 -55.87873)
		(end 175.202088 -56.00573)
		(width 0.127)
		(layer "In2.Cu")
		(net "XM_DATA_14")
	)
	(segment
		(start 172.027088 -56.7563)
		(end 171.773088 -56.7563)
		(width 0.127)
		(layer "In2.Cu")
		(net "XM_DATA_14")
	)
	(segment
		(start 174.313088 -55.87873)
		(end 174.186088 -56.00573)
		(width 0.127)
		(layer "In2.Cu")
		(net "XM_DATA_14")
	)
	(segment
		(start 175.075088 -56.7563)
		(end 174.821088 -56.7563)
		(width 0.127)
		(layer "In2.Cu")
		(net "XM_DATA_14")
	)
	(segment
		(start 162.230562 -54.70652)
		(end 161.668714 -55.268368)
		(width 0.127)
		(layer "In2.Cu")
		(net "XM_DATA_14")
	)
	(segment
		(start 171.646088 -56.6293)
		(end 171.646088 -56.00573)
		(width 0.127)
		(layer "In2.Cu")
		(net "XM_DATA_14")
	)
	(segment
		(start 175.710088 -56.00573)
		(end 175.583088 -55.87873)
		(width 0.127)
		(layer "In2.Cu")
		(net "XM_DATA_14")
	)
	(segment
		(start 178.810666 -55.87873)
		(end 178.377088 -55.87873)
		(width 0.127)
		(layer "In2.Cu")
		(net "XM_DATA_14")
	)
	(segment
		(start 173.678088 -56.00573)
		(end 173.551088 -55.87873)
		(width 0.127)
		(layer "In2.Cu")
		(net "XM_DATA_14")
	)
	(segment
		(start 172.789088 -56.7563)
		(end 172.662088 -56.6293)
		(width 0.127)
		(layer "In2.Cu")
		(net "XM_DATA_14")
	)
	(segment
		(start 169.614088 -56.00573)
		(end 169.487088 -55.87873)
		(width 0.127)
		(layer "In2.Cu")
		(net "XM_DATA_14")
	)
	(segment
		(start 170.249088 -55.87873)
		(end 170.122088 -56.00573)
		(width 0.127)
		(layer "In2.Cu")
		(net "XM_DATA_14")
	)
	(segment
		(start 174.694088 -56.00573)
		(end 174.567088 -55.87873)
		(width 0.127)
		(layer "In2.Cu")
		(net "XM_DATA_14")
	)
	(segment
		(start 175.710088 -56.6293)
		(end 175.710088 -56.00573)
		(width 0.127)
		(layer "In2.Cu")
		(net "XM_DATA_14")
	)
	(segment
		(start 175.202088 -56.00573)
		(end 175.202088 -56.6293)
		(width 0.127)
		(layer "In2.Cu")
		(net "XM_DATA_14")
	)
	(segment
		(start 175.837088 -56.7563)
		(end 175.710088 -56.6293)
		(width 0.127)
		(layer "In2.Cu")
		(net "XM_DATA_14")
	)
	(segment
		(start 173.678088 -56.6293)
		(end 173.678088 -56.00573)
		(width 0.127)
		(layer "In2.Cu")
		(net "XM_DATA_14")
	)
	(segment
		(start 177.742088 -56.00573)
		(end 177.615088 -55.87873)
		(width 0.127)
		(layer "In2.Cu")
		(net "XM_DATA_14")
	)
	(segment
		(start 169.995088 -56.7563)
		(end 169.741088 -56.7563)
		(width 0.127)
		(layer "In2.Cu")
		(net "XM_DATA_14")
	)
	(segment
		(start 172.154088 -56.6293)
		(end 172.027088 -56.7563)
		(width 0.127)
		(layer "In2.Cu")
		(net "XM_DATA_14")
	)
	(segment
		(start 174.567088 -55.87873)
		(end 174.313088 -55.87873)
		(width 0.127)
		(layer "In2.Cu")
		(net "XM_DATA_14")
	)
	(segment
		(start 176.345088 -55.87873)
		(end 176.218088 -56.00573)
		(width 0.127)
		(layer "In2.Cu")
		(net "XM_DATA_14")
	)
	(segment
		(start 163.365434 -54.70652)
		(end 162.230562 -54.70652)
		(width 0.127)
		(layer "In2.Cu")
		(net "XM_DATA_14")
	)
	(segment
		(start 174.059088 -56.7563)
		(end 173.805088 -56.7563)
		(width 0.127)
		(layer "In2.Cu")
		(net "XM_DATA_14")
	)
	(segment
		(start 178.377088 -55.87873)
		(end 178.250088 -56.00573)
		(width 0.127)
		(layer "In2.Cu")
		(net "XM_DATA_14")
	)
	(segment
		(start 171.265088 -55.87873)
		(end 171.138088 -56.00573)
		(width 0.127)
		(layer "In2.Cu")
		(net "XM_DATA_14")
	)
	(segment
		(start 173.805088 -56.7563)
		(end 173.678088 -56.6293)
		(width 0.127)
		(layer "In2.Cu")
		(net "XM_DATA_14")
	)
	(segment
		(start 170.122088 -56.00573)
		(end 170.122088 -56.6293)
		(width 0.127)
		(layer "In2.Cu")
		(net "XM_DATA_14")
	)
	(segment
		(start 174.186088 -56.6293)
		(end 174.059088 -56.7563)
		(width 0.127)
		(layer "In2.Cu")
		(net "XM_DATA_14")
	)
	(segment
		(start 164.537644 -55.87873)
		(end 163.365434 -54.70652)
		(width 0.127)
		(layer "In2.Cu")
		(net "XM_DATA_14")
	)
	(segment
		(start 176.599088 -55.87873)
		(end 176.345088 -55.87873)
		(width 0.127)
		(layer "In2.Cu")
		(net "XM_DATA_14")
	)
	(segment
		(start 171.773088 -56.7563)
		(end 171.646088 -56.6293)
		(width 0.127)
		(layer "In2.Cu")
		(net "XM_DATA_14")
	)
	(segment
		(start 174.821088 -56.7563)
		(end 174.694088 -56.6293)
		(width 0.127)
		(layer "In2.Cu")
		(net "XM_DATA_14")
	)
	(segment
		(start 178.250088 -56.00573)
		(end 178.250088 -56.6293)
		(width 0.127)
		(layer "In2.Cu")
		(net "XM_DATA_14")
	)
	(segment
		(start 169.741088 -56.7563)
		(end 169.614088 -56.6293)
		(width 0.127)
		(layer "In2.Cu")
		(net "XM_DATA_14")
	)
	(segment
		(start 170.630088 -56.6293)
		(end 170.630088 -56.00573)
		(width 0.127)
		(layer "In2.Cu")
		(net "XM_DATA_14")
	)
	(segment
		(start 177.234088 -56.6293)
		(end 177.107088 -56.7563)
		(width 0.127)
		(layer "In2.Cu")
		(net "XM_DATA_14")
	)
	(segment
		(start 176.091088 -56.7563)
		(end 175.837088 -56.7563)
		(width 0.127)
		(layer "In2.Cu")
		(net "XM_DATA_14")
	)
	(segment
		(start 170.630088 -56.00573)
		(end 170.503088 -55.87873)
		(width 0.127)
		(layer "In2.Cu")
		(net "XM_DATA_14")
	)
	(segment
		(start 172.662088 -56.00573)
		(end 172.535088 -55.87873)
		(width 0.127)
		(layer "In2.Cu")
		(net "XM_DATA_14")
	)
	(segment
		(start 176.726088 -56.6293)
		(end 176.726088 -56.00573)
		(width 0.127)
		(layer "In2.Cu")
		(net "XM_DATA_14")
	)
	(segment
		(start 174.694088 -56.6293)
		(end 174.694088 -56.00573)
		(width 0.127)
		(layer "In2.Cu")
		(net "XM_DATA_14")
	)
	(segment
		(start 170.122088 -56.6293)
		(end 169.995088 -56.7563)
		(width 0.127)
		(layer "In2.Cu")
		(net "XM_DATA_14")
	)
	(segment
		(start 169.487088 -55.87873)
		(end 164.537644 -55.87873)
		(width 0.127)
		(layer "In2.Cu")
		(net "XM_DATA_14")
	)
	(segment
		(start 171.138088 -56.6293)
		(end 171.011088 -56.7563)
		(width 0.127)
		(layer "In2.Cu")
		(net "XM_DATA_14")
	)
	(segment
		(start 173.551088 -55.87873)
		(end 173.297088 -55.87873)
		(width 0.127)
		(layer "In2.Cu")
		(net "XM_DATA_14")
	)
	(segment
		(start 172.535088 -55.87873)
		(end 172.281088 -55.87873)
		(width 0.127)
		(layer "In2.Cu")
		(net "XM_DATA_14")
	)
	(segment
		(start 177.869088 -56.7563)
		(end 177.742088 -56.6293)
		(width 0.127)
		(layer "In2.Cu")
		(net "XM_DATA_14")
	)
	(segment
		(start 175.583088 -55.87873)
		(end 175.329088 -55.87873)
		(width 0.127)
		(layer "In2.Cu")
		(net "XM_DATA_14")
	)
	(segment
		(start 176.726088 -56.00573)
		(end 176.599088 -55.87873)
		(width 0.127)
		(layer "In2.Cu")
		(net "XM_DATA_14")
	)
	(segment
		(start 177.234088 -56.00573)
		(end 177.234088 -56.6293)
		(width 0.127)
		(layer "In2.Cu")
		(net "XM_DATA_14")
	)
	(segment
		(start 171.519088 -55.87873)
		(end 171.265088 -55.87873)
		(width 0.127)
		(layer "In2.Cu")
		(net "XM_DATA_14")
	)
	(segment
		(start 172.154088 -56.00573)
		(end 172.154088 -56.6293)
		(width 0.127)
		(layer "In2.Cu")
		(net "XM_DATA_14")
	)
	(segment
		(start 171.138088 -56.00573)
		(end 171.138088 -56.6293)
		(width 0.127)
		(layer "In2.Cu")
		(net "XM_DATA_14")
	)
	(segment
		(start 175.202088 -56.6293)
		(end 175.075088 -56.7563)
		(width 0.127)
		(layer "In2.Cu")
		(net "XM_DATA_14")
	)
	(segment
		(start 174.186088 -56.00573)
		(end 174.186088 -56.6293)
		(width 0.127)
		(layer "In2.Cu")
		(net "XM_DATA_14")
	)
	(segment
		(start 176.218088 -56.6293)
		(end 176.091088 -56.7563)
		(width 0.127)
		(layer "In2.Cu")
		(net "XM_DATA_14")
	)
	(segment
		(start 178.250088 -56.6293)
		(end 178.123088 -56.7563)
		(width 0.127)
		(layer "In2.Cu")
		(net "XM_DATA_14")
	)
	(segment
		(start 177.107088 -56.7563)
		(end 176.853088 -56.7563)
		(width 0.127)
		(layer "In2.Cu")
		(net "XM_DATA_14")
	)
	(segment
		(start 172.662088 -56.6293)
		(end 172.662088 -56.00573)
		(width 0.127)
		(layer "In2.Cu")
		(net "XM_DATA_14")
	)
	(segment
		(start 180.106066 -58.309256)
		(end 181.190646 -58.309256)
		(width 0.127)
		(layer "F.Cu")
		(net "XM_DATA_13")
	)
	(segment
		(start 181.190646 -58.309256)
		(end 181.200044 -58.299858)
		(width 0.127)
		(layer "F.Cu")
		(net "XM_DATA_13")
	)
	(via
		(at 180.106066 -58.309256)
		(size 0.508)
		(drill 0.254)
		(layers "F.Cu" "B.Cu")
		(net "XM_DATA_13")
	)
	(via
		(at 162.6616 -55.2704)
		(size 0.508)
		(drill 0.254)
		(layers "F.Cu" "B.Cu")
		(net "XM_DATA_13")
	)
	(segment
		(start 162.49396 -55.10276)
		(end 162.49396 -53.6575)
		(width 0.127)
		(layer "B.Cu")
		(net "XM_DATA_13")
	)
	(segment
		(start 162.6616 -55.2704)
		(end 162.49396 -55.10276)
		(width 0.127)
		(layer "B.Cu")
		(net "XM_DATA_13")
	)
	(segment
		(start 163.210748 -55.2704)
		(end 162.6616 -55.2704)
		(width 0.127)
		(layer "In2.Cu")
		(net "XM_DATA_13")
	)
	(segment
		(start 172.183298 -58.1787)
		(end 172.056298 -58.3057)
		(width 0.127)
		(layer "In2.Cu")
		(net "XM_DATA_13")
	)
	(segment
		(start 173.072298 -58.3057)
		(end 172.818298 -58.3057)
		(width 0.127)
		(layer "In2.Cu")
		(net "XM_DATA_13")
	)
	(segment
		(start 170.278298 -57.2643)
		(end 170.151298 -57.3913)
		(width 0.127)
		(layer "In2.Cu")
		(net "XM_DATA_13")
	)
	(segment
		(start 171.548298 -57.2643)
		(end 171.294298 -57.2643)
		(width 0.127)
		(layer "In2.Cu")
		(net "XM_DATA_13")
	)
	(segment
		(start 173.199298 -57.3913)
		(end 173.199298 -58.1787)
		(width 0.127)
		(layer "In2.Cu")
		(net "XM_DATA_13")
	)
	(segment
		(start 171.167298 -58.1787)
		(end 171.040298 -58.3057)
		(width 0.127)
		(layer "In2.Cu")
		(net "XM_DATA_13")
	)
	(segment
		(start 165.910514 -57.1373)
		(end 165.783514 -57.2643)
		(width 0.127)
		(layer "In2.Cu")
		(net "XM_DATA_13")
	)
	(segment
		(start 166.418514 -56.5404)
		(end 166.291514 -56.4134)
		(width 0.127)
		(layer "In2.Cu")
		(net "XM_DATA_13")
	)
	(segment
		(start 167.434514 -57.1373)
		(end 167.434514 -56.5404)
		(width 0.127)
		(layer "In2.Cu")
		(net "XM_DATA_13")
	)
	(segment
		(start 173.580298 -57.2643)
		(end 173.326298 -57.2643)
		(width 0.127)
		(layer "In2.Cu")
		(net "XM_DATA_13")
	)
	(segment
		(start 166.291514 -56.4134)
		(end 166.037514 -56.4134)
		(width 0.127)
		(layer "In2.Cu")
		(net "XM_DATA_13")
	)
	(segment
		(start 166.545514 -57.2643)
		(end 166.418514 -57.1373)
		(width 0.127)
		(layer "In2.Cu")
		(net "XM_DATA_13")
	)
	(segment
		(start 170.151298 -58.1787)
		(end 170.024298 -58.3057)
		(width 0.127)
		(layer "In2.Cu")
		(net "XM_DATA_13")
	)
	(segment
		(start 165.3159 -56.51373)
		(end 165.1889 -56.38673)
		(width 0.127)
		(layer "In2.Cu")
		(net "XM_DATA_13")
	)
	(segment
		(start 180.3654 -57.434734)
		(end 179.979066 -57.0484)
		(width 0.127)
		(layer "In2.Cu")
		(net "XM_DATA_13")
	)
	(segment
		(start 165.783514 -57.2643)
		(end 165.4429 -57.2643)
		(width 0.127)
		(layer "In2.Cu")
		(net "XM_DATA_13")
	)
	(segment
		(start 174.215298 -58.1787)
		(end 174.088298 -58.3057)
		(width 0.127)
		(layer "In2.Cu")
		(net "XM_DATA_13")
	)
	(segment
		(start 165.4429 -57.2643)
		(end 165.3159 -57.1373)
		(width 0.127)
		(layer "In2.Cu")
		(net "XM_DATA_13")
	)
	(segment
		(start 178.549554 -57.0484)
		(end 178.333654 -57.2643)
		(width 0.127)
		(layer "In2.Cu")
		(net "XM_DATA_13")
	)
	(segment
		(start 171.294298 -57.2643)
		(end 171.167298 -57.3913)
		(width 0.127)
		(layer "In2.Cu")
		(net "XM_DATA_13")
	)
	(segment
		(start 165.3159 -57.1373)
		(end 165.3159 -56.51373)
		(width 0.127)
		(layer "In2.Cu")
		(net "XM_DATA_13")
	)
	(segment
		(start 173.707298 -58.1787)
		(end 173.707298 -57.3913)
		(width 0.127)
		(layer "In2.Cu")
		(net "XM_DATA_13")
	)
	(segment
		(start 167.434514 -56.5404)
		(end 167.307514 -56.4134)
		(width 0.127)
		(layer "In2.Cu")
		(net "XM_DATA_13")
	)
	(segment
		(start 171.675298 -58.1787)
		(end 171.675298 -57.3913)
		(width 0.127)
		(layer "In2.Cu")
		(net "XM_DATA_13")
	)
	(segment
		(start 166.926514 -57.1373)
		(end 166.799514 -57.2643)
		(width 0.127)
		(layer "In2.Cu")
		(net "XM_DATA_13")
	)
	(segment
		(start 172.818298 -58.3057)
		(end 172.691298 -58.1787)
		(width 0.127)
		(layer "In2.Cu")
		(net "XM_DATA_13")
	)
	(segment
		(start 167.561514 -57.2643)
		(end 167.434514 -57.1373)
		(width 0.127)
		(layer "In2.Cu")
		(net "XM_DATA_13")
	)
	(segment
		(start 178.333654 -57.2643)
		(end 174.342298 -57.2643)
		(width 0.127)
		(layer "In2.Cu")
		(net "XM_DATA_13")
	)
	(segment
		(start 164.327078 -56.38673)
		(end 163.210748 -55.2704)
		(width 0.127)
		(layer "In2.Cu")
		(net "XM_DATA_13")
	)
	(segment
		(start 172.564298 -57.2643)
		(end 172.310298 -57.2643)
		(width 0.127)
		(layer "In2.Cu")
		(net "XM_DATA_13")
	)
	(segment
		(start 173.834298 -58.3057)
		(end 173.707298 -58.1787)
		(width 0.127)
		(layer "In2.Cu")
		(net "XM_DATA_13")
	)
	(segment
		(start 171.040298 -58.3057)
		(end 170.786298 -58.3057)
		(width 0.127)
		(layer "In2.Cu")
		(net "XM_DATA_13")
	)
	(segment
		(start 167.307514 -56.4134)
		(end 167.053514 -56.4134)
		(width 0.127)
		(layer "In2.Cu")
		(net "XM_DATA_13")
	)
	(segment
		(start 168.069514 -56.4134)
		(end 167.942514 -56.5404)
		(width 0.127)
		(layer "In2.Cu")
		(net "XM_DATA_13")
	)
	(segment
		(start 168.450514 -57.1373)
		(end 168.450514 -56.5404)
		(width 0.127)
		(layer "In2.Cu")
		(net "XM_DATA_13")
	)
	(segment
		(start 169.770298 -58.3057)
		(end 169.643298 -58.1787)
		(width 0.127)
		(layer "In2.Cu")
		(net "XM_DATA_13")
	)
	(segment
		(start 171.802298 -58.3057)
		(end 171.675298 -58.1787)
		(width 0.127)
		(layer "In2.Cu")
		(net "XM_DATA_13")
	)
	(segment
		(start 173.326298 -57.2643)
		(end 173.199298 -57.3913)
		(width 0.127)
		(layer "In2.Cu")
		(net "XM_DATA_13")
	)
	(segment
		(start 167.053514 -56.4134)
		(end 166.926514 -56.5404)
		(width 0.127)
		(layer "In2.Cu")
		(net "XM_DATA_13")
	)
	(segment
		(start 170.659298 -57.3913)
		(end 170.532298 -57.2643)
		(width 0.127)
		(layer "In2.Cu")
		(net "XM_DATA_13")
	)
	(segment
		(start 165.1889 -56.38673)
		(end 164.327078 -56.38673)
		(width 0.127)
		(layer "In2.Cu")
		(net "XM_DATA_13")
	)
	(segment
		(start 171.675298 -57.3913)
		(end 171.548298 -57.2643)
		(width 0.127)
		(layer "In2.Cu")
		(net "XM_DATA_13")
	)
	(segment
		(start 172.691298 -58.1787)
		(end 172.691298 -57.3913)
		(width 0.127)
		(layer "In2.Cu")
		(net "XM_DATA_13")
	)
	(segment
		(start 165.910514 -56.5404)
		(end 165.910514 -57.1373)
		(width 0.127)
		(layer "In2.Cu")
		(net "XM_DATA_13")
	)
	(segment
		(start 167.942514 -57.1373)
		(end 167.815514 -57.2643)
		(width 0.127)
		(layer "In2.Cu")
		(net "XM_DATA_13")
	)
	(segment
		(start 170.151298 -57.3913)
		(end 170.151298 -58.1787)
		(width 0.127)
		(layer "In2.Cu")
		(net "XM_DATA_13")
	)
	(segment
		(start 179.979066 -57.0484)
		(end 178.549554 -57.0484)
		(width 0.127)
		(layer "In2.Cu")
		(net "XM_DATA_13")
	)
	(segment
		(start 170.532298 -57.2643)
		(end 170.278298 -57.2643)
		(width 0.127)
		(layer "In2.Cu")
		(net "XM_DATA_13")
	)
	(segment
		(start 169.643298 -57.3913)
		(end 169.516298 -57.2643)
		(width 0.127)
		(layer "In2.Cu")
		(net "XM_DATA_13")
	)
	(segment
		(start 174.215298 -57.3913)
		(end 174.215298 -58.1787)
		(width 0.127)
		(layer "In2.Cu")
		(net "XM_DATA_13")
	)
	(segment
		(start 173.199298 -58.1787)
		(end 173.072298 -58.3057)
		(width 0.127)
		(layer "In2.Cu")
		(net "XM_DATA_13")
	)
	(segment
		(start 171.167298 -57.3913)
		(end 171.167298 -58.1787)
		(width 0.127)
		(layer "In2.Cu")
		(net "XM_DATA_13")
	)
	(segment
		(start 166.418514 -57.1373)
		(end 166.418514 -56.5404)
		(width 0.127)
		(layer "In2.Cu")
		(net "XM_DATA_13")
	)
	(segment
		(start 166.037514 -56.4134)
		(end 165.910514 -56.5404)
		(width 0.127)
		(layer "In2.Cu")
		(net "XM_DATA_13")
	)
	(segment
		(start 170.659298 -58.1787)
		(end 170.659298 -57.3913)
		(width 0.127)
		(layer "In2.Cu")
		(net "XM_DATA_13")
	)
	(segment
		(start 167.942514 -56.5404)
		(end 167.942514 -57.1373)
		(width 0.127)
		(layer "In2.Cu")
		(net "XM_DATA_13")
	)
	(segment
		(start 170.024298 -58.3057)
		(end 169.770298 -58.3057)
		(width 0.127)
		(layer "In2.Cu")
		(net "XM_DATA_13")
	)
	(segment
		(start 174.342298 -57.2643)
		(end 174.215298 -57.3913)
		(width 0.127)
		(layer "In2.Cu")
		(net "XM_DATA_13")
	)
	(segment
		(start 166.926514 -56.5404)
		(end 166.926514 -57.1373)
		(width 0.127)
		(layer "In2.Cu")
		(net "XM_DATA_13")
	)
	(segment
		(start 180.3654 -58.049922)
		(end 180.3654 -57.434734)
		(width 0.127)
		(layer "In2.Cu")
		(net "XM_DATA_13")
	)
	(segment
		(start 168.450514 -56.5404)
		(end 168.323514 -56.4134)
		(width 0.127)
		(layer "In2.Cu")
		(net "XM_DATA_13")
	)
	(segment
		(start 169.643298 -58.1787)
		(end 169.643298 -57.3913)
		(width 0.127)
		(layer "In2.Cu")
		(net "XM_DATA_13")
	)
	(segment
		(start 168.577514 -57.2643)
		(end 168.450514 -57.1373)
		(width 0.127)
		(layer "In2.Cu")
		(net "XM_DATA_13")
	)
	(segment
		(start 170.786298 -58.3057)
		(end 170.659298 -58.1787)
		(width 0.127)
		(layer "In2.Cu")
		(net "XM_DATA_13")
	)
	(segment
		(start 169.516298 -57.2643)
		(end 168.577514 -57.2643)
		(width 0.127)
		(layer "In2.Cu")
		(net "XM_DATA_13")
	)
	(segment
		(start 174.088298 -58.3057)
		(end 173.834298 -58.3057)
		(width 0.127)
		(layer "In2.Cu")
		(net "XM_DATA_13")
	)
	(segment
		(start 172.310298 -57.2643)
		(end 172.183298 -57.3913)
		(width 0.127)
		(layer "In2.Cu")
		(net "XM_DATA_13")
	)
	(segment
		(start 172.183298 -57.3913)
		(end 172.183298 -58.1787)
		(width 0.127)
		(layer "In2.Cu")
		(net "XM_DATA_13")
	)
	(segment
		(start 180.106066 -58.309256)
		(end 180.3654 -58.049922)
		(width 0.127)
		(layer "In2.Cu")
		(net "XM_DATA_13")
	)
	(segment
		(start 167.815514 -57.2643)
		(end 167.561514 -57.2643)
		(width 0.127)
		(layer "In2.Cu")
		(net "XM_DATA_13")
	)
	(segment
		(start 172.056298 -58.3057)
		(end 171.802298 -58.3057)
		(width 0.127)
		(layer "In2.Cu")
		(net "XM_DATA_13")
	)
	(segment
		(start 172.691298 -57.3913)
		(end 172.564298 -57.2643)
		(width 0.127)
		(layer "In2.Cu")
		(net "XM_DATA_13")
	)
	(segment
		(start 168.323514 -56.4134)
		(end 168.069514 -56.4134)
		(width 0.127)
		(layer "In2.Cu")
		(net "XM_DATA_13")
	)
	(segment
		(start 166.799514 -57.2643)
		(end 166.545514 -57.2643)
		(width 0.127)
		(layer "In2.Cu")
		(net "XM_DATA_13")
	)
	(segment
		(start 173.707298 -57.3913)
		(end 173.580298 -57.2643)
		(width 0.127)
		(layer "In2.Cu")
		(net "XM_DATA_13")
	)
	(segment
		(start 182.79999 -59.900058)
		(end 182.400194 -60.299854)
		(width 0.127)
		(layer "F.Cu")
		(net "XM_DATA_12")
	)
	(via
		(at 182.400194 -60.299854)
		(size 0.508)
		(drill 0.254)
		(layers "F.Cu" "B.Cu")
		(net "XM_DATA_12")
	)
	(segment
		(start 167.628062 -60.757562)
		(end 167.44823 -60.757816)
		(width 0.127)
		(layer "B.Cu")
		(net "XM_DATA_12")
	)
	(segment
		(start 177.487072 -63.67272)
		(end 177.487072 -63.672466)
		(width 0.127)
		(layer "B.Cu")
		(net "XM_DATA_12")
	)
	(segment
		(start 181.54523 -62.5475)
		(end 181.796944 -62.295786)
		(width 0.127)
		(layer "B.Cu")
		(net "XM_DATA_12")
	)
	(segment
		(start 181.796944 -62.295786)
		(end 182.011828 -62.295786)
		(width 0.127)
		(layer "B.Cu")
		(net "XM_DATA_12")
	)
	(segment
		(start 163.49472 -55.613554)
		(end 170.36669 -62.485524)
		(width 0.127)
		(layer "B.Cu")
		(net "XM_DATA_12")
	)
	(segment
		(start 182.011828 -62.295786)
		(end 182.687214 -62.295786)
		(width 0.0889)
		(layer "B.Cu")
		(net "XM_DATA_12")
	)
	(segment
		(start 182.800244 -62.182756)
		(end 182.800244 -60.699904)
		(width 0.0889)
		(layer "B.Cu")
		(net "XM_DATA_12")
	)
	(segment
		(start 182.687214 -62.295786)
		(end 182.800244 -62.182756)
		(width 0.0889)
		(layer "B.Cu")
		(net "XM_DATA_12")
	)
	(segment
		(start 169.8498 -63.881)
		(end 177.278792 -63.881)
		(width 0.127)
		(layer "B.Cu")
		(net "XM_DATA_12")
	)
	(segment
		(start 177.278792 -63.881)
		(end 177.487072 -63.67272)
		(width 0.127)
		(layer "B.Cu")
		(net "XM_DATA_12")
	)
	(segment
		(start 167.17772 -61.20892)
		(end 169.8498 -63.881)
		(width 0.127)
		(layer "B.Cu")
		(net "XM_DATA_12")
	)
	(segment
		(start 170.36669 -62.665102)
		(end 170.041062 -62.99073)
		(width 0.127)
		(layer "B.Cu")
		(net "XM_DATA_12")
	)
	(segment
		(start 169.86123 -62.99073)
		(end 167.628062 -60.757562)
		(width 0.127)
		(layer "B.Cu")
		(net "XM_DATA_12")
	)
	(segment
		(start 179.412646 -62.5475)
		(end 181.54523 -62.5475)
		(width 0.127)
		(layer "B.Cu")
		(net "XM_DATA_12")
	)
	(segment
		(start 167.177466 -61.029088)
		(end 167.17772 -61.20892)
		(width 0.127)
		(layer "B.Cu")
		(net "XM_DATA_12")
	)
	(segment
		(start 182.800244 -60.699904)
		(end 182.400194 -60.299854)
		(width 0.0889)
		(layer "B.Cu")
		(net "XM_DATA_12")
	)
	(segment
		(start 163.49472 -53.6575)
		(end 163.49472 -55.613554)
		(width 0.127)
		(layer "B.Cu")
		(net "XM_DATA_12")
	)
	(segment
		(start 177.986182 -63.173356)
		(end 178.78679 -63.173356)
		(width 0.127)
		(layer "B.Cu")
		(net "XM_DATA_12")
	)
	(segment
		(start 170.36669 -62.485524)
		(end 170.36669 -62.665102)
		(width 0.127)
		(layer "B.Cu")
		(net "XM_DATA_12")
	)
	(segment
		(start 167.44823 -60.757816)
		(end 167.177466 -61.029088)
		(width 0.127)
		(layer "B.Cu")
		(net "XM_DATA_12")
	)
	(segment
		(start 177.487072 -63.672466)
		(end 177.986182 -63.173356)
		(width 0.127)
		(layer "B.Cu")
		(net "XM_DATA_12")
	)
	(segment
		(start 178.78679 -63.173356)
		(end 179.412646 -62.5475)
		(width 0.127)
		(layer "B.Cu")
		(net "XM_DATA_12")
	)
	(segment
		(start 170.041062 -62.99073)
		(end 169.86123 -62.99073)
		(width 0.127)
		(layer "B.Cu")
		(net "XM_DATA_12")
	)
	(segment
		(start 181.99989 -52.803552)
		(end 181.99989 -53.50002)
		(width 0.127)
		(layer "F.Cu")
		(net "XM_DATA_11")
	)
	(segment
		(start 181.893464 -52.697126)
		(end 181.99989 -52.803552)
		(width 0.127)
		(layer "F.Cu")
		(net "XM_DATA_11")
	)
	(via
		(at 181.893464 -52.697126)
		(size 0.508)
		(drill 0.254)
		(layers "F.Cu" "B.Cu")
		(net "XM_DATA_11")
	)
	(segment
		(start 179.53609 -53.092858)
		(end 180.054758 -52.57419)
		(width 0.127)
		(layer "B.Cu")
		(net "XM_DATA_11")
	)
	(segment
		(start 174.154592 -48.32858)
		(end 174.027592 -48.45558)
		(width 0.127)
		(layer "B.Cu")
		(net "XM_DATA_11")
	)
	(segment
		(start 166.470076 -50.9397)
		(end 166.37 -50.9397)
		(width 0.127)
		(layer "B.Cu")
		(net "XM_DATA_11")
	)
	(segment
		(start 166.810436 -50.59934)
		(end 166.470076 -50.9397)
		(width 0.127)
		(layer "B.Cu")
		(net "XM_DATA_11")
	)
	(segment
		(start 181.978554 -53.467)
		(end 181.1274 -53.467)
		(width 0.127)
		(layer "B.Cu")
		(net "XM_DATA_11")
	)
	(segment
		(start 175.98898 -48.32858)
		(end 174.154592 -48.32858)
		(width 0.127)
		(layer "B.Cu")
		(net "XM_DATA_11")
	)
	(segment
		(start 181.893464 -52.697126)
		(end 182.124858 -52.92852)
		(width 0.127)
		(layer "B.Cu")
		(net "XM_DATA_11")
	)
	(segment
		(start 181.1274 -53.467)
		(end 180.594 -52.9336)
		(width 0.127)
		(layer "B.Cu")
		(net "XM_DATA_11")
	)
	(segment
		(start 167.570658 -50.59934)
		(end 166.810436 -50.59934)
		(width 0.127)
		(layer "B.Cu")
		(net "XM_DATA_11")
	)
	(segment
		(start 180.594 -52.9336)
		(end 180.414168 -52.9336)
		(width 0.127)
		(layer "B.Cu")
		(net "XM_DATA_11")
	)
	(segment
		(start 172.884592 -48.32858)
		(end 169.841418 -48.32858)
		(width 0.127)
		(layer "B.Cu")
		(net "XM_DATA_11")
	)
	(segment
		(start 182.124858 -52.92852)
		(end 182.124858 -53.320696)
		(width 0.127)
		(layer "B.Cu")
		(net "XM_DATA_11")
	)
	(segment
		(start 179.53609 -53.27269)
		(end 179.53609 -53.092858)
		(width 0.127)
		(layer "B.Cu")
		(net "XM_DATA_11")
	)
	(segment
		(start 174.027592 -48.70958)
		(end 174.154592 -48.83658)
		(width 0.127)
		(layer "B.Cu")
		(net "XM_DATA_11")
	)
	(segment
		(start 178.00955 -51.56835)
		(end 177.781204 -51.56835)
		(width 0.127)
		(layer "B.Cu")
		(net "XM_DATA_11")
	)
	(segment
		(start 174.027592 -48.45558)
		(end 174.027592 -48.70958)
		(width 0.127)
		(layer "B.Cu")
		(net "XM_DATA_11")
	)
	(segment
		(start 169.841418 -48.32858)
		(end 167.570658 -50.59934)
		(width 0.127)
		(layer "B.Cu")
		(net "XM_DATA_11")
	)
	(segment
		(start 175.768 -48.83658)
		(end 178.13655 -51.20513)
		(width 0.127)
		(layer "B.Cu")
		(net "XM_DATA_11")
	)
	(segment
		(start 179.8955 -53.452268)
		(end 179.715668 -53.452268)
		(width 0.127)
		(layer "B.Cu")
		(net "XM_DATA_11")
	)
	(segment
		(start 178.13655 -51.20513)
		(end 178.13655 -51.44135)
		(width 0.127)
		(layer "B.Cu")
		(net "XM_DATA_11")
	)
	(segment
		(start 180.414168 -52.9336)
		(end 179.8955 -53.452268)
		(width 0.127)
		(layer "B.Cu")
		(net "XM_DATA_11")
	)
	(segment
		(start 179.715668 -53.452268)
		(end 179.53609 -53.27269)
		(width 0.127)
		(layer "B.Cu")
		(net "XM_DATA_11")
	)
	(segment
		(start 173.900592 -49.34458)
		(end 172.884592 -48.32858)
		(width 0.127)
		(layer "B.Cu")
		(net "XM_DATA_11")
	)
	(segment
		(start 177.781204 -51.56835)
		(end 175.557434 -49.34458)
		(width 0.127)
		(layer "B.Cu")
		(net "XM_DATA_11")
	)
	(segment
		(start 180.054758 -52.394358)
		(end 175.98898 -48.32858)
		(width 0.127)
		(layer "B.Cu")
		(net "XM_DATA_11")
	)
	(segment
		(start 174.154592 -48.83658)
		(end 175.768 -48.83658)
		(width 0.127)
		(layer "B.Cu")
		(net "XM_DATA_11")
	)
	(segment
		(start 166.37 -50.9397)
		(end 164.99459 -52.31511)
		(width 0.127)
		(layer "B.Cu")
		(net "XM_DATA_11")
	)
	(segment
		(start 175.557434 -49.34458)
		(end 173.900592 -49.34458)
		(width 0.127)
		(layer "B.Cu")
		(net "XM_DATA_11")
	)
	(segment
		(start 180.054758 -52.57419)
		(end 180.054758 -52.394358)
		(width 0.127)
		(layer "B.Cu")
		(net "XM_DATA_11")
	)
	(segment
		(start 178.13655 -51.44135)
		(end 178.00955 -51.56835)
		(width 0.127)
		(layer "B.Cu")
		(net "XM_DATA_11")
	)
	(segment
		(start 182.124858 -53.320696)
		(end 181.978554 -53.467)
		(width 0.127)
		(layer "B.Cu")
		(net "XM_DATA_11")
	)
	(segment
		(start 164.99459 -52.31511)
		(end 164.99459 -53.6575)
		(width 0.127)
		(layer "B.Cu")
		(net "XM_DATA_11")
	)
	(segment
		(start 185.200036 -55.099966)
		(end 184.80024 -54.70017)
		(width 0.127)
		(layer "F.Cu")
		(net "XM_DATA_10")
	)
	(via
		(at 184.80024 -54.70017)
		(size 0.508)
		(drill 0.254)
		(layers "F.Cu" "B.Cu")
		(net "XM_DATA_10")
	)
	(segment
		(start 178.701954 -53.207666)
		(end 178.9557 -53.461412)
		(width 0.127)
		(layer "B.Cu")
		(net "XM_DATA_10")
	)
	(segment
		(start 172.674026 -48.83658)
		(end 173.690026 -49.85258)
		(width 0.127)
		(layer "B.Cu")
		(net "XM_DATA_10")
	)
	(segment
		(start 177.264314 -51.770026)
		(end 177.443892 -51.949604)
		(width 0.127)
		(layer "B.Cu")
		(net "XM_DATA_10")
	)
	(segment
		(start 176.03851 -52.27701)
		(end 176.218088 -52.456588)
		(width 0.127)
		(layer "B.Cu")
		(net "XM_DATA_10")
	)
	(segment
		(start 175.46955 -49.975262)
		(end 175.46955 -50.155094)
		(width 0.127)
		(layer "B.Cu")
		(net "XM_DATA_10")
	)
	(segment
		(start 177.47615 -53.534818)
		(end 177.47615 -53.71465)
		(width 0.127)
		(layer "B.Cu")
		(net "XM_DATA_10")
	)
	(segment
		(start 178.477418 -52.53355)
		(end 177.47615 -53.534818)
		(width 0.127)
		(layer "B.Cu")
		(net "XM_DATA_10")
	)
	(segment
		(start 175.46955 -50.155094)
		(end 175.132238 -50.492406)
		(width 0.127)
		(layer "B.Cu")
		(net "XM_DATA_10")
	)
	(segment
		(start 177.47615 -53.71465)
		(end 177.655728 -53.894228)
		(width 0.127)
		(layer "B.Cu")
		(net "XM_DATA_10")
	)
	(segment
		(start 175.346868 -49.85258)
		(end 175.46955 -49.975262)
		(width 0.127)
		(layer "B.Cu")
		(net "XM_DATA_10")
	)
	(segment
		(start 178.9557 -53.983636)
		(end 179.277264 -54.3052)
		(width 0.127)
		(layer "B.Cu")
		(net "XM_DATA_10")
	)
	(segment
		(start 176.725072 -51.410616)
		(end 176.03851 -52.097178)
		(width 0.127)
		(layer "B.Cu")
		(net "XM_DATA_10")
	)
	(segment
		(start 176.218088 -52.456588)
		(end 176.39792 -52.456588)
		(width 0.127)
		(layer "B.Cu")
		(net "XM_DATA_10")
	)
	(segment
		(start 177.655728 -53.894228)
		(end 177.83556 -53.894228)
		(width 0.127)
		(layer "B.Cu")
		(net "XM_DATA_10")
	)
	(segment
		(start 175.311816 -50.851816)
		(end 175.491648 -50.851816)
		(width 0.127)
		(layer "B.Cu")
		(net "XM_DATA_10")
	)
	(segment
		(start 178.118008 -52.17414)
		(end 178.29784 -52.17414)
		(width 0.127)
		(layer "B.Cu")
		(net "XM_DATA_10")
	)
	(segment
		(start 176.03851 -52.097178)
		(end 176.03851 -52.27701)
		(width 0.127)
		(layer "B.Cu")
		(net "XM_DATA_10")
	)
	(segment
		(start 176.44999 -53.842158)
		(end 178.118008 -52.17414)
		(width 0.127)
		(layer "B.Cu")
		(net "XM_DATA_10")
	)
	(segment
		(start 176.09058 -53.66258)
		(end 176.270158 -53.842158)
		(width 0.127)
		(layer "B.Cu")
		(net "XM_DATA_10")
	)
	(segment
		(start 165.99408 -52.134262)
		(end 167.021002 -51.10734)
		(width 0.127)
		(layer "B.Cu")
		(net "XM_DATA_10")
	)
	(segment
		(start 175.491648 -50.851816)
		(end 175.82896 -50.514504)
		(width 0.127)
		(layer "B.Cu")
		(net "XM_DATA_10")
	)
	(segment
		(start 173.690026 -49.85258)
		(end 175.346868 -49.85258)
		(width 0.127)
		(layer "B.Cu")
		(net "XM_DATA_10")
	)
	(segment
		(start 176.725072 -51.230784)
		(end 176.725072 -51.410616)
		(width 0.127)
		(layer "B.Cu")
		(net "XM_DATA_10")
	)
	(segment
		(start 176.270158 -53.842158)
		(end 176.44999 -53.842158)
		(width 0.127)
		(layer "B.Cu")
		(net "XM_DATA_10")
	)
	(segment
		(start 184.16397 -54.0639)
		(end 184.80024 -54.70017)
		(width 0.127)
		(layer "B.Cu")
		(net "XM_DATA_10")
	)
	(segment
		(start 176.39792 -52.456588)
		(end 177.084482 -51.770026)
		(width 0.127)
		(layer "B.Cu")
		(net "XM_DATA_10")
	)
	(segment
		(start 177.443892 -51.949604)
		(end 177.443892 -52.129436)
		(width 0.127)
		(layer "B.Cu")
		(net "XM_DATA_10")
	)
	(segment
		(start 175.82896 -50.514504)
		(end 176.008792 -50.514504)
		(width 0.127)
		(layer "B.Cu")
		(net "XM_DATA_10")
	)
	(segment
		(start 177.83556 -53.894228)
		(end 178.522122 -53.207666)
		(width 0.127)
		(layer "B.Cu")
		(net "XM_DATA_10")
	)
	(segment
		(start 177.084482 -51.770026)
		(end 177.264314 -51.770026)
		(width 0.127)
		(layer "B.Cu")
		(net "XM_DATA_10")
	)
	(segment
		(start 179.886864 -54.0639)
		(end 184.16397 -54.0639)
		(width 0.127)
		(layer "B.Cu")
		(net "XM_DATA_10")
	)
	(segment
		(start 179.645564 -54.3052)
		(end 179.886864 -54.0639)
		(width 0.127)
		(layer "B.Cu")
		(net "XM_DATA_10")
	)
	(segment
		(start 176.008792 -50.514504)
		(end 176.725072 -51.230784)
		(width 0.127)
		(layer "B.Cu")
		(net "XM_DATA_10")
	)
	(segment
		(start 179.277264 -54.3052)
		(end 179.645564 -54.3052)
		(width 0.127)
		(layer "B.Cu")
		(net "XM_DATA_10")
	)
	(segment
		(start 165.99408 -53.6575)
		(end 165.99408 -52.134262)
		(width 0.127)
		(layer "B.Cu")
		(net "XM_DATA_10")
	)
	(segment
		(start 176.09058 -53.482748)
		(end 176.09058 -53.66258)
		(width 0.127)
		(layer "B.Cu")
		(net "XM_DATA_10")
	)
	(segment
		(start 178.522122 -53.207666)
		(end 178.701954 -53.207666)
		(width 0.127)
		(layer "B.Cu")
		(net "XM_DATA_10")
	)
	(segment
		(start 177.443892 -52.129436)
		(end 176.09058 -53.482748)
		(width 0.127)
		(layer "B.Cu")
		(net "XM_DATA_10")
	)
	(segment
		(start 167.781224 -51.10734)
		(end 170.051984 -48.83658)
		(width 0.127)
		(layer "B.Cu")
		(net "XM_DATA_10")
	)
	(segment
		(start 178.9557 -53.461412)
		(end 178.9557 -53.983636)
		(width 0.127)
		(layer "B.Cu")
		(net "XM_DATA_10")
	)
	(segment
		(start 178.477418 -52.353718)
		(end 178.477418 -52.53355)
		(width 0.127)
		(layer "B.Cu")
		(net "XM_DATA_10")
	)
	(segment
		(start 175.132238 -50.492406)
		(end 175.132238 -50.672238)
		(width 0.127)
		(layer "B.Cu")
		(net "XM_DATA_10")
	)
	(segment
		(start 175.132238 -50.672238)
		(end 175.311816 -50.851816)
		(width 0.127)
		(layer "B.Cu")
		(net "XM_DATA_10")
	)
	(segment
		(start 178.29784 -52.17414)
		(end 178.477418 -52.353718)
		(width 0.127)
		(layer "B.Cu")
		(net "XM_DATA_10")
	)
	(segment
		(start 170.051984 -48.83658)
		(end 172.674026 -48.83658)
		(width 0.127)
		(layer "B.Cu")
		(net "XM_DATA_10")
	)
	(segment
		(start 167.021002 -51.10734)
		(end 167.781224 -51.10734)
		(width 0.127)
		(layer "B.Cu")
		(net "XM_DATA_10")
	)
	(segment
		(start 180.306218 -60.699904)
		(end 181.200044 -60.699904)
		(width 0.127)
		(layer "F.Cu")
		(net "XM_DATA_1")
	)
	(segment
		(start 180.258466 -60.747656)
		(end 180.306218 -60.699904)
		(width 0.127)
		(layer "F.Cu")
		(net "XM_DATA_1")
	)
	(via
		(at 180.258466 -60.747656)
		(size 0.508)
		(drill 0.254)
		(layers "F.Cu" "B.Cu")
		(net "XM_DATA_1")
	)
	(segment
		(start 170.960796 -57.003696)
		(end 170.815 -56.8579)
		(width 0.127)
		(layer "B.Cu")
		(net "XM_DATA_1")
	)
	(segment
		(start 175.151796 -57.8231)
		(end 175.024796 -57.6961)
		(width 0.127)
		(layer "B.Cu")
		(net "XM_DATA_1")
	)
	(segment
		(start 169.479722 -56.1975)
		(end 169.479722 -56.7309)
		(width 0.127)
		(layer "B.Cu")
		(net "XM_DATA_1")
	)
	(segment
		(start 169.202354 -56.8579)
		(end 167.49395 -55.149496)
		(width 0.127)
		(layer "B.Cu")
		(net "XM_DATA_1")
	)
	(segment
		(start 171.468796 -57.0357)
		(end 171.468796 -58.5724)
		(width 0.127)
		(layer "B.Cu")
		(net "XM_DATA_1")
	)
	(segment
		(start 174.008796 -58.5724)
		(end 174.008796 -57.15)
		(width 0.127)
		(layer "B.Cu")
		(net "XM_DATA_1")
	)
	(segment
		(start 176.040796 -57.3786)
		(end 175.913796 -57.2516)
		(width 0.127)
		(layer "B.Cu")
		(net "XM_DATA_1")
	)
	(segment
		(start 179.846986 -60.07862)
		(end 178.391566 -58.6232)
		(width 0.127)
		(layer "B.Cu")
		(net "XM_DATA_1")
	)
	(segment
		(start 180.258466 -60.747656)
		(end 179.846986 -60.336176)
		(width 0.127)
		(layer "B.Cu")
		(net "XM_DATA_1")
	)
	(segment
		(start 173.500796 -58.5724)
		(end 173.373796 -58.6994)
		(width 0.127)
		(layer "B.Cu")
		(net "XM_DATA_1")
	)
	(segment
		(start 172.484796 -58.5724)
		(end 172.357796 -58.6994)
		(width 0.127)
		(layer "B.Cu")
		(net "XM_DATA_1")
	)
	(segment
		(start 176.421796 -58.6994)
		(end 176.167796 -58.6994)
		(width 0.127)
		(layer "B.Cu")
		(net "XM_DATA_1")
	)
	(segment
		(start 178.391566 -58.6232)
		(end 177.2285 -58.6232)
		(width 0.127)
		(layer "B.Cu")
		(net "XM_DATA_1")
	)
	(segment
		(start 176.548796 -58.5724)
		(end 176.421796 -58.6994)
		(width 0.127)
		(layer "B.Cu")
		(net "XM_DATA_1")
	)
	(segment
		(start 175.405796 -57.8231)
		(end 175.151796 -57.8231)
		(width 0.127)
		(layer "B.Cu")
		(net "XM_DATA_1")
	)
	(segment
		(start 176.167796 -58.6994)
		(end 176.040796 -58.5724)
		(width 0.127)
		(layer "B.Cu")
		(net "XM_DATA_1")
	)
	(segment
		(start 177.056796 -57.6199)
		(end 176.929796 -57.4929)
		(width 0.127)
		(layer "B.Cu")
		(net "XM_DATA_1")
	)
	(segment
		(start 169.987722 -56.7309)
		(end 169.987722 -56.1975)
		(width 0.127)
		(layer "B.Cu")
		(net "XM_DATA_1")
	)
	(segment
		(start 173.894496 -57.0357)
		(end 173.615096 -57.0357)
		(width 0.127)
		(layer "B.Cu")
		(net "XM_DATA_1")
	)
	(segment
		(start 174.516796 -58.5724)
		(end 174.389796 -58.6994)
		(width 0.127)
		(layer "B.Cu")
		(net "XM_DATA_1")
	)
	(segment
		(start 179.846986 -60.336176)
		(end 179.846986 -60.07862)
		(width 0.127)
		(layer "B.Cu")
		(net "XM_DATA_1")
	)
	(segment
		(start 171.976796 -57.0357)
		(end 171.849796 -56.9087)
		(width 0.127)
		(layer "B.Cu")
		(net "XM_DATA_1")
	)
	(segment
		(start 174.389796 -58.6994)
		(end 174.135796 -58.6994)
		(width 0.127)
		(layer "B.Cu")
		(net "XM_DATA_1")
	)
	(segment
		(start 173.373796 -58.6994)
		(end 173.119796 -58.6994)
		(width 0.127)
		(layer "B.Cu")
		(net "XM_DATA_1")
	)
	(segment
		(start 169.479722 -56.7309)
		(end 169.352722 -56.8579)
		(width 0.127)
		(layer "B.Cu")
		(net "XM_DATA_1")
	)
	(segment
		(start 171.468796 -58.5724)
		(end 171.341796 -58.6994)
		(width 0.127)
		(layer "B.Cu")
		(net "XM_DATA_1")
	)
	(segment
		(start 175.913796 -57.2516)
		(end 175.659796 -57.2516)
		(width 0.127)
		(layer "B.Cu")
		(net "XM_DATA_1")
	)
	(segment
		(start 172.992796 -58.5724)
		(end 172.992796 -57.0484)
		(width 0.127)
		(layer "B.Cu")
		(net "XM_DATA_1")
	)
	(segment
		(start 167.49395 -55.149496)
		(end 167.49395 -53.6575)
		(width 0.127)
		(layer "B.Cu")
		(net "XM_DATA_1")
	)
	(segment
		(start 172.611796 -56.9214)
		(end 172.484796 -57.0484)
		(width 0.127)
		(layer "B.Cu")
		(net "XM_DATA_1")
	)
	(segment
		(start 175.532796 -57.3786)
		(end 175.532796 -57.6961)
		(width 0.127)
		(layer "B.Cu")
		(net "XM_DATA_1")
	)
	(segment
		(start 172.357796 -58.6994)
		(end 172.103796 -58.6994)
		(width 0.127)
		(layer "B.Cu")
		(net "XM_DATA_1")
	)
	(segment
		(start 169.987722 -56.1975)
		(end 169.860722 -56.0705)
		(width 0.127)
		(layer "B.Cu")
		(net "XM_DATA_1")
	)
	(segment
		(start 176.929796 -57.4929)
		(end 176.675796 -57.4929)
		(width 0.127)
		(layer "B.Cu")
		(net "XM_DATA_1")
	)
	(segment
		(start 172.865796 -56.9214)
		(end 172.611796 -56.9214)
		(width 0.127)
		(layer "B.Cu")
		(net "XM_DATA_1")
	)
	(segment
		(start 175.532796 -57.6961)
		(end 175.405796 -57.8231)
		(width 0.127)
		(layer "B.Cu")
		(net "XM_DATA_1")
	)
	(segment
		(start 170.815 -56.8579)
		(end 170.114722 -56.8579)
		(width 0.127)
		(layer "B.Cu")
		(net "XM_DATA_1")
	)
	(segment
		(start 174.897796 -57.0611)
		(end 174.643796 -57.0611)
		(width 0.127)
		(layer "B.Cu")
		(net "XM_DATA_1")
	)
	(segment
		(start 170.114722 -56.8579)
		(end 169.987722 -56.7309)
		(width 0.127)
		(layer "B.Cu")
		(net "XM_DATA_1")
	)
	(segment
		(start 174.008796 -57.15)
		(end 173.894496 -57.0357)
		(width 0.127)
		(layer "B.Cu")
		(net "XM_DATA_1")
	)
	(segment
		(start 174.643796 -57.0611)
		(end 174.516796 -57.1881)
		(width 0.127)
		(layer "B.Cu")
		(net "XM_DATA_1")
	)
	(segment
		(start 169.606722 -56.0705)
		(end 169.479722 -56.1975)
		(width 0.127)
		(layer "B.Cu")
		(net "XM_DATA_1")
	)
	(segment
		(start 170.960796 -58.5724)
		(end 170.960796 -57.003696)
		(width 0.127)
		(layer "B.Cu")
		(net "XM_DATA_1")
	)
	(segment
		(start 171.595796 -56.9087)
		(end 171.468796 -57.0357)
		(width 0.127)
		(layer "B.Cu")
		(net "XM_DATA_1")
	)
	(segment
		(start 171.849796 -56.9087)
		(end 171.595796 -56.9087)
		(width 0.127)
		(layer "B.Cu")
		(net "XM_DATA_1")
	)
	(segment
		(start 169.860722 -56.0705)
		(end 169.606722 -56.0705)
		(width 0.127)
		(layer "B.Cu")
		(net "XM_DATA_1")
	)
	(segment
		(start 177.2285 -58.6232)
		(end 177.056796 -58.451496)
		(width 0.127)
		(layer "B.Cu")
		(net "XM_DATA_1")
	)
	(segment
		(start 169.352722 -56.8579)
		(end 169.202354 -56.8579)
		(width 0.127)
		(layer "B.Cu")
		(net "XM_DATA_1")
	)
	(segment
		(start 172.484796 -57.0484)
		(end 172.484796 -58.5724)
		(width 0.127)
		(layer "B.Cu")
		(net "XM_DATA_1")
	)
	(segment
		(start 175.659796 -57.2516)
		(end 175.532796 -57.3786)
		(width 0.127)
		(layer "B.Cu")
		(net "XM_DATA_1")
	)
	(segment
		(start 175.024796 -57.1881)
		(end 174.897796 -57.0611)
		(width 0.127)
		(layer "B.Cu")
		(net "XM_DATA_1")
	)
	(segment
		(start 176.675796 -57.4929)
		(end 176.548796 -57.6199)
		(width 0.127)
		(layer "B.Cu")
		(net "XM_DATA_1")
	)
	(segment
		(start 173.500796 -57.15)
		(end 173.500796 -58.5724)
		(width 0.127)
		(layer "B.Cu")
		(net "XM_DATA_1")
	)
	(segment
		(start 171.087796 -58.6994)
		(end 170.960796 -58.5724)
		(width 0.127)
		(layer "B.Cu")
		(net "XM_DATA_1")
	)
	(segment
		(start 171.341796 -58.6994)
		(end 171.087796 -58.6994)
		(width 0.127)
		(layer "B.Cu")
		(net "XM_DATA_1")
	)
	(segment
		(start 171.976796 -58.5724)
		(end 171.976796 -57.0357)
		(width 0.127)
		(layer "B.Cu")
		(net "XM_DATA_1")
	)
	(segment
		(start 174.135796 -58.6994)
		(end 174.008796 -58.5724)
		(width 0.127)
		(layer "B.Cu")
		(net "XM_DATA_1")
	)
	(segment
		(start 173.119796 -58.6994)
		(end 172.992796 -58.5724)
		(width 0.127)
		(layer "B.Cu")
		(net "XM_DATA_1")
	)
	(segment
		(start 173.615096 -57.0357)
		(end 173.500796 -57.15)
		(width 0.127)
		(layer "B.Cu")
		(net "XM_DATA_1")
	)
	(segment
		(start 172.103796 -58.6994)
		(end 171.976796 -58.5724)
		(width 0.127)
		(layer "B.Cu")
		(net "XM_DATA_1")
	)
	(segment
		(start 174.516796 -57.1881)
		(end 174.516796 -58.5724)
		(width 0.127)
		(layer "B.Cu")
		(net "XM_DATA_1")
	)
	(segment
		(start 176.548796 -57.6199)
		(end 176.548796 -58.5724)
		(width 0.127)
		(layer "B.Cu")
		(net "XM_DATA_1")
	)
	(segment
		(start 177.056796 -58.451496)
		(end 177.056796 -57.6199)
		(width 0.127)
		(layer "B.Cu")
		(net "XM_DATA_1")
	)
	(segment
		(start 175.024796 -57.6961)
		(end 175.024796 -57.1881)
		(width 0.127)
		(layer "B.Cu")
		(net "XM_DATA_1")
	)
	(segment
		(start 176.040796 -58.5724)
		(end 176.040796 -57.3786)
		(width 0.127)
		(layer "B.Cu")
		(net "XM_DATA_1")
	)
	(segment
		(start 172.992796 -57.0484)
		(end 172.865796 -56.9214)
		(width 0.127)
		(layer "B.Cu")
		(net "XM_DATA_1")
	)
	(segment
		(start 182.79999 -59.099958)
		(end 182.39994 -59.500008)
		(width 0.127)
		(layer "F.Cu")
		(net "XM_DATA_0")
	)
	(via
		(at 182.39994 -59.500008)
		(size 0.508)
		(drill 0.254)
		(layers "F.Cu" "B.Cu")
		(net "XM_DATA_0")
	)
	(segment
		(start 177.634138 -56.1975)
		(end 177.634138 -56.0197)
		(width 0.127)
		(layer "B.Cu")
		(net "XM_DATA_0")
	)
	(segment
		(start 172.554138 -56.261)
		(end 172.554138 -55.6387)
		(width 0.127)
		(layer "B.Cu")
		(net "XM_DATA_0")
	)
	(segment
		(start 177.634138 -56.0197)
		(end 177.507138 -55.8927)
		(width 0.127)
		(layer "B.Cu")
		(net "XM_DATA_0")
	)
	(segment
		(start 173.570138 -53.6321)
		(end 173.443138 -53.5051)
		(width 0.127)
		(layer "B.Cu")
		(net "XM_DATA_0")
	)
	(segment
		(start 176.618138 -56.8198)
		(end 176.618138 -55.9435)
		(width 0.127)
		(layer "B.Cu")
		(net "XM_DATA_0")
	)
	(segment
		(start 173.951138 -56.5277)
		(end 173.697138 -56.5277)
		(width 0.127)
		(layer "B.Cu")
		(net "XM_DATA_0")
	)
	(segment
		(start 171.411138 -55.3466)
		(end 171.157138 -55.3466)
		(width 0.127)
		(layer "B.Cu")
		(net "XM_DATA_0")
	)
	(segment
		(start 177.507138 -55.8927)
		(end 177.253138 -55.8927)
		(width 0.127)
		(layer "B.Cu")
		(net "XM_DATA_0")
	)
	(segment
		(start 177.126138 -56.0197)
		(end 177.126138 -56.8198)
		(width 0.127)
		(layer "B.Cu")
		(net "XM_DATA_0")
	)
	(segment
		(start 176.999138 -56.9468)
		(end 176.745138 -56.9468)
		(width 0.127)
		(layer "B.Cu")
		(net "XM_DATA_0")
	)
	(segment
		(start 170.903138 -56.2864)
		(end 170.649138 -56.2864)
		(width 0.127)
		(layer "B.Cu")
		(net "XM_DATA_0")
	)
	(segment
		(start 176.110138 -56.6166)
		(end 175.983138 -56.7436)
		(width 0.127)
		(layer "B.Cu")
		(net "XM_DATA_0")
	)
	(segment
		(start 173.062138 -56.261)
		(end 172.935138 -56.388)
		(width 0.127)
		(layer "B.Cu")
		(net "XM_DATA_0")
	)
	(segment
		(start 174.586138 -56.4134)
		(end 174.586138 -54.483)
		(width 0.127)
		(layer "B.Cu")
		(net "XM_DATA_0")
	)
	(segment
		(start 172.935138 -56.388)
		(end 172.681138 -56.388)
		(width 0.127)
		(layer "B.Cu")
		(net "XM_DATA_0")
	)
	(segment
		(start 170.649138 -56.2864)
		(end 170.522138 -56.1594)
		(width 0.127)
		(layer "B.Cu")
		(net "XM_DATA_0")
	)
	(segment
		(start 177.126138 -56.8198)
		(end 176.999138 -56.9468)
		(width 0.127)
		(layer "B.Cu")
		(net "XM_DATA_0")
	)
	(segment
		(start 172.046138 -56.1975)
		(end 171.919138 -56.3245)
		(width 0.127)
		(layer "B.Cu")
		(net "XM_DATA_0")
	)
	(segment
		(start 175.983138 -56.7436)
		(end 175.729138 -56.7436)
		(width 0.127)
		(layer "B.Cu")
		(net "XM_DATA_0")
	)
	(segment
		(start 172.681138 -56.388)
		(end 172.554138 -56.261)
		(width 0.127)
		(layer "B.Cu")
		(net "XM_DATA_0")
	)
	(segment
		(start 175.221138 -55.3466)
		(end 175.094138 -55.4736)
		(width 0.127)
		(layer "B.Cu")
		(net "XM_DATA_0")
	)
	(segment
		(start 169.093388 -55.4736)
		(end 168.49471 -54.874922)
		(width 0.127)
		(layer "B.Cu")
		(net "XM_DATA_0")
	)
	(segment
		(start 176.491138 -55.8165)
		(end 176.237138 -55.8165)
		(width 0.127)
		(layer "B.Cu")
		(net "XM_DATA_0")
	)
	(segment
		(start 175.094138 -56.4134)
		(end 174.967138 -56.5404)
		(width 0.127)
		(layer "B.Cu")
		(net "XM_DATA_0")
	)
	(segment
		(start 174.205138 -54.356)
		(end 174.078138 -54.483)
		(width 0.127)
		(layer "B.Cu")
		(net "XM_DATA_0")
	)
	(segment
		(start 170.522138 -56.1594)
		(end 170.522138 -55.764684)
		(width 0.127)
		(layer "B.Cu")
		(net "XM_DATA_0")
	)
	(segment
		(start 176.237138 -55.8165)
		(end 176.110138 -55.9435)
		(width 0.127)
		(layer "B.Cu")
		(net "XM_DATA_0")
	)
	(segment
		(start 175.729138 -56.7436)
		(end 175.602138 -56.6166)
		(width 0.127)
		(layer "B.Cu")
		(net "XM_DATA_0")
	)
	(segment
		(start 174.713138 -56.5404)
		(end 174.586138 -56.4134)
		(width 0.127)
		(layer "B.Cu")
		(net "XM_DATA_0")
	)
	(segment
		(start 171.157138 -55.3466)
		(end 171.030138 -55.4736)
		(width 0.127)
		(layer "B.Cu")
		(net "XM_DATA_0")
	)
	(segment
		(start 174.459138 -54.356)
		(end 174.205138 -54.356)
		(width 0.127)
		(layer "B.Cu")
		(net "XM_DATA_0")
	)
	(segment
		(start 175.602138 -55.4736)
		(end 175.475138 -55.3466)
		(width 0.127)
		(layer "B.Cu")
		(net "XM_DATA_0")
	)
	(segment
		(start 170.231054 -55.4736)
		(end 169.093388 -55.4736)
		(width 0.127)
		(layer "B.Cu")
		(net "XM_DATA_0")
	)
	(segment
		(start 177.761138 -56.3245)
		(end 177.634138 -56.1975)
		(width 0.127)
		(layer "B.Cu")
		(net "XM_DATA_0")
	)
	(segment
		(start 174.967138 -56.5404)
		(end 174.713138 -56.5404)
		(width 0.127)
		(layer "B.Cu")
		(net "XM_DATA_0")
	)
	(segment
		(start 172.427138 -55.5117)
		(end 172.173138 -55.5117)
		(width 0.127)
		(layer "B.Cu")
		(net "XM_DATA_0")
	)
	(segment
		(start 176.618138 -55.9435)
		(end 176.491138 -55.8165)
		(width 0.127)
		(layer "B.Cu")
		(net "XM_DATA_0")
	)
	(segment
		(start 170.522138 -55.764684)
		(end 170.231054 -55.4736)
		(width 0.127)
		(layer "B.Cu")
		(net "XM_DATA_0")
	)
	(segment
		(start 171.538138 -56.1975)
		(end 171.538138 -55.4736)
		(width 0.127)
		(layer "B.Cu")
		(net "XM_DATA_0")
	)
	(segment
		(start 174.078138 -54.483)
		(end 174.078138 -56.4007)
		(width 0.127)
		(layer "B.Cu")
		(net "XM_DATA_0")
	)
	(segment
		(start 175.094138 -55.4736)
		(end 175.094138 -56.4134)
		(width 0.127)
		(layer "B.Cu")
		(net "XM_DATA_0")
	)
	(segment
		(start 173.189138 -53.5051)
		(end 173.062138 -53.6321)
		(width 0.127)
		(layer "B.Cu")
		(net "XM_DATA_0")
	)
	(segment
		(start 171.030138 -55.4736)
		(end 171.030138 -56.1594)
		(width 0.127)
		(layer "B.Cu")
		(net "XM_DATA_0")
	)
	(segment
		(start 173.062138 -53.6321)
		(end 173.062138 -56.261)
		(width 0.127)
		(layer "B.Cu")
		(net "XM_DATA_0")
	)
	(segment
		(start 175.602138 -56.6166)
		(end 175.602138 -55.4736)
		(width 0.127)
		(layer "B.Cu")
		(net "XM_DATA_0")
	)
	(segment
		(start 182.39994 -59.500008)
		(end 179.224432 -56.3245)
		(width 0.127)
		(layer "B.Cu")
		(net "XM_DATA_0")
	)
	(segment
		(start 171.030138 -56.1594)
		(end 170.903138 -56.2864)
		(width 0.127)
		(layer "B.Cu")
		(net "XM_DATA_0")
	)
	(segment
		(start 171.919138 -56.3245)
		(end 171.665138 -56.3245)
		(width 0.127)
		(layer "B.Cu")
		(net "XM_DATA_0")
	)
	(segment
		(start 176.745138 -56.9468)
		(end 176.618138 -56.8198)
		(width 0.127)
		(layer "B.Cu")
		(net "XM_DATA_0")
	)
	(segment
		(start 174.078138 -56.4007)
		(end 173.951138 -56.5277)
		(width 0.127)
		(layer "B.Cu")
		(net "XM_DATA_0")
	)
	(segment
		(start 174.586138 -54.483)
		(end 174.459138 -54.356)
		(width 0.127)
		(layer "B.Cu")
		(net "XM_DATA_0")
	)
	(segment
		(start 177.253138 -55.8927)
		(end 177.126138 -56.0197)
		(width 0.127)
		(layer "B.Cu")
		(net "XM_DATA_0")
	)
	(segment
		(start 173.697138 -56.5277)
		(end 173.570138 -56.4007)
		(width 0.127)
		(layer "B.Cu")
		(net "XM_DATA_0")
	)
	(segment
		(start 172.046138 -55.6387)
		(end 172.046138 -56.1975)
		(width 0.127)
		(layer "B.Cu")
		(net "XM_DATA_0")
	)
	(segment
		(start 168.49471 -54.874922)
		(end 168.49471 -53.6575)
		(width 0.127)
		(layer "B.Cu")
		(net "XM_DATA_0")
	)
	(segment
		(start 172.554138 -55.6387)
		(end 172.427138 -55.5117)
		(width 0.127)
		(layer "B.Cu")
		(net "XM_DATA_0")
	)
	(segment
		(start 175.475138 -55.3466)
		(end 175.221138 -55.3466)
		(width 0.127)
		(layer "B.Cu")
		(net "XM_DATA_0")
	)
	(segment
		(start 176.110138 -55.9435)
		(end 176.110138 -56.6166)
		(width 0.127)
		(layer "B.Cu")
		(net "XM_DATA_0")
	)
	(segment
		(start 173.570138 -56.4007)
		(end 173.570138 -53.6321)
		(width 0.127)
		(layer "B.Cu")
		(net "XM_DATA_0")
	)
	(segment
		(start 171.538138 -55.4736)
		(end 171.411138 -55.3466)
		(width 0.127)
		(layer "B.Cu")
		(net "XM_DATA_0")
	)
	(segment
		(start 179.224432 -56.3245)
		(end 177.761138 -56.3245)
		(width 0.127)
		(layer "B.Cu")
		(net "XM_DATA_0")
	)
	(segment
		(start 171.665138 -56.3245)
		(end 171.538138 -56.1975)
		(width 0.127)
		(layer "B.Cu")
		(net "XM_DATA_0")
	)
	(segment
		(start 172.173138 -55.5117)
		(end 172.046138 -55.6387)
		(width 0.127)
		(layer "B.Cu")
		(net "XM_DATA_0")
	)
	(segment
		(start 173.443138 -53.5051)
		(end 173.189138 -53.5051)
		(width 0.127)
		(layer "B.Cu")
		(net "XM_DATA_0")
	)
	(segment
		(start 187.97016 -50.89652)
		(end 187.97016 -50.528474)
		(width 0.127)
		(layer "F.Cu")
		(net "XM_CS0_N")
	)
	(segment
		(start 189.6364 -53.936392)
		(end 189.6364 -52.6542)
		(width 0.127)
		(layer "F.Cu")
		(net "XM_CS0_N")
	)
	(segment
		(start 188.6458 -51.6636)
		(end 188.6458 -51.57216)
		(width 0.127)
		(layer "F.Cu")
		(net "XM_CS0_N")
	)
	(segment
		(start 188.6458 -51.57216)
		(end 188.341 -51.26736)
		(width 0.127)
		(layer "F.Cu")
		(net "XM_CS0_N")
	)
	(segment
		(start 189.6364 -52.6542)
		(end 188.6458 -51.6636)
		(width 0.127)
		(layer "F.Cu")
		(net "XM_CS0_N")
	)
	(segment
		(start 187.6425 -50.200814)
		(end 187.6425 -49.3268)
		(width 0.127)
		(layer "F.Cu")
		(net "XM_CS0_N")
	)
	(segment
		(start 187.6425 -49.3268)
		(end 187.198 -48.8823)
		(width 0.127)
		(layer "F.Cu")
		(net "XM_CS0_N")
	)
	(segment
		(start 189.999874 -54.299866)
		(end 189.6364 -53.936392)
		(width 0.127)
		(layer "F.Cu")
		(net "XM_CS0_N")
	)
	(segment
		(start 187.97016 -50.528474)
		(end 187.6425 -50.200814)
		(width 0.127)
		(layer "F.Cu")
		(net "XM_CS0_N")
	)
	(segment
		(start 188.341 -51.26736)
		(end 187.97016 -50.89652)
		(width 0.127)
		(layer "F.Cu")
		(net "XM_CS0_N")
	)
	(via
		(at 188.341 -51.26736)
		(size 0.6604)
		(drill 0.3302)
		(layers "F.Cu" "B.Cu")
		(net "XM_CS0_N")
	)
	(segment
		(start 186.799982 -55.099966)
		(end 186.400186 -54.70017)
		(width 0.127)
		(layer "F.Cu")
		(net "XM_CLE")
	)
	(via
		(at 186.400186 -54.70017)
		(size 0.508)
		(drill 0.254)
		(layers "F.Cu" "B.Cu")
		(net "XM_CLE")
	)
	(segment
		(start 186.400186 -54.70017)
		(end 186.26963 -54.70017)
		(width 0.127)
		(layer "B.Cu")
		(net "XM_CLE")
	)
	(segment
		(start 186.26963 -54.70017)
		(end 185.40222 -53.83276)
		(width 0.127)
		(layer "B.Cu")
		(net "XM_CLE")
	)
	(segment
		(start 185.0898 -52.408582)
		(end 185.0898 -51.0032)
		(width 0.127)
		(layer "F.Cu")
		(net "XM_ALE")
	)
	(segment
		(start 184.399936 -54.299866)
		(end 184.829196 -53.870606)
		(width 0.127)
		(layer "F.Cu")
		(net "XM_ALE")
	)
	(segment
		(start 184.829196 -53.870606)
		(end 184.829196 -52.669186)
		(width 0.127)
		(layer "F.Cu")
		(net "XM_ALE")
	)
	(segment
		(start 185.0898 -51.0032)
		(end 184.0738 -49.9872)
		(width 0.127)
		(layer "F.Cu")
		(net "XM_ALE")
	)
	(segment
		(start 184.829196 -52.669186)
		(end 185.0898 -52.408582)
		(width 0.127)
		(layer "F.Cu")
		(net "XM_ALE")
	)
	(segment
		(start 182.79999 -55.900066)
		(end 182.400194 -56.299862)
		(width 0.127)
		(layer "F.Cu")
		(net "XM_ADDR_9")
	)
	(via
		(at 162.595814 -66.004186)
		(size 0.508)
		(drill 0.254)
		(layers "F.Cu" "B.Cu")
		(net "XM_ADDR_9")
	)
	(via
		(at 182.400194 -56.299862)
		(size 0.508)
		(drill 0.254)
		(layers "F.Cu" "B.Cu")
		(net "XM_ADDR_9")
	)
	(segment
		(start 162.62096 -68.612258)
		(end 164.6682 -68.612258)
		(width 0.127)
		(layer "B.Cu")
		(net "XM_ADDR_9")
	)
	(segment
		(start 162.49396 -66.961258)
		(end 162.49396 -66.16954)
		(width 0.127)
		(layer "B.Cu")
		(net "XM_ADDR_9")
	)
	(segment
		(start 162.595814 -66.067686)
		(end 162.595814 -66.004186)
		(width 0.127)
		(layer "B.Cu")
		(net "XM_ADDR_9")
	)
	(segment
		(start 164.7952 -68.231258)
		(end 164.6682 -68.104258)
		(width 0.127)
		(layer "B.Cu")
		(net "XM_ADDR_9")
	)
	(segment
		(start 164.7952 -68.485258)
		(end 164.7952 -68.231258)
		(width 0.127)
		(layer "B.Cu")
		(net "XM_ADDR_9")
	)
	(segment
		(start 162.49396 -68.993258)
		(end 162.49396 -68.739258)
		(width 0.127)
		(layer "B.Cu")
		(net "XM_ADDR_9")
	)
	(segment
		(start 163.8173 -69.628258)
		(end 163.9443 -69.501258)
		(width 0.127)
		(layer "B.Cu")
		(net "XM_ADDR_9")
	)
	(segment
		(start 163.9443 -69.247258)
		(end 163.8173 -69.120258)
		(width 0.127)
		(layer "B.Cu")
		(net "XM_ADDR_9")
	)
	(segment
		(start 163.4617 -67.469258)
		(end 163.4617 -67.215258)
		(width 0.127)
		(layer "B.Cu")
		(net "XM_ADDR_9")
	)
	(segment
		(start 162.62096 -67.088258)
		(end 162.49396 -66.961258)
		(width 0.127)
		(layer "B.Cu")
		(net "XM_ADDR_9")
	)
	(segment
		(start 162.49396 -67.723258)
		(end 162.62096 -67.596258)
		(width 0.127)
		(layer "B.Cu")
		(net "XM_ADDR_9")
	)
	(segment
		(start 162.49396 -72.8853)
		(end 162.49396 -69.755258)
		(width 0.127)
		(layer "B.Cu")
		(net "XM_ADDR_9")
	)
	(segment
		(start 162.62096 -69.628258)
		(end 163.8173 -69.628258)
		(width 0.127)
		(layer "B.Cu")
		(net "XM_ADDR_9")
	)
	(segment
		(start 163.3347 -67.088258)
		(end 162.62096 -67.088258)
		(width 0.127)
		(layer "B.Cu")
		(net "XM_ADDR_9")
	)
	(segment
		(start 163.3347 -67.596258)
		(end 163.4617 -67.469258)
		(width 0.127)
		(layer "B.Cu")
		(net "XM_ADDR_9")
	)
	(segment
		(start 162.49396 -66.16954)
		(end 162.595814 -66.067686)
		(width 0.127)
		(layer "B.Cu")
		(net "XM_ADDR_9")
	)
	(segment
		(start 164.6682 -68.104258)
		(end 162.62096 -68.104258)
		(width 0.127)
		(layer "B.Cu")
		(net "XM_ADDR_9")
	)
	(segment
		(start 162.49396 -69.755258)
		(end 162.62096 -69.628258)
		(width 0.127)
		(layer "B.Cu")
		(net "XM_ADDR_9")
	)
	(segment
		(start 162.49396 -67.977258)
		(end 162.49396 -67.723258)
		(width 0.127)
		(layer "B.Cu")
		(net "XM_ADDR_9")
	)
	(segment
		(start 162.49396 -68.739258)
		(end 162.62096 -68.612258)
		(width 0.127)
		(layer "B.Cu")
		(net "XM_ADDR_9")
	)
	(segment
		(start 163.8173 -69.120258)
		(end 162.62096 -69.120258)
		(width 0.127)
		(layer "B.Cu")
		(net "XM_ADDR_9")
	)
	(segment
		(start 164.6682 -68.612258)
		(end 164.7952 -68.485258)
		(width 0.127)
		(layer "B.Cu")
		(net "XM_ADDR_9")
	)
	(segment
		(start 163.4617 -67.215258)
		(end 163.3347 -67.088258)
		(width 0.127)
		(layer "B.Cu")
		(net "XM_ADDR_9")
	)
	(segment
		(start 162.62096 -68.104258)
		(end 162.49396 -67.977258)
		(width 0.127)
		(layer "B.Cu")
		(net "XM_ADDR_9")
	)
	(segment
		(start 162.62096 -67.596258)
		(end 163.3347 -67.596258)
		(width 0.127)
		(layer "B.Cu")
		(net "XM_ADDR_9")
	)
	(segment
		(start 162.62096 -69.120258)
		(end 162.49396 -68.993258)
		(width 0.127)
		(layer "B.Cu")
		(net "XM_ADDR_9")
	)
	(segment
		(start 163.9443 -69.501258)
		(end 163.9443 -69.247258)
		(width 0.127)
		(layer "B.Cu")
		(net "XM_ADDR_9")
	)
	(segment
		(start 171.427394 -61.592206)
		(end 171.606972 -61.412628)
		(width 0.127)
		(layer "In5.Cu")
		(net "XM_ADDR_9")
	)
	(segment
		(start 171.68622 -60.593224)
		(end 171.966382 -60.873386)
		(width 0.127)
		(layer "In5.Cu")
		(net "XM_ADDR_9")
	)
	(segment
		(start 175.659796 -56.8325)
		(end 177.419 -56.8325)
		(width 0.127)
		(layer "In5.Cu")
		(net "XM_ADDR_9")
	)
	(segment
		(start 173.583854 -59.435746)
		(end 173.763432 -59.256168)
		(width 0.127)
		(layer "In5.Cu")
		(net "XM_ADDR_9")
	)
	(segment
		(start 172.40504 -59.874404)
		(end 172.685202 -60.154566)
		(width 0.127)
		(layer "In5.Cu")
		(net "XM_ADDR_9")
	)
	(segment
		(start 165.227 -65.9765)
		(end 166.0525 -65.151)
		(width 0.127)
		(layer "In5.Cu")
		(net "XM_ADDR_9")
	)
	(segment
		(start 177.419 -56.8325)
		(end 177.702464 -56.8325)
		(width 0.0889)
		(layer "In5.Cu")
		(net "XM_ADDR_9")
	)
	(segment
		(start 171.506388 -60.593224)
		(end 171.68622 -60.593224)
		(width 0.127)
		(layer "In5.Cu")
		(net "XM_ADDR_9")
	)
	(segment
		(start 171.32681 -60.952634)
		(end 171.32681 -60.772802)
		(width 0.127)
		(layer "In5.Cu")
		(net "XM_ADDR_9")
	)
	(segment
		(start 173.48327 -58.616342)
		(end 173.705012 -58.3946)
		(width 0.127)
		(layer "In5.Cu")
		(net "XM_ADDR_9")
	)
	(segment
		(start 177.702464 -56.8325)
		(end 177.750216 -56.784748)
		(width 0.0889)
		(layer "In5.Cu")
		(net "XM_ADDR_9")
	)
	(segment
		(start 181.994556 -56.7055)
		(end 182.400194 -56.299862)
		(width 0.0889)
		(layer "In5.Cu")
		(net "XM_ADDR_9")
	)
	(segment
		(start 178.498246 -56.299862)
		(end 181.229762 -56.299862)
		(width 0.0889)
		(layer "In5.Cu")
		(net "XM_ADDR_9")
	)
	(segment
		(start 172.685202 -60.154566)
		(end 172.865034 -60.154566)
		(width 0.127)
		(layer "In5.Cu")
		(net "XM_ADDR_9")
	)
	(segment
		(start 171.966382 -60.873386)
		(end 172.146214 -60.873386)
		(width 0.127)
		(layer "In5.Cu")
		(net "XM_ADDR_9")
	)
	(segment
		(start 171.32681 -60.772802)
		(end 171.506388 -60.593224)
		(width 0.127)
		(layer "In5.Cu")
		(net "XM_ADDR_9")
	)
	(segment
		(start 172.76445 -59.335162)
		(end 172.944028 -59.155584)
		(width 0.127)
		(layer "In5.Cu")
		(net "XM_ADDR_9")
	)
	(segment
		(start 166.948612 -65.151)
		(end 170.787568 -61.312044)
		(width 0.127)
		(layer "In5.Cu")
		(net "XM_ADDR_9")
	)
	(segment
		(start 172.225208 -59.874404)
		(end 172.40504 -59.874404)
		(width 0.127)
		(layer "In5.Cu")
		(net "XM_ADDR_9")
	)
	(segment
		(start 172.325792 -60.693808)
		(end 172.325792 -60.513976)
		(width 0.127)
		(layer "In5.Cu")
		(net "XM_ADDR_9")
	)
	(segment
		(start 173.12386 -59.155584)
		(end 173.404022 -59.435746)
		(width 0.127)
		(layer "In5.Cu")
		(net "XM_ADDR_9")
	)
	(segment
		(start 172.76445 -59.514994)
		(end 172.76445 -59.335162)
		(width 0.127)
		(layer "In5.Cu")
		(net "XM_ADDR_9")
	)
	(segment
		(start 181.6354 -56.7055)
		(end 181.994556 -56.7055)
		(width 0.0889)
		(layer "In5.Cu")
		(net "XM_ADDR_9")
	)
	(segment
		(start 170.787568 -61.312044)
		(end 170.9674 -61.312044)
		(width 0.127)
		(layer "In5.Cu")
		(net "XM_ADDR_9")
	)
	(segment
		(start 171.247562 -61.592206)
		(end 171.427394 -61.592206)
		(width 0.127)
		(layer "In5.Cu")
		(net "XM_ADDR_9")
	)
	(segment
		(start 173.705012 -58.3946)
		(end 174.097696 -58.3946)
		(width 0.127)
		(layer "In5.Cu")
		(net "XM_ADDR_9")
	)
	(segment
		(start 177.750216 -56.784748)
		(end 178.01336 -56.784748)
		(width 0.0889)
		(layer "In5.Cu")
		(net "XM_ADDR_9")
	)
	(segment
		(start 173.044612 -59.795156)
		(end 172.76445 -59.514994)
		(width 0.127)
		(layer "In5.Cu")
		(net "XM_ADDR_9")
	)
	(segment
		(start 181.229762 -56.299862)
		(end 181.6354 -56.7055)
		(width 0.0889)
		(layer "In5.Cu")
		(net "XM_ADDR_9")
	)
	(segment
		(start 173.763432 -59.076336)
		(end 173.48327 -58.796174)
		(width 0.127)
		(layer "In5.Cu")
		(net "XM_ADDR_9")
	)
	(segment
		(start 162.595814 -66.004186)
		(end 162.6235 -65.9765)
		(width 0.127)
		(layer "In5.Cu")
		(net "XM_ADDR_9")
	)
	(segment
		(start 174.097696 -58.3946)
		(end 175.659796 -56.8325)
		(width 0.127)
		(layer "In5.Cu")
		(net "XM_ADDR_9")
	)
	(segment
		(start 173.48327 -58.796174)
		(end 173.48327 -58.616342)
		(width 0.127)
		(layer "In5.Cu")
		(net "XM_ADDR_9")
	)
	(segment
		(start 162.6235 -65.9765)
		(end 165.227 -65.9765)
		(width 0.127)
		(layer "In5.Cu")
		(net "XM_ADDR_9")
	)
	(segment
		(start 172.865034 -60.154566)
		(end 173.044612 -59.974988)
		(width 0.127)
		(layer "In5.Cu")
		(net "XM_ADDR_9")
	)
	(segment
		(start 172.04563 -60.233814)
		(end 172.04563 -60.053982)
		(width 0.127)
		(layer "In5.Cu")
		(net "XM_ADDR_9")
	)
	(segment
		(start 172.944028 -59.155584)
		(end 173.12386 -59.155584)
		(width 0.127)
		(layer "In5.Cu")
		(net "XM_ADDR_9")
	)
	(segment
		(start 173.404022 -59.435746)
		(end 173.583854 -59.435746)
		(width 0.127)
		(layer "In5.Cu")
		(net "XM_ADDR_9")
	)
	(segment
		(start 173.763432 -59.256168)
		(end 173.763432 -59.076336)
		(width 0.127)
		(layer "In5.Cu")
		(net "XM_ADDR_9")
	)
	(segment
		(start 171.606972 -61.232796)
		(end 171.32681 -60.952634)
		(width 0.127)
		(layer "In5.Cu")
		(net "XM_ADDR_9")
	)
	(segment
		(start 172.325792 -60.513976)
		(end 172.04563 -60.233814)
		(width 0.127)
		(layer "In5.Cu")
		(net "XM_ADDR_9")
	)
	(segment
		(start 166.0525 -65.151)
		(end 166.948612 -65.151)
		(width 0.127)
		(layer "In5.Cu")
		(net "XM_ADDR_9")
	)
	(segment
		(start 178.01336 -56.784748)
		(end 178.498246 -56.299862)
		(width 0.0889)
		(layer "In5.Cu")
		(net "XM_ADDR_9")
	)
	(segment
		(start 170.9674 -61.312044)
		(end 171.247562 -61.592206)
		(width 0.127)
		(layer "In5.Cu")
		(net "XM_ADDR_9")
	)
	(segment
		(start 172.146214 -60.873386)
		(end 172.325792 -60.693808)
		(width 0.127)
		(layer "In5.Cu")
		(net "XM_ADDR_9")
	)
	(segment
		(start 173.044612 -59.974988)
		(end 173.044612 -59.795156)
		(width 0.127)
		(layer "In5.Cu")
		(net "XM_ADDR_9")
	)
	(segment
		(start 172.04563 -60.053982)
		(end 172.225208 -59.874404)
		(width 0.127)
		(layer "In5.Cu")
		(net "XM_ADDR_9")
	)
	(segment
		(start 171.606972 -61.412628)
		(end 171.606972 -61.232796)
		(width 0.127)
		(layer "In5.Cu")
		(net "XM_ADDR_9")
	)
	(segment
		(start 179.896262 -50.315114)
		(end 181.144672 -51.563524)
		(width 0.127)
		(layer "F.Cu")
		(net "XM_ADDR_8")
	)
	(segment
		(start 179.888134 -46.625002)
		(end 179.888134 -50.178208)
		(width 0.127)
		(layer "F.Cu")
		(net "XM_ADDR_8")
	)
	(segment
		(start 181.99989 -54.054502)
		(end 181.144672 -53.199284)
		(width 0.127)
		(layer "F.Cu")
		(net "XM_ADDR_8")
	)
	(segment
		(start 181.144672 -53.199284)
		(end 181.144672 -52.753006)
		(width 0.127)
		(layer "F.Cu")
		(net "XM_ADDR_8")
	)
	(segment
		(start 179.414678 -46.151546)
		(end 179.888134 -46.625002)
		(width 0.127)
		(layer "F.Cu")
		(net "XM_ADDR_8")
	)
	(segment
		(start 179.888134 -50.178208)
		(end 179.896262 -50.186336)
		(width 0.127)
		(layer "F.Cu")
		(net "XM_ADDR_8")
	)
	(segment
		(start 181.99989 -54.299866)
		(end 181.99989 -54.054502)
		(width 0.127)
		(layer "F.Cu")
		(net "XM_ADDR_8")
	)
	(segment
		(start 180.568854 -45.923454)
		(end 179.414678 -45.923454)
		(width 0.127)
		(layer "F.Cu")
		(net "XM_ADDR_8")
	)
	(segment
		(start 181.144672 -51.563524)
		(end 181.144672 -52.753006)
		(width 0.127)
		(layer "F.Cu")
		(net "XM_ADDR_8")
	)
	(segment
		(start 179.896262 -50.186336)
		(end 179.896262 -50.315114)
		(width 0.127)
		(layer "F.Cu")
		(net "XM_ADDR_8")
	)
	(segment
		(start 179.414678 -45.923454)
		(end 179.414678 -46.151546)
		(width 0.127)
		(layer "F.Cu")
		(net "XM_ADDR_8")
	)
	(segment
		(start 180.6321 -45.9867)
		(end 180.568854 -45.923454)
		(width 0.127)
		(layer "F.Cu")
		(net "XM_ADDR_8")
	)
	(via
		(at 179.414678 -45.923454)
		(size 0.6604)
		(drill 0.3302)
		(layers "F.Cu" "B.Cu")
		(net "XM_ADDR_8")
	)
	(via
		(at 158.9278 -59.8805)
		(size 0.508)
		(drill 0.254)
		(layers "F.Cu" "B.Cu")
		(net "XM_ADDR_8")
	)
	(via
		(at 181.144672 -52.753006)
		(size 0.508)
		(drill 0.254)
		(layers "F.Cu" "B.Cu")
		(net "XM_ADDR_8")
	)
	(segment
		(start 167.49395 -70.601586)
		(end 167.49395 -72.8853)
		(width 0.127)
		(layer "B.Cu")
		(net "XM_ADDR_8")
	)
	(segment
		(start 167.48633 -70.593966)
		(end 167.49395 -70.601586)
		(width 0.127)
		(layer "B.Cu")
		(net "XM_ADDR_8")
	)
	(segment
		(start 158.9278 -60.404502)
		(end 167.48633 -68.963032)
		(width 0.127)
		(layer "B.Cu")
		(net "XM_ADDR_8")
	)
	(segment
		(start 167.48633 -68.963032)
		(end 167.48633 -70.593966)
		(width 0.127)
		(layer "B.Cu")
		(net "XM_ADDR_8")
	)
	(segment
		(start 158.9278 -59.8805)
		(end 158.9278 -60.404502)
		(width 0.127)
		(layer "B.Cu")
		(net "XM_ADDR_8")
	)
	(segment
		(start 159.0421 -60.249054)
		(end 159.0421 -60.256166)
		(width 0.127)
		(layer "In5.Cu")
		(net "XM_ADDR_8")
	)
	(segment
		(start 159.0421 -60.256166)
		(end 160.253934 -61.468)
		(width 0.127)
		(layer "In5.Cu")
		(net "XM_ADDR_8")
	)
	(segment
		(start 160.253934 -61.468)
		(end 161.424366 -61.468)
		(width 0.127)
		(layer "In5.Cu")
		(net "XM_ADDR_8")
	)
	(segment
		(start 162.554666 -60.3377)
		(end 166.61003 -60.3377)
		(width 0.127)
		(layer "In5.Cu")
		(net "XM_ADDR_8")
	)
	(segment
		(start 171.60113 -55.3466)
		(end 172.5168 -55.3466)
		(width 0.127)
		(layer "In5.Cu")
		(net "XM_ADDR_8")
	)
	(segment
		(start 158.9278 -60.134754)
		(end 159.0421 -60.249054)
		(width 0.127)
		(layer "In5.Cu")
		(net "XM_ADDR_8")
	)
	(segment
		(start 161.424366 -61.468)
		(end 162.554666 -60.3377)
		(width 0.127)
		(layer "In5.Cu")
		(net "XM_ADDR_8")
	)
	(segment
		(start 180.584856 -53.312822)
		(end 181.144672 -52.753006)
		(width 0.127)
		(layer "In5.Cu")
		(net "XM_ADDR_8")
	)
	(segment
		(start 174.550578 -53.312822)
		(end 180.584856 -53.312822)
		(width 0.127)
		(layer "In5.Cu")
		(net "XM_ADDR_8")
	)
	(segment
		(start 172.5168 -55.3466)
		(end 174.550578 -53.312822)
		(width 0.127)
		(layer "In5.Cu")
		(net "XM_ADDR_8")
	)
	(segment
		(start 158.9278 -59.8805)
		(end 158.9278 -60.134754)
		(width 0.127)
		(layer "In5.Cu")
		(net "XM_ADDR_8")
	)
	(segment
		(start 166.61003 -60.3377)
		(end 171.60113 -55.3466)
		(width 0.127)
		(layer "In5.Cu")
		(net "XM_ADDR_8")
	)
	(segment
		(start 179.162456 -51.52898)
		(end 178.676808 -51.043332)
		(width 0.127)
		(layer "F.Cu")
		(net "XM_ADDR_7")
	)
	(segment
		(start 179.162456 -52.289456)
		(end 179.162456 -51.52898)
		(width 0.127)
		(layer "F.Cu")
		(net "XM_ADDR_7")
	)
	(segment
		(start 178.36642 -50.80508)
		(end 178.622706 -51.061366)
		(width 0.127)
		(layer "F.Cu")
		(net "XM_ADDR_7")
	)
	(segment
		(start 179.162456 -52.289456)
		(end 179.189634 -52.289456)
		(width 0.127)
		(layer "F.Cu")
		(net "XM_ADDR_7")
	)
	(segment
		(start 177.79238 -50.22596)
		(end 178.36642 -50.8)
		(width 0.127)
		(layer "F.Cu")
		(net "XM_ADDR_7")
	)
	(segment
		(start 179.189634 -52.289456)
		(end 181.200044 -54.299866)
		(width 0.127)
		(layer "F.Cu")
		(net "XM_ADDR_7")
	)
	(segment
		(start 178.622706 -51.061366)
		(end 178.658774 -51.061366)
		(width 0.127)
		(layer "F.Cu")
		(net "XM_ADDR_7")
	)
	(segment
		(start 178.658774 -51.061366)
		(end 178.676808 -51.043332)
		(width 0.127)
		(layer "F.Cu")
		(net "XM_ADDR_7")
	)
	(segment
		(start 178.36642 -50.8)
		(end 178.36642 -50.80508)
		(width 0.127)
		(layer "F.Cu")
		(net "XM_ADDR_7")
	)
	(via
		(at 179.162456 -52.289456)
		(size 0.508)
		(drill 0.254)
		(layers "F.Cu" "B.Cu")
		(net "XM_ADDR_7")
	)
	(via
		(at 178.676808 -51.043332)
		(size 0.6604)
		(drill 0.3302)
		(layers "F.Cu" "B.Cu")
		(net "XM_ADDR_7")
	)
	(via
		(at 159.5882 -58.5597)
		(size 0.508)
		(drill 0.254)
		(layers "F.Cu" "B.Cu")
		(net "XM_ADDR_7")
	)
	(segment
		(start 167.99433 -68.50253)
		(end 167.99433 -72.8853)
		(width 0.127)
		(layer "B.Cu")
		(net "XM_ADDR_7")
	)
	(segment
		(start 159.5501 -60.0583)
		(end 167.99433 -68.50253)
		(width 0.127)
		(layer "B.Cu")
		(net "XM_ADDR_7")
	)
	(segment
		(start 159.5882 -58.5597)
		(end 159.5501 -58.5978)
		(width 0.127)
		(layer "B.Cu")
		(net "XM_ADDR_7")
	)
	(segment
		(start 159.5501 -58.5978)
		(end 159.5501 -60.0583)
		(width 0.127)
		(layer "B.Cu")
		(net "XM_ADDR_7")
	)
	(segment
		(start 162.3441 -59.8297)
		(end 166.399464 -59.8297)
		(width 0.127)
		(layer "In5.Cu")
		(net "XM_ADDR_7")
	)
	(segment
		(start 159.5501 -60.0456)
		(end 160.4645 -60.96)
		(width 0.127)
		(layer "In5.Cu")
		(net "XM_ADDR_7")
	)
	(segment
		(start 159.5882 -58.5597)
		(end 159.5501 -58.5978)
		(width 0.127)
		(layer "In5.Cu")
		(net "XM_ADDR_7")
	)
	(segment
		(start 160.4645 -60.96)
		(end 161.2138 -60.96)
		(width 0.127)
		(layer "In5.Cu")
		(net "XM_ADDR_7")
	)
	(segment
		(start 161.2138 -60.96)
		(end 162.3441 -59.8297)
		(width 0.127)
		(layer "In5.Cu")
		(net "XM_ADDR_7")
	)
	(segment
		(start 179.1335 -52.2605)
		(end 179.162456 -52.289456)
		(width 0.127)
		(layer "In5.Cu")
		(net "XM_ADDR_7")
	)
	(segment
		(start 174.815246 -52.2605)
		(end 179.1335 -52.2605)
		(width 0.127)
		(layer "In5.Cu")
		(net "XM_ADDR_7")
	)
	(segment
		(start 166.399464 -59.8297)
		(end 172.000164 -54.229)
		(width 0.127)
		(layer "In5.Cu")
		(net "XM_ADDR_7")
	)
	(segment
		(start 159.5501 -58.5978)
		(end 159.5501 -60.0456)
		(width 0.127)
		(layer "In5.Cu")
		(net "XM_ADDR_7")
	)
	(segment
		(start 172.846746 -54.229)
		(end 174.815246 -52.2605)
		(width 0.127)
		(layer "In5.Cu")
		(net "XM_ADDR_7")
	)
	(segment
		(start 172.000164 -54.229)
		(end 172.846746 -54.229)
		(width 0.127)
		(layer "In5.Cu")
		(net "XM_ADDR_7")
	)
	(segment
		(start 182.59933 -52.60975)
		(end 182.118 -52.12842)
		(width 0.127)
		(layer "F.Cu")
		(net "XM_ADDR_6")
	)
	(segment
		(start 180.594 -49.391062)
		(end 180.442362 -49.5427)
		(width 0.127)
		(layer "F.Cu")
		(net "XM_ADDR_6")
	)
	(segment
		(start 182.118 -52.12842)
		(end 182.118 -51.764438)
		(width 0.127)
		(layer "F.Cu")
		(net "XM_ADDR_6")
	)
	(segment
		(start 182.59933 -52.964842)
		(end 182.59933 -52.60975)
		(width 0.127)
		(layer "F.Cu")
		(net "XM_ADDR_6")
	)
	(segment
		(start 182.428134 -53.136038)
		(end 182.59933 -52.964842)
		(width 0.127)
		(layer "F.Cu")
		(net "XM_ADDR_6")
	)
	(segment
		(start 182.428134 -53.92801)
		(end 182.428134 -53.136038)
		(width 0.127)
		(layer "F.Cu")
		(net "XM_ADDR_6")
	)
	(segment
		(start 180.442362 -49.5427)
		(end 180.442362 -50.0888)
		(width 0.127)
		(layer "F.Cu")
		(net "XM_ADDR_6")
	)
	(segment
		(start 180.594 -48.6283)
		(end 180.594 -49.391062)
		(width 0.127)
		(layer "F.Cu")
		(net "XM_ADDR_6")
	)
	(segment
		(start 182.79999 -54.299866)
		(end 182.428134 -53.92801)
		(width 0.127)
		(layer "F.Cu")
		(net "XM_ADDR_6")
	)
	(segment
		(start 182.118 -51.764438)
		(end 180.442362 -50.0888)
		(width 0.127)
		(layer "F.Cu")
		(net "XM_ADDR_6")
	)
	(segment
		(start 180.6321 -48.5902)
		(end 180.594 -48.6283)
		(width 0.127)
		(layer "F.Cu")
		(net "XM_ADDR_6")
	)
	(via
		(at 180.442362 -50.0888)
		(size 0.6604)
		(drill 0.3302)
		(layers "F.Cu" "B.Cu")
		(net "XM_ADDR_6")
	)
	(via
		(at 182.59933 -52.60975)
		(size 0.508)
		(drill 0.254)
		(layers "F.Cu" "B.Cu")
		(net "XM_ADDR_6")
	)
	(via
		(at 160.7566 -60.452)
		(size 0.508)
		(drill 0.254)
		(layers "F.Cu" "B.Cu")
		(net "XM_ADDR_6")
	)
	(segment
		(start 168.49471 -70.601586)
		(end 168.49471 -72.8853)
		(width 0.127)
		(layer "B.Cu")
		(net "XM_ADDR_6")
	)
	(segment
		(start 168.50233 -70.593966)
		(end 168.49471 -70.601586)
		(width 0.127)
		(layer "B.Cu")
		(net "XM_ADDR_6")
	)
	(segment
		(start 168.49471 -68.284344)
		(end 168.50233 -68.291964)
		(width 0.127)
		(layer "B.Cu")
		(net "XM_ADDR_6")
	)
	(segment
		(start 160.7566 -60.452)
		(end 168.49471 -68.19011)
		(width 0.127)
		(layer "B.Cu")
		(net "XM_ADDR_6")
	)
	(segment
		(start 168.49471 -68.19011)
		(end 168.49471 -68.284344)
		(width 0.127)
		(layer "B.Cu")
		(net "XM_ADDR_6")
	)
	(segment
		(start 168.50233 -68.291964)
		(end 168.50233 -70.593966)
		(width 0.127)
		(layer "B.Cu")
		(net "XM_ADDR_6")
	)
	(segment
		(start 181.750208 -52.197)
		(end 181.623208 -52.07)
		(width 0.127)
		(layer "In5.Cu")
		(net "XM_ADDR_6")
	)
	(segment
		(start 161.003234 -60.452)
		(end 160.7566 -60.452)
		(width 0.127)
		(layer "In5.Cu")
		(net "XM_ADDR_6")
	)
	(segment
		(start 182.18658 -52.197)
		(end 181.750208 -52.197)
		(width 0.127)
		(layer "In5.Cu")
		(net "XM_ADDR_6")
	)
	(segment
		(start 182.59933 -52.60975)
		(end 182.18658 -52.197)
		(width 0.127)
		(layer "In5.Cu")
		(net "XM_ADDR_6")
	)
	(segment
		(start 181.115208 -52.07)
		(end 180.988208 -52.197)
		(width 0.127)
		(layer "In5.Cu")
		(net "XM_ADDR_6")
	)
	(segment
		(start 179.3748 -51.3715)
		(end 177.9397 -51.3715)
		(width 0.127)
		(layer "In5.Cu")
		(net "XM_ADDR_6")
	)
	(segment
		(start 181.242208 -51.4096)
		(end 181.115208 -51.5366)
		(width 0.127)
		(layer "In5.Cu")
		(net "XM_ADDR_6")
	)
	(segment
		(start 166.188898 -59.3217)
		(end 162.133534 -59.3217)
		(width 0.127)
		(layer "In5.Cu")
		(net "XM_ADDR_6")
	)
	(segment
		(start 180.988208 -52.197)
		(end 180.2003 -52.197)
		(width 0.127)
		(layer "In5.Cu")
		(net "XM_ADDR_6")
	)
	(segment
		(start 171.789598 -53.721)
		(end 166.188898 -59.3217)
		(width 0.127)
		(layer "In5.Cu")
		(net "XM_ADDR_6")
	)
	(segment
		(start 181.496208 -51.4096)
		(end 181.242208 -51.4096)
		(width 0.127)
		(layer "In5.Cu")
		(net "XM_ADDR_6")
	)
	(segment
		(start 181.623208 -52.07)
		(end 181.623208 -51.5366)
		(width 0.127)
		(layer "In5.Cu")
		(net "XM_ADDR_6")
	)
	(segment
		(start 180.2003 -52.197)
		(end 179.3748 -51.3715)
		(width 0.127)
		(layer "In5.Cu")
		(net "XM_ADDR_6")
	)
	(segment
		(start 174.47514 -51.7525)
		(end 172.50664 -53.721)
		(width 0.127)
		(layer "In5.Cu")
		(net "XM_ADDR_6")
	)
	(segment
		(start 181.623208 -51.5366)
		(end 181.496208 -51.4096)
		(width 0.127)
		(layer "In5.Cu")
		(net "XM_ADDR_6")
	)
	(segment
		(start 177.5587 -51.7525)
		(end 174.47514 -51.7525)
		(width 0.127)
		(layer "In5.Cu")
		(net "XM_ADDR_6")
	)
	(segment
		(start 177.9397 -51.3715)
		(end 177.5587 -51.7525)
		(width 0.127)
		(layer "In5.Cu")
		(net "XM_ADDR_6")
	)
	(segment
		(start 172.50664 -53.721)
		(end 171.789598 -53.721)
		(width 0.127)
		(layer "In5.Cu")
		(net "XM_ADDR_6")
	)
	(segment
		(start 181.115208 -51.5366)
		(end 181.115208 -52.07)
		(width 0.127)
		(layer "In5.Cu")
		(net "XM_ADDR_6")
	)
	(segment
		(start 162.133534 -59.3217)
		(end 161.003234 -60.452)
		(width 0.127)
		(layer "In5.Cu")
		(net "XM_ADDR_6")
	)
	(segment
		(start 179.1843 -48.641)
		(end 179.2351 -48.5902)
		(width 0.127)
		(layer "F.Cu")
		(net "XM_ADDR_5")
	)
	(segment
		(start 182.37962 -54.679596)
		(end 181.837584 -54.679596)
		(width 0.127)
		(layer "F.Cu")
		(net "XM_ADDR_5")
	)
	(segment
		(start 182.79999 -55.099966)
		(end 182.37962 -54.679596)
		(width 0.127)
		(layer "F.Cu")
		(net "XM_ADDR_5")
	)
	(segment
		(start 180.749956 -52.300632)
		(end 180.749956 -52.120546)
		(width 0.127)
		(layer "F.Cu")
		(net "XM_ADDR_5")
	)
	(segment
		(start 181.63159 -54.142386)
		(end 180.359812 -52.870608)
		(width 0.127)
		(layer "F.Cu")
		(net "XM_ADDR_5")
	)
	(segment
		(start 179.1843 -50.55489)
		(end 179.1843 -48.641)
		(width 0.127)
		(layer "F.Cu")
		(net "XM_ADDR_5")
	)
	(segment
		(start 181.63159 -54.473602)
		(end 181.63159 -54.142386)
		(width 0.127)
		(layer "F.Cu")
		(net "XM_ADDR_5")
	)
	(segment
		(start 180.359812 -52.690776)
		(end 180.749956 -52.300632)
		(width 0.127)
		(layer "F.Cu")
		(net "XM_ADDR_5")
	)
	(segment
		(start 180.359812 -52.870608)
		(end 180.359812 -52.690776)
		(width 0.127)
		(layer "F.Cu")
		(net "XM_ADDR_5")
	)
	(segment
		(start 180.360066 -51.730656)
		(end 179.1843 -50.55489)
		(width 0.127)
		(layer "F.Cu")
		(net "XM_ADDR_5")
	)
	(segment
		(start 181.837584 -54.679596)
		(end 181.63159 -54.473602)
		(width 0.127)
		(layer "F.Cu")
		(net "XM_ADDR_5")
	)
	(segment
		(start 180.749956 -52.120546)
		(end 180.360066 -51.730656)
		(width 0.127)
		(layer "F.Cu")
		(net "XM_ADDR_5")
	)
	(via
		(at 180.360066 -51.730656)
		(size 0.508)
		(drill 0.254)
		(layers "F.Cu" "B.Cu")
		(net "XM_ADDR_5")
	)
	(via
		(at 160.809686 -59.536838)
		(size 0.508)
		(drill 0.254)
		(layers "F.Cu" "B.Cu")
		(net "XM_ADDR_5")
	)
	(segment
		(start 169.01033 -67.737482)
		(end 169.01033 -70.593966)
		(width 0.127)
		(layer "B.Cu")
		(net "XM_ADDR_5")
	)
	(segment
		(start 168.99382 -70.610476)
		(end 168.99382 -72.8853)
		(width 0.127)
		(layer "B.Cu")
		(net "XM_ADDR_5")
	)
	(segment
		(start 169.01033 -70.593966)
		(end 168.99382 -70.610476)
		(width 0.127)
		(layer "B.Cu")
		(net "XM_ADDR_5")
	)
	(segment
		(start 160.809686 -59.536838)
		(end 169.01033 -67.737482)
		(width 0.127)
		(layer "B.Cu")
		(net "XM_ADDR_5")
	)
	(segment
		(start 160.857438 -59.536838)
		(end 160.809686 -59.536838)
		(width 0.127)
		(layer "In5.Cu")
		(net "XM_ADDR_5")
	)
	(segment
		(start 172.246036 -53.213)
		(end 171.579032 -53.213)
		(width 0.127)
		(layer "In5.Cu")
		(net "XM_ADDR_5")
	)
	(segment
		(start 179.8574 -51.2826)
		(end 179.2351 -50.6603)
		(width 0.127)
		(layer "In5.Cu")
		(net "XM_ADDR_5")
	)
	(segment
		(start 165.978332 -58.8137)
		(end 161.580576 -58.8137)
		(width 0.127)
		(layer "In5.Cu")
		(net "XM_ADDR_5")
	)
	(segment
		(start 179.91201 -51.2826)
		(end 179.8574 -51.2826)
		(width 0.127)
		(layer "In5.Cu")
		(net "XM_ADDR_5")
	)
	(segment
		(start 161.580576 -58.8137)
		(end 160.857438 -59.536838)
		(width 0.127)
		(layer "In5.Cu")
		(net "XM_ADDR_5")
	)
	(segment
		(start 179.2351 -50.6603)
		(end 174.798736 -50.6603)
		(width 0.127)
		(layer "In5.Cu")
		(net "XM_ADDR_5")
	)
	(segment
		(start 174.798736 -50.6603)
		(end 172.246036 -53.213)
		(width 0.127)
		(layer "In5.Cu")
		(net "XM_ADDR_5")
	)
	(segment
		(start 180.360066 -51.730656)
		(end 179.91201 -51.2826)
		(width 0.127)
		(layer "In5.Cu")
		(net "XM_ADDR_5")
	)
	(segment
		(start 171.579032 -53.213)
		(end 165.978332 -58.8137)
		(width 0.127)
		(layer "In5.Cu")
		(net "XM_ADDR_5")
	)
	(segment
		(start 182.403242 -51.079654)
		(end 182.403242 -50.609754)
		(width 0.127)
		(layer "F.Cu")
		(net "XM_ADDR_4")
	)
	(segment
		(start 182.79999 -53.50002)
		(end 182.79999 -53.28539)
		(width 0.127)
		(layer "F.Cu")
		(net "XM_ADDR_4")
	)
	(segment
		(start 182.2958 -50.502312)
		(end 182.2958 -49.8856)
		(width 0.127)
		(layer "F.Cu")
		(net "XM_ADDR_4")
	)
	(segment
		(start 181.9783 -48.5902)
		(end 182.0291 -48.5902)
		(width 0.127)
		(layer "F.Cu")
		(net "XM_ADDR_4")
	)
	(segment
		(start 182.0291 -48.5902)
		(end 182.0291 -48.9204)
		(width 0.127)
		(layer "F.Cu")
		(net "XM_ADDR_4")
	)
	(segment
		(start 181.3306 -46.4312)
		(end 181.3306 -47.9425)
		(width 0.127)
		(layer "F.Cu")
		(net "XM_ADDR_4")
	)
	(segment
		(start 181.3306 -47.9425)
		(end 181.9783 -48.5902)
		(width 0.127)
		(layer "F.Cu")
		(net "XM_ADDR_4")
	)
	(segment
		(start 183.039766 -51.716178)
		(end 182.403242 -51.079654)
		(width 0.127)
		(layer "F.Cu")
		(net "XM_ADDR_4")
	)
	(segment
		(start 182.403242 -50.609754)
		(end 182.2958 -50.502312)
		(width 0.127)
		(layer "F.Cu")
		(net "XM_ADDR_4")
	)
	(segment
		(start 182.0291 -48.9204)
		(end 182.2958 -49.1871)
		(width 0.127)
		(layer "F.Cu")
		(net "XM_ADDR_4")
	)
	(segment
		(start 182.0291 -45.9867)
		(end 181.7751 -45.9867)
		(width 0.127)
		(layer "F.Cu")
		(net "XM_ADDR_4")
	)
	(segment
		(start 183.039766 -53.045614)
		(end 183.039766 -51.716178)
		(width 0.127)
		(layer "F.Cu")
		(net "XM_ADDR_4")
	)
	(segment
		(start 181.7751 -45.9867)
		(end 181.3306 -46.4312)
		(width 0.127)
		(layer "F.Cu")
		(net "XM_ADDR_4")
	)
	(segment
		(start 182.2958 -49.1871)
		(end 182.2958 -49.8856)
		(width 0.127)
		(layer "F.Cu")
		(net "XM_ADDR_4")
	)
	(segment
		(start 182.79999 -53.28539)
		(end 183.039766 -53.045614)
		(width 0.127)
		(layer "F.Cu")
		(net "XM_ADDR_4")
	)
	(via
		(at 160.771332 -58.674)
		(size 0.508)
		(drill 0.254)
		(layers "F.Cu" "B.Cu")
		(net "XM_ADDR_4")
	)
	(via
		(at 182.403242 -51.079654)
		(size 0.508)
		(drill 0.254)
		(layers "F.Cu" "B.Cu")
		(net "XM_ADDR_4")
	)
	(via
		(at 182.2958 -49.8856)
		(size 0.6604)
		(drill 0.3302)
		(layers "F.Cu" "B.Cu")
		(net "XM_ADDR_4")
	)
	(segment
		(start 169.50182 -70.80377)
		(end 169.4942 -70.81139)
		(width 0.127)
		(layer "B.Cu")
		(net "XM_ADDR_4")
	)
	(segment
		(start 169.4942 -70.81139)
		(end 169.4942 -72.8853)
		(width 0.127)
		(layer "B.Cu")
		(net "XM_ADDR_4")
	)
	(segment
		(start 160.771332 -58.674)
		(end 169.51833 -67.420998)
		(width 0.127)
		(layer "B.Cu")
		(net "XM_ADDR_4")
	)
	(segment
		(start 169.51833 -67.420998)
		(end 169.51833 -70.593966)
		(width 0.127)
		(layer "B.Cu")
		(net "XM_ADDR_4")
	)
	(segment
		(start 169.51833 -70.593966)
		(end 169.50182 -70.610476)
		(width 0.127)
		(layer "B.Cu")
		(net "XM_ADDR_4")
	)
	(segment
		(start 169.50182 -70.610476)
		(end 169.50182 -70.80377)
		(width 0.127)
		(layer "B.Cu")
		(net "XM_ADDR_4")
	)
	(segment
		(start 161.2519 -58.3057)
		(end 160.8836 -58.674)
		(width 0.127)
		(layer "In5.Cu")
		(net "XM_ADDR_4")
	)
	(segment
		(start 182.403242 -51.079654)
		(end 181.420008 -51.079654)
		(width 0.127)
		(layer "In5.Cu")
		(net "XM_ADDR_4")
	)
	(segment
		(start 180.492654 -50.1523)
		(end 174.58817 -50.1523)
		(width 0.127)
		(layer "In5.Cu")
		(net "XM_ADDR_4")
	)
	(segment
		(start 160.8836 -58.674)
		(end 160.771332 -58.674)
		(width 0.127)
		(layer "In5.Cu")
		(net "XM_ADDR_4")
	)
	(segment
		(start 174.58817 -50.1523)
		(end 172.03547 -52.705)
		(width 0.127)
		(layer "In5.Cu")
		(net "XM_ADDR_4")
	)
	(segment
		(start 171.368466 -52.705)
		(end 165.767766 -58.3057)
		(width 0.127)
		(layer "In5.Cu")
		(net "XM_ADDR_4")
	)
	(segment
		(start 172.03547 -52.705)
		(end 171.368466 -52.705)
		(width 0.127)
		(layer "In5.Cu")
		(net "XM_ADDR_4")
	)
	(segment
		(start 165.767766 -58.3057)
		(end 161.2519 -58.3057)
		(width 0.127)
		(layer "In5.Cu")
		(net "XM_ADDR_4")
	)
	(segment
		(start 181.420008 -51.079654)
		(end 180.492654 -50.1523)
		(width 0.127)
		(layer "In5.Cu")
		(net "XM_ADDR_4")
	)
	(segment
		(start 184.399936 -52.150264)
		(end 184.399936 -53.50002)
		(width 0.127)
		(layer "F.Cu")
		(net "XM_ADDR_3")
	)
	(segment
		(start 184.654952 -51.895248)
		(end 184.399936 -52.150264)
		(width 0.127)
		(layer "F.Cu")
		(net "XM_ADDR_3")
	)
	(via
		(at 163.206938 -57.655968)
		(size 0.508)
		(drill 0.254)
		(layers "F.Cu" "B.Cu")
		(net "XM_ADDR_3")
	)
	(via
		(at 184.654952 -51.895248)
		(size 0.508)
		(drill 0.254)
		(layers "F.Cu" "B.Cu")
		(net "XM_ADDR_3")
	)
	(segment
		(start 170.00982 -70.610476)
		(end 170.00982 -70.803516)
		(width 0.127)
		(layer "B.Cu")
		(net "XM_ADDR_3")
	)
	(segment
		(start 163.206938 -60.159392)
		(end 170.02633 -66.978784)
		(width 0.127)
		(layer "B.Cu")
		(net "XM_ADDR_3")
	)
	(segment
		(start 170.02633 -70.593966)
		(end 170.00982 -70.610476)
		(width 0.127)
		(layer "B.Cu")
		(net "XM_ADDR_3")
	)
	(segment
		(start 169.99458 -70.81901)
		(end 169.99458 -72.8853)
		(width 0.127)
		(layer "B.Cu")
		(net "XM_ADDR_3")
	)
	(segment
		(start 170.02633 -66.978784)
		(end 170.02633 -70.593966)
		(width 0.127)
		(layer "B.Cu")
		(net "XM_ADDR_3")
	)
	(segment
		(start 163.206938 -57.655968)
		(end 163.206938 -60.159392)
		(width 0.127)
		(layer "B.Cu")
		(net "XM_ADDR_3")
	)
	(segment
		(start 169.99839 -70.8152)
		(end 169.99458 -70.81901)
		(width 0.127)
		(layer "B.Cu")
		(net "XM_ADDR_3")
	)
	(segment
		(start 170.00982 -70.803516)
		(end 169.99839 -70.8152)
		(width 0.127)
		(layer "B.Cu")
		(net "XM_ADDR_3")
	)
	(segment
		(start 184.654952 -51.895248)
		(end 184.448704 -51.689)
		(width 0.127)
		(layer "In5.Cu")
		(net "XM_ADDR_3")
	)
	(segment
		(start 174.377604 -49.6443)
		(end 173.056804 -50.9651)
		(width 0.127)
		(layer "In5.Cu")
		(net "XM_ADDR_3")
	)
	(segment
		(start 181.5465 -49.6443)
		(end 174.377604 -49.6443)
		(width 0.127)
		(layer "In5.Cu")
		(net "XM_ADDR_3")
	)
	(segment
		(start 172.3898 -50.9651)
		(end 165.5572 -57.7977)
		(width 0.127)
		(layer "In5.Cu")
		(net "XM_ADDR_3")
	)
	(segment
		(start 173.056804 -50.9651)
		(end 172.3898 -50.9651)
		(width 0.127)
		(layer "In5.Cu")
		(net "XM_ADDR_3")
	)
	(segment
		(start 182.562754 -50.660554)
		(end 181.5465 -49.6443)
		(width 0.127)
		(layer "In5.Cu")
		(net "XM_ADDR_3")
	)
	(segment
		(start 183.324246 -51.689)
		(end 182.822342 -51.187096)
		(width 0.127)
		(layer "In5.Cu")
		(net "XM_ADDR_3")
	)
	(segment
		(start 163.307268 -57.655968)
		(end 163.206938 -57.655968)
		(width 0.127)
		(layer "In5.Cu")
		(net "XM_ADDR_3")
	)
	(segment
		(start 184.448704 -51.689)
		(end 183.324246 -51.689)
		(width 0.127)
		(layer "In5.Cu")
		(net "XM_ADDR_3")
	)
	(segment
		(start 165.5572 -57.7977)
		(end 163.449 -57.7977)
		(width 0.127)
		(layer "In5.Cu")
		(net "XM_ADDR_3")
	)
	(segment
		(start 163.449 -57.7977)
		(end 163.307268 -57.655968)
		(width 0.127)
		(layer "In5.Cu")
		(net "XM_ADDR_3")
	)
	(segment
		(start 182.822342 -50.905918)
		(end 182.576978 -50.660554)
		(width 0.127)
		(layer "In5.Cu")
		(net "XM_ADDR_3")
	)
	(segment
		(start 182.822342 -51.187096)
		(end 182.822342 -50.905918)
		(width 0.127)
		(layer "In5.Cu")
		(net "XM_ADDR_3")
	)
	(segment
		(start 182.576978 -50.660554)
		(end 182.562754 -50.660554)
		(width 0.127)
		(layer "In5.Cu")
		(net "XM_ADDR_3")
	)
	(segment
		(start 181.990492 -59.099958)
		(end 181.99989 -59.099958)
		(width 0.127)
		(layer "F.Cu")
		(net "XM_ADDR_25")
	)
	(segment
		(start 181.59603 -59.49442)
		(end 181.990492 -59.099958)
		(width 0.127)
		(layer "F.Cu")
		(net "XM_ADDR_25")
	)
	(via
		(at 181.59603 -59.49442)
		(size 0.508)
		(drill 0.254)
		(layers "F.Cu" "B.Cu")
		(net "XM_ADDR_25")
	)
	(segment
		(start 181.59603 -59.49442)
		(end 181.23281 -59.1312)
		(width 0.127)
		(layer "B.Cu")
		(net "XM_ADDR_25")
	)
	(segment
		(start 181.23281 -59.1312)
		(end 180.594 -59.1312)
		(width 0.127)
		(layer "B.Cu")
		(net "XM_ADDR_25")
	)
	(segment
		(start 181.200044 -59.900058)
		(end 180.521864 -59.900058)
		(width 0.127)
		(layer "F.Cu")
		(net "XM_ADDR_24")
	)
	(via
		(at 180.521864 -59.900058)
		(size 0.508)
		(drill 0.254)
		(layers "F.Cu" "B.Cu")
		(net "XM_ADDR_24")
	)
	(segment
		(start 180.626258 -59.900058)
		(end 181.3814 -60.6552)
		(width 0.127)
		(layer "B.Cu")
		(net "XM_ADDR_24")
	)
	(segment
		(start 180.521864 -59.900058)
		(end 180.626258 -59.900058)
		(width 0.127)
		(layer "B.Cu")
		(net "XM_ADDR_24")
	)
	(segment
		(start 181.60619 -61.093604)
		(end 181.99989 -60.699904)
		(width 0.127)
		(layer "F.Cu")
		(net "XM_ADDR_23")
	)
	(segment
		(start 179.344066 -61.128656)
		(end 179.415694 -61.200284)
		(width 0.127)
		(layer "F.Cu")
		(net "XM_ADDR_23")
	)
	(segment
		(start 177.24501 -59.0296)
		(end 177.1269 -59.0296)
		(width 0.127)
		(layer "F.Cu")
		(net "XM_ADDR_23")
	)
	(segment
		(start 179.415694 -61.200284)
		(end 180.607716 -61.200284)
		(width 0.127)
		(layer "F.Cu")
		(net "XM_ADDR_23")
	)
	(segment
		(start 180.714396 -61.093604)
		(end 181.60619 -61.093604)
		(width 0.127)
		(layer "F.Cu")
		(net "XM_ADDR_23")
	)
	(segment
		(start 180.607716 -61.200284)
		(end 180.714396 -61.093604)
		(width 0.127)
		(layer "F.Cu")
		(net "XM_ADDR_23")
	)
	(segment
		(start 179.344066 -61.128656)
		(end 177.24501 -59.0296)
		(width 0.127)
		(layer "F.Cu")
		(net "XM_ADDR_23")
	)
	(via
		(at 179.344066 -61.128656)
		(size 0.508)
		(drill 0.254)
		(layers "F.Cu" "B.Cu")
		(net "XM_ADDR_23")
	)
	(via
		(at 157.6705 -65.5447)
		(size 0.508)
		(drill 0.254)
		(layers "F.Cu" "B.Cu")
		(net "XM_ADDR_23")
	)
	(segment
		(start 158.49473 -72.8853)
		(end 158.49473 -71.394828)
		(width 0.127)
		(layer "B.Cu")
		(net "XM_ADDR_23")
	)
	(segment
		(start 157.6197 -67.7799)
		(end 157.6197 -65.5955)
		(width 0.127)
		(layer "B.Cu")
		(net "XM_ADDR_23")
	)
	(segment
		(start 157.97784 -68.13804)
		(end 157.6197 -67.7799)
		(width 0.127)
		(layer "B.Cu")
		(net "XM_ADDR_23")
	)
	(segment
		(start 158.49473 -71.394828)
		(end 157.97784 -70.877938)
		(width 0.127)
		(layer "B.Cu")
		(net "XM_ADDR_23")
	)
	(segment
		(start 157.6197 -65.5955)
		(end 157.6705 -65.5447)
		(width 0.127)
		(layer "B.Cu")
		(net "XM_ADDR_23")
	)
	(segment
		(start 157.97784 -70.877938)
		(end 157.97784 -68.13804)
		(width 0.127)
		(layer "B.Cu")
		(net "XM_ADDR_23")
	)
	(segment
		(start 176.84115 -68.6181)
		(end 177.075846 -68.6181)
		(width 0.127)
		(layer "In5.Cu")
		(net "XM_ADDR_23")
	)
	(segment
		(start 166.943786 -70.7644)
		(end 174.69485 -70.7644)
		(width 0.127)
		(layer "In5.Cu")
		(net "XM_ADDR_23")
	)
	(segment
		(start 164.137848 -70.9549)
		(end 164.927534 -70.9549)
		(width 0.127)
		(layer "In5.Cu")
		(net "XM_ADDR_23")
	)
	(segment
		(start 160.248092 -71.5772)
		(end 163.515548 -71.5772)
		(width 0.127)
		(layer "In5.Cu")
		(net "XM_ADDR_23")
	)
	(segment
		(start 178.250088 -67.443858)
		(end 179.088542 -67.443858)
		(width 0.127)
		(layer "In5.Cu")
		(net "XM_ADDR_23")
	)
	(segment
		(start 157.6705 -65.5447)
		(end 157.6705 -67.8307)
		(width 0.127)
		(layer "In5.Cu")
		(net "XM_ADDR_23")
	)
	(segment
		(start 179.088542 -67.443858)
		(end 180.0479 -66.4845)
		(width 0.127)
		(layer "In5.Cu")
		(net "XM_ADDR_23")
	)
	(segment
		(start 164.927534 -70.9549)
		(end 165.423088 -71.450454)
		(width 0.127)
		(layer "In5.Cu")
		(net "XM_ADDR_23")
	)
	(segment
		(start 158.040324 -68.200524)
		(end 158.040324 -69.369432)
		(width 0.127)
		(layer "In5.Cu")
		(net "XM_ADDR_23")
	)
	(segment
		(start 163.515548 -71.5772)
		(end 164.137848 -70.9549)
		(width 0.127)
		(layer "In5.Cu")
		(net "XM_ADDR_23")
	)
	(segment
		(start 174.69485 -70.7644)
		(end 176.84115 -68.6181)
		(width 0.127)
		(layer "In5.Cu")
		(net "XM_ADDR_23")
	)
	(segment
		(start 177.075846 -68.6181)
		(end 178.250088 -67.443858)
		(width 0.127)
		(layer "In5.Cu")
		(net "XM_ADDR_23")
	)
	(segment
		(start 180.0479 -61.83249)
		(end 179.344066 -61.128656)
		(width 0.127)
		(layer "In5.Cu")
		(net "XM_ADDR_23")
	)
	(segment
		(start 180.0479 -66.4845)
		(end 180.0479 -61.83249)
		(width 0.127)
		(layer "In5.Cu")
		(net "XM_ADDR_23")
	)
	(segment
		(start 158.040324 -69.369432)
		(end 160.248092 -71.5772)
		(width 0.127)
		(layer "In5.Cu")
		(net "XM_ADDR_23")
	)
	(segment
		(start 166.257732 -71.450454)
		(end 166.943786 -70.7644)
		(width 0.127)
		(layer "In5.Cu")
		(net "XM_ADDR_23")
	)
	(segment
		(start 165.423088 -71.450454)
		(end 166.257732 -71.450454)
		(width 0.127)
		(layer "In5.Cu")
		(net "XM_ADDR_23")
	)
	(segment
		(start 157.6705 -67.8307)
		(end 158.040324 -68.200524)
		(width 0.127)
		(layer "In5.Cu")
		(net "XM_ADDR_23")
	)
	(segment
		(start 181.99989 -59.900058)
		(end 181.57571 -60.324238)
		(width 0.127)
		(layer "F.Cu")
		(net "XM_ADDR_22")
	)
	(segment
		(start 181.57571 -60.324238)
		(end 179.454048 -60.324238)
		(width 0.127)
		(layer "F.Cu")
		(net "XM_ADDR_22")
	)
	(segment
		(start 178.945032 -59.815222)
		(end 178.945032 -59.426856)
		(width 0.127)
		(layer "F.Cu")
		(net "XM_ADDR_22")
	)
	(segment
		(start 179.267866 -60.138056)
		(end 178.945032 -59.815222)
		(width 0.127)
		(layer "F.Cu")
		(net "XM_ADDR_22")
	)
	(segment
		(start 179.454048 -60.324238)
		(end 179.267866 -60.138056)
		(width 0.127)
		(layer "F.Cu")
		(net "XM_ADDR_22")
	)
	(segment
		(start 177.531776 -58.0136)
		(end 178.945032 -59.426856)
		(width 0.127)
		(layer "F.Cu")
		(net "XM_ADDR_22")
	)
	(segment
		(start 177.1269 -58.0136)
		(end 177.531776 -58.0136)
		(width 0.127)
		(layer "F.Cu")
		(net "XM_ADDR_22")
	)
	(via
		(at 179.267866 -60.138056)
		(size 0.508)
		(drill 0.254)
		(layers "F.Cu" "B.Cu")
		(net "XM_ADDR_22")
	)
	(via
		(at 178.945032 -59.426856)
		(size 0.6604)
		(drill 0.3302)
		(layers "F.Cu" "B.Cu")
		(net "XM_ADDR_22")
	)
	(via
		(at 165.6334 -70.9422)
		(size 0.508)
		(drill 0.254)
		(layers "F.Cu" "B.Cu")
		(net "XM_ADDR_22")
	)
	(segment
		(start 165.6334 -70.9422)
		(end 165.6334 -71.0311)
		(width 0.127)
		(layer "B.Cu")
		(net "XM_ADDR_22")
	)
	(segment
		(start 165.225222 -71.618602)
		(end 164.99459 -71.849234)
		(width 0.127)
		(layer "B.Cu")
		(net "XM_ADDR_22")
	)
	(segment
		(start 164.99459 -71.849234)
		(end 164.99459 -72.8853)
		(width 0.127)
		(layer "B.Cu")
		(net "XM_ADDR_22")
	)
	(segment
		(start 165.6334 -71.0311)
		(end 165.225222 -71.439278)
		(width 0.127)
		(layer "B.Cu")
		(net "XM_ADDR_22")
	)
	(segment
		(start 165.225222 -71.439278)
		(end 165.225222 -71.618602)
		(width 0.127)
		(layer "B.Cu")
		(net "XM_ADDR_22")
	)
	(segment
		(start 172.21073 -67.6275)
		(end 171.95673 -67.6275)
		(width 0.127)
		(layer "In5.Cu")
		(net "XM_ADDR_22")
	)
	(segment
		(start 171.95673 -67.6275)
		(end 171.82973 -67.7545)
		(width 0.127)
		(layer "In5.Cu")
		(net "XM_ADDR_22")
	)
	(segment
		(start 171.32173 -69.8246)
		(end 171.32173 -68.1101)
		(width 0.127)
		(layer "In5.Cu")
		(net "XM_ADDR_22")
	)
	(segment
		(start 179.7685 -62.1665)
		(end 179.7685 -66.326258)
		(width 0.127)
		(layer "In5.Cu")
		(net "XM_ADDR_22")
	)
	(segment
		(start 174.87773 -68.289424)
		(end 174.87773 -69.7484)
		(width 0.127)
		(layer "In5.Cu")
		(net "XM_ADDR_22")
	)
	(segment
		(start 172.97273 -67.6275)
		(end 172.84573 -67.7545)
		(width 0.127)
		(layer "In5.Cu")
		(net "XM_ADDR_22")
	)
	(segment
		(start 171.82973 -67.7545)
		(end 171.82973 -69.8246)
		(width 0.127)
		(layer "In5.Cu")
		(net "XM_ADDR_22")
	)
	(segment
		(start 170.81373 -68.515992)
		(end 170.68673 -68.642992)
		(width 0.127)
		(layer "In5.Cu")
		(net "XM_ADDR_22")
	)
	(segment
		(start 174.24273 -67.6275)
		(end 173.98873 -67.6275)
		(width 0.127)
		(layer "In5.Cu")
		(net "XM_ADDR_22")
	)
	(segment
		(start 172.71873 -69.9135)
		(end 172.46473 -69.9135)
		(width 0.127)
		(layer "In5.Cu")
		(net "XM_ADDR_22")
	)
	(segment
		(start 172.84573 -67.7545)
		(end 172.84573 -69.7865)
		(width 0.127)
		(layer "In5.Cu")
		(net "XM_ADDR_22")
	)
	(segment
		(start 172.33773 -67.7545)
		(end 172.21073 -67.6275)
		(width 0.127)
		(layer "In5.Cu")
		(net "XM_ADDR_22")
	)
	(segment
		(start 166.14902 -70.8406)
		(end 165.735 -70.8406)
		(width 0.127)
		(layer "In5.Cu")
		(net "XM_ADDR_22")
	)
	(segment
		(start 170.68673 -68.642992)
		(end 170.307508 -68.642992)
		(width 0.127)
		(layer "In5.Cu")
		(net "XM_ADDR_22")
	)
	(segment
		(start 171.32173 -68.1101)
		(end 171.19473 -67.9831)
		(width 0.127)
		(layer "In5.Cu")
		(net "XM_ADDR_22")
	)
	(segment
		(start 172.84573 -69.7865)
		(end 172.71873 -69.9135)
		(width 0.127)
		(layer "In5.Cu")
		(net "XM_ADDR_22")
	)
	(segment
		(start 174.36973 -67.7545)
		(end 174.24273 -67.6275)
		(width 0.127)
		(layer "In5.Cu")
		(net "XM_ADDR_22")
	)
	(segment
		(start 170.81373 -68.1101)
		(end 170.81373 -68.515992)
		(width 0.127)
		(layer "In5.Cu")
		(net "XM_ADDR_22")
	)
	(segment
		(start 174.75073 -69.8754)
		(end 174.49673 -69.8754)
		(width 0.127)
		(layer "In5.Cu")
		(net "XM_ADDR_22")
	)
	(segment
		(start 173.86173 -69.8373)
		(end 173.73473 -69.9643)
		(width 0.127)
		(layer "In5.Cu")
		(net "XM_ADDR_22")
	)
	(segment
		(start 176.617884 -68.1228)
		(end 175.044354 -68.1228)
		(width 0.127)
		(layer "In5.Cu")
		(net "XM_ADDR_22")
	)
	(segment
		(start 173.48073 -69.9643)
		(end 173.35373 -69.8373)
		(width 0.127)
		(layer "In5.Cu")
		(net "XM_ADDR_22")
	)
	(segment
		(start 179.7685 -66.326258)
		(end 179.136802 -66.957956)
		(width 0.127)
		(layer "In5.Cu")
		(net "XM_ADDR_22")
	)
	(segment
		(start 173.98873 -67.6275)
		(end 173.86173 -67.7545)
		(width 0.127)
		(layer "In5.Cu")
		(net "XM_ADDR_22")
	)
	(segment
		(start 173.35373 -67.7545)
		(end 173.22673 -67.6275)
		(width 0.127)
		(layer "In5.Cu")
		(net "XM_ADDR_22")
	)
	(segment
		(start 165.735 -70.8406)
		(end 165.6334 -70.9422)
		(width 0.127)
		(layer "In5.Cu")
		(net "XM_ADDR_22")
	)
	(segment
		(start 173.73473 -69.9643)
		(end 173.48073 -69.9643)
		(width 0.127)
		(layer "In5.Cu")
		(net "XM_ADDR_22")
	)
	(segment
		(start 175.044354 -68.1228)
		(end 174.87773 -68.289424)
		(width 0.127)
		(layer "In5.Cu")
		(net "XM_ADDR_22")
	)
	(segment
		(start 174.36973 -69.7484)
		(end 174.36973 -67.7545)
		(width 0.127)
		(layer "In5.Cu")
		(net "XM_ADDR_22")
	)
	(segment
		(start 171.19473 -67.9831)
		(end 170.94073 -67.9831)
		(width 0.127)
		(layer "In5.Cu")
		(net "XM_ADDR_22")
	)
	(segment
		(start 172.46473 -69.9135)
		(end 172.33773 -69.7865)
		(width 0.127)
		(layer "In5.Cu")
		(net "XM_ADDR_22")
	)
	(segment
		(start 174.87773 -69.7484)
		(end 174.75073 -69.8754)
		(width 0.127)
		(layer "In5.Cu")
		(net "XM_ADDR_22")
	)
	(segment
		(start 168.6941 -70.2564)
		(end 166.73322 -70.2564)
		(width 0.127)
		(layer "In5.Cu")
		(net "XM_ADDR_22")
	)
	(segment
		(start 173.35373 -69.8373)
		(end 173.35373 -67.7545)
		(width 0.127)
		(layer "In5.Cu")
		(net "XM_ADDR_22")
	)
	(segment
		(start 166.73322 -70.2564)
		(end 166.14902 -70.8406)
		(width 0.127)
		(layer "In5.Cu")
		(net "XM_ADDR_22")
	)
	(segment
		(start 179.267866 -60.138056)
		(end 178.924966 -60.480956)
		(width 0.127)
		(layer "In5.Cu")
		(net "XM_ADDR_22")
	)
	(segment
		(start 171.70273 -69.9516)
		(end 171.44873 -69.9516)
		(width 0.127)
		(layer "In5.Cu")
		(net "XM_ADDR_22")
	)
	(segment
		(start 179.136802 -66.957956)
		(end 177.782728 -66.957956)
		(width 0.127)
		(layer "In5.Cu")
		(net "XM_ADDR_22")
	)
	(segment
		(start 171.44873 -69.9516)
		(end 171.32173 -69.8246)
		(width 0.127)
		(layer "In5.Cu")
		(net "XM_ADDR_22")
	)
	(segment
		(start 177.782728 -66.957956)
		(end 176.617884 -68.1228)
		(width 0.127)
		(layer "In5.Cu")
		(net "XM_ADDR_22")
	)
	(segment
		(start 174.49673 -69.8754)
		(end 174.36973 -69.7484)
		(width 0.127)
		(layer "In5.Cu")
		(net "XM_ADDR_22")
	)
	(segment
		(start 173.22673 -67.6275)
		(end 172.97273 -67.6275)
		(width 0.127)
		(layer "In5.Cu")
		(net "XM_ADDR_22")
	)
	(segment
		(start 178.924966 -60.480956)
		(end 178.924966 -61.322966)
		(width 0.127)
		(layer "In5.Cu")
		(net "XM_ADDR_22")
	)
	(segment
		(start 170.307508 -68.642992)
		(end 168.6941 -70.2564)
		(width 0.127)
		(layer "In5.Cu")
		(net "XM_ADDR_22")
	)
	(segment
		(start 173.86173 -67.7545)
		(end 173.86173 -69.8373)
		(width 0.127)
		(layer "In5.Cu")
		(net "XM_ADDR_22")
	)
	(segment
		(start 178.924966 -61.322966)
		(end 179.7685 -62.1665)
		(width 0.127)
		(layer "In5.Cu")
		(net "XM_ADDR_22")
	)
	(segment
		(start 170.94073 -67.9831)
		(end 170.81373 -68.1101)
		(width 0.127)
		(layer "In5.Cu")
		(net "XM_ADDR_22")
	)
	(segment
		(start 171.82973 -69.8246)
		(end 171.70273 -69.9516)
		(width 0.127)
		(layer "In5.Cu")
		(net "XM_ADDR_22")
	)
	(segment
		(start 172.33773 -69.7865)
		(end 172.33773 -67.7545)
		(width 0.127)
		(layer "In5.Cu")
		(net "XM_ADDR_22")
	)
	(segment
		(start 180.073046 -59.0804)
		(end 180.52669 -59.0804)
		(width 0.127)
		(layer "F.Cu")
		(net "XM_ADDR_21")
	)
	(segment
		(start 179.204366 -58.690256)
		(end 179.445666 -58.931556)
		(width 0.127)
		(layer "F.Cu")
		(net "XM_ADDR_21")
	)
	(segment
		(start 180.52669 -59.0804)
		(end 180.86959 -58.7375)
		(width 0.127)
		(layer "F.Cu")
		(net "XM_ADDR_21")
	)
	(segment
		(start 179.445666 -58.931556)
		(end 179.924202 -58.931556)
		(width 0.127)
		(layer "F.Cu")
		(net "XM_ADDR_21")
	)
	(segment
		(start 181.99989 -58.575194)
		(end 181.99989 -58.299858)
		(width 0.127)
		(layer "F.Cu")
		(net "XM_ADDR_21")
	)
	(segment
		(start 181.837584 -58.7375)
		(end 181.99989 -58.575194)
		(width 0.127)
		(layer "F.Cu")
		(net "XM_ADDR_21")
	)
	(segment
		(start 180.86959 -58.7375)
		(end 181.837584 -58.7375)
		(width 0.127)
		(layer "F.Cu")
		(net "XM_ADDR_21")
	)
	(segment
		(start 179.924202 -58.931556)
		(end 180.073046 -59.0804)
		(width 0.127)
		(layer "F.Cu")
		(net "XM_ADDR_21")
	)
	(via
		(at 164.846 -69.469)
		(size 0.508)
		(drill 0.254)
		(layers "F.Cu" "B.Cu")
		(net "XM_ADDR_21")
	)
	(via
		(at 179.204366 -58.690256)
		(size 0.508)
		(drill 0.254)
		(layers "F.Cu" "B.Cu")
		(net "XM_ADDR_21")
	)
	(segment
		(start 163.49472 -70.88378)
		(end 164.4523 -69.9262)
		(width 0.127)
		(layer "B.Cu")
		(net "XM_ADDR_21")
	)
	(segment
		(start 164.4523 -69.9262)
		(end 164.4523 -69.71157)
		(width 0.127)
		(layer "B.Cu")
		(net "XM_ADDR_21")
	)
	(segment
		(start 164.69487 -69.469)
		(end 164.846 -69.469)
		(width 0.127)
		(layer "B.Cu")
		(net "XM_ADDR_21")
	)
	(segment
		(start 164.4523 -69.71157)
		(end 164.69487 -69.469)
		(width 0.127)
		(layer "B.Cu")
		(net "XM_ADDR_21")
	)
	(segment
		(start 163.49472 -72.8853)
		(end 163.49472 -70.88378)
		(width 0.127)
		(layer "B.Cu")
		(net "XM_ADDR_21")
	)
	(segment
		(start 168.592754 -67.949826)
		(end 168.772586 -67.949826)
		(width 0.127)
		(layer "In5.Cu")
		(net "XM_ADDR_21")
	)
	(segment
		(start 177.67554 -64.130428)
		(end 177.67554 -64.31026)
		(width 0.127)
		(layer "In5.Cu")
		(net "XM_ADDR_21")
	)
	(segment
		(start 175.383698 -64.534034)
		(end 175.383698 -64.713866)
		(width 0.127)
		(layer "In5.Cu")
		(net "XM_ADDR_21")
	)
	(segment
		(start 166.371524 -69.2404)
		(end 165.0746 -69.2404)
		(width 0.127)
		(layer "In5.Cu")
		(net "XM_ADDR_21")
	)
	(segment
		(start 165.0746 -69.2404)
		(end 164.846 -69.469)
		(width 0.127)
		(layer "In5.Cu")
		(net "XM_ADDR_21")
	)
	(segment
		(start 177.67554 -64.31026)
		(end 177.495962 -64.489838)
		(width 0.127)
		(layer "In5.Cu")
		(net "XM_ADDR_21")
	)
	(segment
		(start 168.952164 -68.309236)
		(end 168.021 -69.2404)
		(width 0.127)
		(layer "In5.Cu")
		(net "XM_ADDR_21")
	)
	(segment
		(start 167.006524 -69.1134)
		(end 167.006524 -68.6054)
		(width 0.127)
		(layer "In5.Cu")
		(net "XM_ADDR_21")
	)
	(segment
		(start 168.772586 -67.231006)
		(end 168.592754 -67.231006)
		(width 0.127)
		(layer "In5.Cu")
		(net "XM_ADDR_21")
	)
	(segment
		(start 167.133524 -69.2404)
		(end 167.006524 -69.1134)
		(width 0.127)
		(layer "In5.Cu")
		(net "XM_ADDR_21")
	)
	(segment
		(start 175.563276 -64.354456)
		(end 175.383698 -64.534034)
		(width 0.127)
		(layer "In5.Cu")
		(net "XM_ADDR_21")
	)
	(segment
		(start 176.102518 -63.815214)
		(end 176.102518 -63.995046)
		(width 0.127)
		(layer "In5.Cu")
		(net "XM_ADDR_21")
	)
	(segment
		(start 176.102518 -63.995046)
		(end 177.49012 -65.382648)
		(width 0.127)
		(layer "In5.Cu")
		(net "XM_ADDR_21")
	)
	(segment
		(start 177.31613 -64.489838)
		(end 176.461928 -63.635636)
		(width 0.127)
		(layer "In5.Cu")
		(net "XM_ADDR_21")
	)
	(segment
		(start 177.49012 -65.382648)
		(end 177.49012 -65.56248)
		(width 0.127)
		(layer "In5.Cu")
		(net "XM_ADDR_21")
	)
	(segment
		(start 168.021 -69.2404)
		(end 167.133524 -69.2404)
		(width 0.127)
		(layer "In5.Cu")
		(net "XM_ADDR_21")
	)
	(segment
		(start 167.531796 -68.471796)
		(end 167.711374 -68.651374)
		(width 0.127)
		(layer "In5.Cu")
		(net "XM_ADDR_21")
	)
	(segment
		(start 168.592754 -67.231006)
		(end 167.531796 -68.291964)
		(width 0.127)
		(layer "In5.Cu")
		(net "XM_ADDR_21")
	)
	(segment
		(start 174.511716 -66.034666)
		(end 174.087282 -66.4591)
		(width 0.127)
		(layer "In5.Cu")
		(net "XM_ADDR_21")
	)
	(segment
		(start 177.310542 -65.742058)
		(end 177.13071 -65.742058)
		(width 0.127)
		(layer "In5.Cu")
		(net "XM_ADDR_21")
	)
	(segment
		(start 176.461928 -63.635636)
		(end 176.282096 -63.635636)
		(width 0.127)
		(layer "In5.Cu")
		(net "XM_ADDR_21")
	)
	(segment
		(start 174.844456 -65.073276)
		(end 174.511716 -65.406016)
		(width 0.127)
		(layer "In5.Cu")
		(net "XM_ADDR_21")
	)
	(segment
		(start 174.511716 -65.406016)
		(end 174.511716 -66.034666)
		(width 0.127)
		(layer "In5.Cu")
		(net "XM_ADDR_21")
	)
	(segment
		(start 176.636172 -66.505328)
		(end 176.45634 -66.505328)
		(width 0.127)
		(layer "In5.Cu")
		(net "XM_ADDR_21")
	)
	(segment
		(start 174.087282 -66.4591)
		(end 170.8023 -66.4591)
		(width 0.127)
		(layer "In5.Cu")
		(net "XM_ADDR_21")
	)
	(segment
		(start 179.204366 -58.690256)
		(end 179.204366 -58.870088)
		(width 0.0889)
		(layer "In5.Cu")
		(net "XM_ADDR_21")
	)
	(segment
		(start 175.383698 -64.713866)
		(end 176.81575 -66.145918)
		(width 0.127)
		(layer "In5.Cu")
		(net "XM_ADDR_21")
	)
	(segment
		(start 168.772586 -67.949826)
		(end 168.952164 -68.129404)
		(width 0.127)
		(layer "In5.Cu")
		(net "XM_ADDR_21")
	)
	(segment
		(start 166.879524 -68.4784)
		(end 166.625524 -68.4784)
		(width 0.127)
		(layer "In5.Cu")
		(net "XM_ADDR_21")
	)
	(segment
		(start 166.498524 -68.6054)
		(end 166.498524 -69.1134)
		(width 0.127)
		(layer "In5.Cu")
		(net "XM_ADDR_21")
	)
	(segment
		(start 176.821338 -63.096394)
		(end 176.821338 -63.276226)
		(width 0.127)
		(layer "In5.Cu")
		(net "XM_ADDR_21")
	)
	(segment
		(start 177.9143 -62.003432)
		(end 176.821338 -63.096394)
		(width 0.127)
		(layer "In5.Cu")
		(net "XM_ADDR_21")
	)
	(segment
		(start 169.311574 -67.769994)
		(end 168.772586 -67.231006)
		(width 0.127)
		(layer "In5.Cu")
		(net "XM_ADDR_21")
	)
	(segment
		(start 176.81575 -66.145918)
		(end 176.81575 -66.32575)
		(width 0.127)
		(layer "In5.Cu")
		(net "XM_ADDR_21")
	)
	(segment
		(start 166.498524 -69.1134)
		(end 166.371524 -69.2404)
		(width 0.127)
		(layer "In5.Cu")
		(net "XM_ADDR_21")
	)
	(segment
		(start 167.531796 -68.291964)
		(end 167.531796 -68.471796)
		(width 0.127)
		(layer "In5.Cu")
		(net "XM_ADDR_21")
	)
	(segment
		(start 177.495962 -64.489838)
		(end 177.31613 -64.489838)
		(width 0.127)
		(layer "In5.Cu")
		(net "XM_ADDR_21")
	)
	(segment
		(start 167.006524 -68.6054)
		(end 166.879524 -68.4784)
		(width 0.127)
		(layer "In5.Cu")
		(net "XM_ADDR_21")
	)
	(segment
		(start 177.49012 -65.56248)
		(end 177.310542 -65.742058)
		(width 0.127)
		(layer "In5.Cu")
		(net "XM_ADDR_21")
	)
	(segment
		(start 169.491406 -67.769994)
		(end 169.311574 -67.769994)
		(width 0.127)
		(layer "In5.Cu")
		(net "XM_ADDR_21")
	)
	(segment
		(start 176.45634 -66.505328)
		(end 175.024288 -65.073276)
		(width 0.127)
		(layer "In5.Cu")
		(net "XM_ADDR_21")
	)
	(segment
		(start 177.9143 -60.160154)
		(end 177.9143 -62.003432)
		(width 0.127)
		(layer "In5.Cu")
		(net "XM_ADDR_21")
	)
	(segment
		(start 177.13071 -65.742058)
		(end 175.743108 -64.354456)
		(width 0.127)
		(layer "In5.Cu")
		(net "XM_ADDR_21")
	)
	(segment
		(start 170.8023 -66.4591)
		(end 169.491406 -67.769994)
		(width 0.127)
		(layer "In5.Cu")
		(net "XM_ADDR_21")
	)
	(segment
		(start 175.743108 -64.354456)
		(end 175.563276 -64.354456)
		(width 0.127)
		(layer "In5.Cu")
		(net "XM_ADDR_21")
	)
	(segment
		(start 176.282096 -63.635636)
		(end 176.102518 -63.815214)
		(width 0.127)
		(layer "In5.Cu")
		(net "XM_ADDR_21")
	)
	(segment
		(start 175.024288 -65.073276)
		(end 174.844456 -65.073276)
		(width 0.127)
		(layer "In5.Cu")
		(net "XM_ADDR_21")
	)
	(segment
		(start 167.711374 -68.651374)
		(end 167.891206 -68.651374)
		(width 0.127)
		(layer "In5.Cu")
		(net "XM_ADDR_21")
	)
	(segment
		(start 178.07305 -60.001404)
		(end 177.9143 -60.160154)
		(width 0.127)
		(layer "In5.Cu")
		(net "XM_ADDR_21")
	)
	(segment
		(start 166.625524 -68.4784)
		(end 166.498524 -68.6054)
		(width 0.127)
		(layer "In5.Cu")
		(net "XM_ADDR_21")
	)
	(segment
		(start 179.204366 -58.870088)
		(end 178.07305 -60.001404)
		(width 0.0889)
		(layer "In5.Cu")
		(net "XM_ADDR_21")
	)
	(segment
		(start 176.81575 -66.32575)
		(end 176.636172 -66.505328)
		(width 0.127)
		(layer "In5.Cu")
		(net "XM_ADDR_21")
	)
	(segment
		(start 176.821338 -63.276226)
		(end 177.67554 -64.130428)
		(width 0.127)
		(layer "In5.Cu")
		(net "XM_ADDR_21")
	)
	(segment
		(start 168.952164 -68.129404)
		(end 168.952164 -68.309236)
		(width 0.127)
		(layer "In5.Cu")
		(net "XM_ADDR_21")
	)
	(segment
		(start 167.891206 -68.651374)
		(end 168.592754 -67.949826)
		(width 0.127)
		(layer "In5.Cu")
		(net "XM_ADDR_21")
	)
	(segment
		(start 178.95951 -57.500012)
		(end 181.200044 -57.500012)
		(width 0.127)
		(layer "F.Cu")
		(net "XM_ADDR_20")
	)
	(segment
		(start 178.886866 -57.572656)
		(end 178.95951 -57.500012)
		(width 0.127)
		(layer "F.Cu")
		(net "XM_ADDR_20")
	)
	(via
		(at 178.886866 -57.572656)
		(size 0.508)
		(drill 0.254)
		(layers "F.Cu" "B.Cu")
		(net "XM_ADDR_20")
	)
	(via
		(at 163.1442 -70.2183)
		(size 0.508)
		(drill 0.254)
		(layers "F.Cu" "B.Cu")
		(net "XM_ADDR_20")
	)
	(segment
		(start 162.99434 -72.8853)
		(end 162.99434 -70.36816)
		(width 0.127)
		(layer "B.Cu")
		(net "XM_ADDR_20")
	)
	(segment
		(start 162.99434 -70.36816)
		(end 163.1442 -70.2183)
		(width 0.127)
		(layer "B.Cu")
		(net "XM_ADDR_20")
	)
	(segment
		(start 174.5615 -63.701676)
		(end 174.5615 -63.881254)
		(width 0.127)
		(layer "In5.Cu")
		(net "XM_ADDR_20")
	)
	(segment
		(start 177.03673 -59.538362)
		(end 176.856644 -59.718448)
		(width 0.127)
		(layer "In5.Cu")
		(net "XM_ADDR_20")
	)
	(segment
		(start 174.5615 -63.881254)
		(end 174.381414 -64.06134)
		(width 0.127)
		(layer "In5.Cu")
		(net "XM_ADDR_20")
	)
	(segment
		(start 164.295074 -68.267326)
		(end 164.295074 -68.447158)
		(width 0.127)
		(layer "In5.Cu")
		(net "XM_ADDR_20")
	)
	(segment
		(start 178.715162 -57.923684)
		(end 178.244246 -58.3946)
		(width 0.127)
		(layer "In5.Cu")
		(net "XM_ADDR_20")
	)
	(segment
		(start 176.856644 -59.718448)
		(end 176.67732 -59.718448)
		(width 0.127)
		(layer "In5.Cu")
		(net "XM_ADDR_20")
	)
	(segment
		(start 162.8013 -70.5612)
		(end 163.1442 -70.2183)
		(width 0.127)
		(layer "In5.Cu")
		(net "XM_ADDR_20")
	)
	(segment
		(start 164.959792 -68.393056)
		(end 164.654484 -68.087748)
		(width 0.127)
		(layer "In5.Cu")
		(net "XM_ADDR_20")
	)
	(segment
		(start 174.381414 -64.06134)
		(end 174.20209 -64.06134)
		(width 0.127)
		(layer "In5.Cu")
		(net "XM_ADDR_20")
	)
	(segment
		(start 172.064172 -63.3349)
		(end 171.937172 -63.2079)
		(width 0.127)
		(layer "In5.Cu")
		(net "XM_ADDR_20")
	)
	(segment
		(start 171.04741 -63.2079)
		(end 167.58031 -66.675)
		(width 0.127)
		(layer "In5.Cu")
		(net "XM_ADDR_20")
	)
	(segment
		(start 178.244246 -58.3946)
		(end 177.083466 -58.3946)
		(width 0.127)
		(layer "In5.Cu")
		(net "XM_ADDR_20")
	)
	(segment
		(start 177.083466 -58.3946)
		(end 176.667414 -58.810652)
		(width 0.127)
		(layer "In5.Cu")
		(net "XM_ADDR_20")
	)
	(segment
		(start 176.667414 -58.810652)
		(end 176.667414 -58.989976)
		(width 0.127)
		(layer "In5.Cu")
		(net "XM_ADDR_20")
	)
	(segment
		(start 175.77435 -62.578996)
		(end 175.595026 -62.578996)
		(width 0.127)
		(layer "In5.Cu")
		(net "XM_ADDR_20")
	)
	(segment
		(start 173.90999 -62.331346)
		(end 173.730666 -62.331346)
		(width 0.127)
		(layer "In5.Cu")
		(net "XM_ADDR_20")
	)
	(segment
		(start 172.445172 -64.4144)
		(end 172.191172 -64.4144)
		(width 0.127)
		(layer "In5.Cu")
		(net "XM_ADDR_20")
	)
	(segment
		(start 174.449486 -61.612526)
		(end 174.2694 -61.792612)
		(width 0.127)
		(layer "In5.Cu")
		(net "XM_ADDR_20")
	)
	(segment
		(start 174.2694 -61.97219)
		(end 175.28032 -62.98311)
		(width 0.127)
		(layer "In5.Cu")
		(net "XM_ADDR_20")
	)
	(segment
		(start 165.139624 -68.393056)
		(end 164.959792 -68.393056)
		(width 0.127)
		(layer "In5.Cu")
		(net "XM_ADDR_20")
	)
	(segment
		(start 167.58031 -66.675)
		(end 166.85768 -66.675)
		(width 0.127)
		(layer "In5.Cu")
		(net "XM_ADDR_20")
	)
	(segment
		(start 175.954436 -62.219332)
		(end 175.954436 -62.39891)
		(width 0.127)
		(layer "In5.Cu")
		(net "XM_ADDR_20")
	)
	(segment
		(start 161.5313 -69.4309)
		(end 161.5313 -70.3834)
		(width 0.127)
		(layer "In5.Cu")
		(net "XM_ADDR_20")
	)
	(segment
		(start 175.100488 -63.342266)
		(end 174.92091 -63.342266)
		(width 0.127)
		(layer "In5.Cu")
		(net "XM_ADDR_20")
	)
	(segment
		(start 176.308004 -59.349386)
		(end 176.12868 -59.349386)
		(width 0.127)
		(layer "In5.Cu")
		(net "XM_ADDR_20")
	)
	(segment
		(start 173.730666 -62.331346)
		(end 173.55058 -62.511432)
		(width 0.127)
		(layer "In5.Cu")
		(net "XM_ADDR_20")
	)
	(segment
		(start 174.98822 -61.073792)
		(end 174.98822 -61.253116)
		(width 0.127)
		(layer "In5.Cu")
		(net "XM_ADDR_20")
	)
	(segment
		(start 164.600382 -68.932298)
		(end 164.26688 -69.2658)
		(width 0.127)
		(layer "In5.Cu")
		(net "XM_ADDR_20")
	)
	(segment
		(start 161.7091 -70.5612)
		(end 162.8013 -70.5612)
		(width 0.127)
		(layer "In5.Cu")
		(net "XM_ADDR_20")
	)
	(segment
		(start 175.28032 -63.162434)
		(end 175.100488 -63.342266)
		(width 0.127)
		(layer "In5.Cu")
		(net "XM_ADDR_20")
	)
	(segment
		(start 174.2694 -61.792612)
		(end 174.2694 -61.97219)
		(width 0.127)
		(layer "In5.Cu")
		(net "XM_ADDR_20")
	)
	(segment
		(start 178.886866 -57.572656)
		(end 178.886866 -57.671716)
		(width 0.127)
		(layer "In5.Cu")
		(net "XM_ADDR_20")
	)
	(segment
		(start 173.34865 -63.2079)
		(end 172.699172 -63.2079)
		(width 0.127)
		(layer "In5.Cu")
		(net "XM_ADDR_20")
	)
	(segment
		(start 176.667414 -58.989976)
		(end 177.03673 -59.359038)
		(width 0.127)
		(layer "In5.Cu")
		(net "XM_ADDR_20")
	)
	(segment
		(start 173.55058 -62.690756)
		(end 174.5615 -63.701676)
		(width 0.127)
		(layer "In5.Cu")
		(net "XM_ADDR_20")
	)
	(segment
		(start 164.600382 -68.752466)
		(end 164.600382 -68.932298)
		(width 0.127)
		(layer "In5.Cu")
		(net "XM_ADDR_20")
	)
	(segment
		(start 173.55058 -62.511432)
		(end 173.55058 -62.690756)
		(width 0.127)
		(layer "In5.Cu")
		(net "XM_ADDR_20")
	)
	(segment
		(start 172.572172 -63.3349)
		(end 172.572172 -64.2874)
		(width 0.127)
		(layer "In5.Cu")
		(net "XM_ADDR_20")
	)
	(segment
		(start 172.191172 -64.4144)
		(end 172.064172 -64.2874)
		(width 0.127)
		(layer "In5.Cu")
		(net "XM_ADDR_20")
	)
	(segment
		(start 178.886866 -57.671716)
		(end 178.715162 -57.84342)
		(width 0.127)
		(layer "In5.Cu")
		(net "XM_ADDR_20")
	)
	(segment
		(start 172.572172 -64.2874)
		(end 172.445172 -64.4144)
		(width 0.127)
		(layer "In5.Cu")
		(net "XM_ADDR_20")
	)
	(segment
		(start 176.67732 -59.718448)
		(end 176.308004 -59.349386)
		(width 0.127)
		(layer "In5.Cu")
		(net "XM_ADDR_20")
	)
	(segment
		(start 174.20209 -64.06134)
		(end 173.34865 -63.2079)
		(width 0.127)
		(layer "In5.Cu")
		(net "XM_ADDR_20")
	)
	(segment
		(start 171.937172 -63.2079)
		(end 171.04741 -63.2079)
		(width 0.127)
		(layer "In5.Cu")
		(net "XM_ADDR_20")
	)
	(segment
		(start 176.12868 -59.349386)
		(end 175.9585 -59.519566)
		(width 0.127)
		(layer "In5.Cu")
		(net "XM_ADDR_20")
	)
	(segment
		(start 177.03673 -59.359038)
		(end 177.03673 -59.538362)
		(width 0.127)
		(layer "In5.Cu")
		(net "XM_ADDR_20")
	)
	(segment
		(start 172.699172 -63.2079)
		(end 172.572172 -63.3349)
		(width 0.127)
		(layer "In5.Cu")
		(net "XM_ADDR_20")
	)
	(segment
		(start 175.954436 -62.39891)
		(end 175.77435 -62.578996)
		(width 0.127)
		(layer "In5.Cu")
		(net "XM_ADDR_20")
	)
	(segment
		(start 175.28032 -62.98311)
		(end 175.28032 -63.162434)
		(width 0.127)
		(layer "In5.Cu")
		(net "XM_ADDR_20")
	)
	(segment
		(start 172.064172 -64.2874)
		(end 172.064172 -63.3349)
		(width 0.127)
		(layer "In5.Cu")
		(net "XM_ADDR_20")
	)
	(segment
		(start 174.98822 -61.253116)
		(end 175.954436 -62.219332)
		(width 0.127)
		(layer "In5.Cu")
		(net "XM_ADDR_20")
	)
	(segment
		(start 166.85768 -66.675)
		(end 165.139624 -68.393056)
		(width 0.127)
		(layer "In5.Cu")
		(net "XM_ADDR_20")
	)
	(segment
		(start 175.683418 -60.8457)
		(end 175.216566 -60.8457)
		(width 0.127)
		(layer "In5.Cu")
		(net "XM_ADDR_20")
	)
	(segment
		(start 174.628556 -61.612526)
		(end 174.449486 -61.612526)
		(width 0.127)
		(layer "In5.Cu")
		(net "XM_ADDR_20")
	)
	(segment
		(start 161.6964 -69.2658)
		(end 161.5313 -69.4309)
		(width 0.127)
		(layer "In5.Cu")
		(net "XM_ADDR_20")
	)
	(segment
		(start 164.26688 -69.2658)
		(end 161.6964 -69.2658)
		(width 0.127)
		(layer "In5.Cu")
		(net "XM_ADDR_20")
	)
	(segment
		(start 161.5313 -70.3834)
		(end 161.7091 -70.5612)
		(width 0.127)
		(layer "In5.Cu")
		(net "XM_ADDR_20")
	)
	(segment
		(start 175.595026 -62.578996)
		(end 174.628556 -61.612526)
		(width 0.127)
		(layer "In5.Cu")
		(net "XM_ADDR_20")
	)
	(segment
		(start 164.474652 -68.087748)
		(end 164.295074 -68.267326)
		(width 0.127)
		(layer "In5.Cu")
		(net "XM_ADDR_20")
	)
	(segment
		(start 164.295074 -68.447158)
		(end 164.600382 -68.752466)
		(width 0.127)
		(layer "In5.Cu")
		(net "XM_ADDR_20")
	)
	(segment
		(start 178.715162 -57.84342)
		(end 178.715162 -57.923684)
		(width 0.127)
		(layer "In5.Cu")
		(net "XM_ADDR_20")
	)
	(segment
		(start 174.92091 -63.342266)
		(end 173.90999 -62.331346)
		(width 0.127)
		(layer "In5.Cu")
		(net "XM_ADDR_20")
	)
	(segment
		(start 175.216566 -60.8457)
		(end 174.98822 -61.073792)
		(width 0.127)
		(layer "In5.Cu")
		(net "XM_ADDR_20")
	)
	(segment
		(start 164.654484 -68.087748)
		(end 164.474652 -68.087748)
		(width 0.127)
		(layer "In5.Cu")
		(net "XM_ADDR_20")
	)
	(segment
		(start 175.9585 -59.519566)
		(end 175.9585 -60.570618)
		(width 0.127)
		(layer "In5.Cu")
		(net "XM_ADDR_20")
	)
	(segment
		(start 175.9585 -60.570618)
		(end 175.683418 -60.8457)
		(width 0.127)
		(layer "In5.Cu")
		(net "XM_ADDR_20")
	)
	(segment
		(start 183.252364 -53.318156)
		(end 183.252364 -54.75224)
		(width 0.127)
		(layer "F.Cu")
		(net "XM_ADDR_2")
	)
	(segment
		(start 182.6895 -46.237398)
		(end 183.102758 -45.82414)
		(width 0.127)
		(layer "F.Cu")
		(net "XM_ADDR_2")
	)
	(segment
		(start 183.469788 -53.100732)
		(end 183.252364 -53.318156)
		(width 0.127)
		(layer "F.Cu")
		(net "XM_ADDR_2")
	)
	(segment
		(start 183.284114 -45.642784)
		(end 183.103012 -45.823886)
		(width 0.127)
		(layer "F.Cu")
		(net "XM_ADDR_2")
	)
	(segment
		(start 182.88 -48.47336)
		(end 182.6895 -48.28286)
		(width 0.127)
		(layer "F.Cu")
		(net "XM_ADDR_2")
	)
	(segment
		(start 182.6895 -48.28286)
		(end 182.6895 -46.237398)
		(width 0.127)
		(layer "F.Cu")
		(net "XM_ADDR_2")
	)
	(segment
		(start 183.252364 -54.75224)
		(end 183.60009 -55.099966)
		(width 0.127)
		(layer "F.Cu")
		(net "XM_ADDR_2")
	)
	(segment
		(start 183.102758 -45.82414)
		(end 183.103012 -45.82414)
		(width 0.127)
		(layer "F.Cu")
		(net "XM_ADDR_2")
	)
	(segment
		(start 183.469788 -51.03749)
		(end 182.88 -50.447702)
		(width 0.127)
		(layer "F.Cu")
		(net "XM_ADDR_2")
	)
	(segment
		(start 183.469788 -51.03749)
		(end 183.469788 -53.100732)
		(width 0.127)
		(layer "F.Cu")
		(net "XM_ADDR_2")
	)
	(segment
		(start 183.103012 -45.823886)
		(end 183.103012 -45.82414)
		(width 0.127)
		(layer "F.Cu")
		(net "XM_ADDR_2")
	)
	(segment
		(start 182.88 -50.447702)
		(end 182.88 -48.47336)
		(width 0.127)
		(layer "F.Cu")
		(net "XM_ADDR_2")
	)
	(segment
		(start 184.322212 -45.832268)
		(end 184.132728 -45.642784)
		(width 0.127)
		(layer "F.Cu")
		(net "XM_ADDR_2")
	)
	(segment
		(start 184.132728 -45.642784)
		(end 183.284114 -45.642784)
		(width 0.127)
		(layer "F.Cu")
		(net "XM_ADDR_2")
	)
	(via
		(at 183.103012 -45.82414)
		(size 0.6604)
		(drill 0.3302)
		(layers "F.Cu" "B.Cu")
		(net "XM_ADDR_2")
	)
	(via
		(at 163.961064 -57.234836)
		(size 0.508)
		(drill 0.254)
		(layers "F.Cu" "B.Cu")
		(net "XM_ADDR_2")
	)
	(via
		(at 183.469788 -51.03749)
		(size 0.508)
		(drill 0.254)
		(layers "F.Cu" "B.Cu")
		(net "XM_ADDR_2")
	)
	(segment
		(start 163.961064 -57.234836)
		(end 163.961064 -59.973464)
		(width 0.127)
		(layer "B.Cu")
		(net "XM_ADDR_2")
	)
	(segment
		(start 163.961064 -59.973464)
		(end 170.53433 -66.54673)
		(width 0.127)
		(layer "B.Cu")
		(net "XM_ADDR_2")
	)
	(segment
		(start 170.53433 -66.54673)
		(end 170.53433 -70.593966)
		(width 0.127)
		(layer "B.Cu")
		(net "XM_ADDR_2")
	)
	(segment
		(start 170.53433 -70.593966)
		(end 170.49496 -70.633336)
		(width 0.127)
		(layer "B.Cu")
		(net "XM_ADDR_2")
	)
	(segment
		(start 170.49496 -70.633336)
		(end 170.49496 -72.8853)
		(width 0.127)
		(layer "B.Cu")
		(net "XM_ADDR_2")
	)
	(segment
		(start 182.974234 -50.353468)
		(end 182.974234 -50.541936)
		(width 0.127)
		(layer "In5.Cu")
		(net "XM_ADDR_2")
	)
	(segment
		(start 182.974234 -50.541936)
		(end 183.469788 -51.03749)
		(width 0.127)
		(layer "In5.Cu")
		(net "XM_ADDR_2")
	)
	(segment
		(start 163.961064 -57.234836)
		(end 165.24351 -57.234836)
		(width 0.127)
		(layer "In5.Cu")
		(net "XM_ADDR_2")
	)
	(segment
		(start 181.757066 -49.1363)
		(end 182.974234 -50.353468)
		(width 0.127)
		(layer "In5.Cu")
		(net "XM_ADDR_2")
	)
	(segment
		(start 172.945298 -50.35804)
		(end 174.167038 -49.1363)
		(width 0.127)
		(layer "In5.Cu")
		(net "XM_ADDR_2")
	)
	(segment
		(start 172.120306 -50.35804)
		(end 172.945298 -50.35804)
		(width 0.127)
		(layer "In5.Cu")
		(net "XM_ADDR_2")
	)
	(segment
		(start 174.167038 -49.1363)
		(end 181.757066 -49.1363)
		(width 0.127)
		(layer "In5.Cu")
		(net "XM_ADDR_2")
	)
	(segment
		(start 165.24351 -57.234836)
		(end 172.120306 -50.35804)
		(width 0.127)
		(layer "In5.Cu")
		(net "XM_ADDR_2")
	)
	(segment
		(start 182.79999 -57.500012)
		(end 182.400194 -57.899808)
		(width 0.127)
		(layer "F.Cu")
		(net "XM_ADDR_19")
	)
	(via
		(at 182.400194 -57.899808)
		(size 0.508)
		(drill 0.254)
		(layers "F.Cu" "B.Cu")
		(net "XM_ADDR_19")
	)
	(via
		(at 165.8239 -68.4784)
		(size 0.508)
		(drill 0.254)
		(layers "F.Cu" "B.Cu")
		(net "XM_ADDR_19")
	)
	(segment
		(start 166.248334 -71.608442)
		(end 166.49446 -71.854568)
		(width 0.127)
		(layer "B.Cu")
		(net "XM_ADDR_19")
	)
	(segment
		(start 166.248334 -68.6054)
		(end 166.248334 -71.608442)
		(width 0.127)
		(layer "B.Cu")
		(net "XM_ADDR_19")
	)
	(segment
		(start 165.8239 -68.4784)
		(end 166.121334 -68.4784)
		(width 0.127)
		(layer "B.Cu")
		(net "XM_ADDR_19")
	)
	(segment
		(start 166.121334 -68.4784)
		(end 166.248334 -68.6054)
		(width 0.127)
		(layer "B.Cu")
		(net "XM_ADDR_19")
	)
	(segment
		(start 166.49446 -71.854568)
		(end 166.49446 -72.8853)
		(width 0.127)
		(layer "B.Cu")
		(net "XM_ADDR_19")
	)
	(segment
		(start 180.792882 -58.4581)
		(end 180.970682 -58.4581)
		(width 0.0889)
		(layer "In5.Cu")
		(net "XM_ADDR_19")
	)
	(segment
		(start 176.972214 -62.047628)
		(end 177.151538 -62.047628)
		(width 0.127)
		(layer "In5.Cu")
		(net "XM_ADDR_19")
	)
	(segment
		(start 177.4063 -60.164472)
		(end 177.4063 -59.949588)
		(width 0.127)
		(layer "In5.Cu")
		(net "XM_ADDR_19")
	)
	(segment
		(start 177.708306 -59.46775)
		(end 177.567844 -59.327288)
		(width 0.127)
		(layer "In5.Cu")
		(net "XM_ADDR_19")
	)
	(segment
		(start 177.927254 -58.967878)
		(end 178.067716 -59.10834)
		(width 0.127)
		(layer "In5.Cu")
		(net "XM_ADDR_19")
	)
	(segment
		(start 181.059582 -58.3692)
		(end 181.059582 -57.988708)
		(width 0.0889)
		(layer "In5.Cu")
		(net "XM_ADDR_19")
	)
	(segment
		(start 167.790876 -67.183)
		(end 170.038776 -64.9351)
		(width 0.127)
		(layer "In5.Cu")
		(net "XM_ADDR_19")
	)
	(segment
		(start 167.1193 -67.183)
		(end 167.790876 -67.183)
		(width 0.127)
		(layer "In5.Cu")
		(net "XM_ADDR_19")
	)
	(segment
		(start 177.4063 -60.926472)
		(end 177.2793 -60.799472)
		(width 0.127)
		(layer "In5.Cu")
		(net "XM_ADDR_19")
	)
	(segment
		(start 165.8239 -68.4784)
		(end 167.1193 -67.183)
		(width 0.127)
		(layer "In5.Cu")
		(net "XM_ADDR_19")
	)
	(segment
		(start 178.247548 -59.10834)
		(end 178.520344 -58.835544)
		(width 0.127)
		(layer "In5.Cu")
		(net "XM_ADDR_19")
	)
	(segment
		(start 171.033948 -64.0207)
		(end 171.160948 -63.8937)
		(width 0.127)
		(layer "In5.Cu")
		(net "XM_ADDR_19")
	)
	(segment
		(start 180.703982 -57.988708)
		(end 180.703982 -58.3692)
		(width 0.0889)
		(layer "In5.Cu")
		(net "XM_ADDR_19")
	)
	(segment
		(start 174.003716 -65.8241)
		(end 174.003716 -65.0621)
		(width 0.127)
		(layer "In5.Cu")
		(net "XM_ADDR_19")
	)
	(segment
		(start 174.003716 -65.0621)
		(end 174.130716 -64.9351)
		(width 0.127)
		(layer "In5.Cu")
		(net "XM_ADDR_19")
	)
	(segment
		(start 180.970682 -58.4581)
		(end 181.059582 -58.3692)
		(width 0.0889)
		(layer "In5.Cu")
		(net "XM_ADDR_19")
	)
	(segment
		(start 176.612804 -62.586362)
		(end 176.612804 -62.407038)
		(width 0.127)
		(layer "In5.Cu")
		(net "XM_ADDR_19")
	)
	(segment
		(start 171.668948 -64.9351)
		(end 173.368716 -64.9351)
		(width 0.127)
		(layer "In5.Cu")
		(net "XM_ADDR_19")
	)
	(segment
		(start 174.130716 -64.9351)
		(end 174.264066 -64.9351)
		(width 0.127)
		(layer "In5.Cu")
		(net "XM_ADDR_19")
	)
	(segment
		(start 177.567844 -59.327288)
		(end 177.567844 -59.147456)
		(width 0.127)
		(layer "In5.Cu")
		(net "XM_ADDR_19")
	)
	(segment
		(start 176.5046 -60.418472)
		(end 176.6316 -60.291472)
		(width 0.127)
		(layer "In5.Cu")
		(net "XM_ADDR_19")
	)
	(segment
		(start 169.408094 -66.931794)
		(end 169.587926 -66.931794)
		(width 0.127)
		(layer "In5.Cu")
		(net "XM_ADDR_19")
	)
	(segment
		(start 171.541948 -64.0207)
		(end 171.541948 -64.8081)
		(width 0.127)
		(layer "In5.Cu")
		(net "XM_ADDR_19")
	)
	(segment
		(start 177.708306 -59.647582)
		(end 177.708306 -59.46775)
		(width 0.127)
		(layer "In5.Cu")
		(net "XM_ADDR_19")
	)
	(segment
		(start 177.2793 -60.291472)
		(end 177.4063 -60.164472)
		(width 0.127)
		(layer "In5.Cu")
		(net "XM_ADDR_19")
	)
	(segment
		(start 181.504082 -58.4581)
		(end 181.681882 -58.4581)
		(width 0.0889)
		(layer "In5.Cu")
		(net "XM_ADDR_19")
	)
	(segment
		(start 178.804316 -58.551572)
		(end 178.804316 -58.380884)
		(width 0.0889)
		(layer "In5.Cu")
		(net "XM_ADDR_19")
	)
	(segment
		(start 173.495716 -65.0621)
		(end 173.495716 -65.3161)
		(width 0.127)
		(layer "In5.Cu")
		(net "XM_ADDR_19")
	)
	(segment
		(start 169.228516 -66.572384)
		(end 169.228516 -66.752216)
		(width 0.127)
		(layer "In5.Cu")
		(net "XM_ADDR_19")
	)
	(segment
		(start 181.326282 -57.899808)
		(end 181.415182 -57.988708)
		(width 0.0889)
		(layer "In5.Cu")
		(net "XM_ADDR_19")
	)
	(segment
		(start 173.876716 -65.9511)
		(end 174.003716 -65.8241)
		(width 0.127)
		(layer "In5.Cu")
		(net "XM_ADDR_19")
	)
	(segment
		(start 179.285392 -57.899808)
		(end 180.615082 -57.899808)
		(width 0.0889)
		(layer "In5.Cu")
		(net "XM_ADDR_19")
	)
	(segment
		(start 171.160948 -63.8937)
		(end 171.414948 -63.8937)
		(width 0.127)
		(layer "In5.Cu")
		(net "XM_ADDR_19")
	)
	(segment
		(start 171.033948 -64.8081)
		(end 171.033948 -64.0207)
		(width 0.127)
		(layer "In5.Cu")
		(net "XM_ADDR_19")
	)
	(segment
		(start 177.567844 -59.147456)
		(end 177.747422 -58.967878)
		(width 0.127)
		(layer "In5.Cu")
		(net "XM_ADDR_19")
	)
	(segment
		(start 170.906948 -64.9351)
		(end 171.033948 -64.8081)
		(width 0.127)
		(layer "In5.Cu")
		(net "XM_ADDR_19")
	)
	(segment
		(start 178.804316 -58.380884)
		(end 179.285392 -57.899808)
		(width 0.0889)
		(layer "In5.Cu")
		(net "XM_ADDR_19")
	)
	(segment
		(start 170.038776 -64.9351)
		(end 170.906948 -64.9351)
		(width 0.127)
		(layer "In5.Cu")
		(net "XM_ADDR_19")
	)
	(segment
		(start 169.228516 -66.752216)
		(end 169.408094 -66.931794)
		(width 0.127)
		(layer "In5.Cu")
		(net "XM_ADDR_19")
	)
	(segment
		(start 170.56862 -65.9511)
		(end 173.876716 -65.9511)
		(width 0.127)
		(layer "In5.Cu")
		(net "XM_ADDR_19")
	)
	(segment
		(start 180.703982 -58.3692)
		(end 180.792882 -58.4581)
		(width 0.0889)
		(layer "In5.Cu")
		(net "XM_ADDR_19")
	)
	(segment
		(start 170.3578 -65.4431)
		(end 169.228516 -66.572384)
		(width 0.127)
		(layer "In5.Cu")
		(net "XM_ADDR_19")
	)
	(segment
		(start 176.471072 -62.26556)
		(end 176.471072 -62.086236)
		(width 0.127)
		(layer "In5.Cu")
		(net "XM_ADDR_19")
	)
	(segment
		(start 171.414948 -63.8937)
		(end 171.541948 -64.0207)
		(width 0.127)
		(layer "In5.Cu")
		(net "XM_ADDR_19")
	)
	(segment
		(start 173.368716 -65.4431)
		(end 170.3578 -65.4431)
		(width 0.127)
		(layer "In5.Cu")
		(net "XM_ADDR_19")
	)
	(segment
		(start 181.859682 -57.899808)
		(end 182.400194 -57.899808)
		(width 0.0889)
		(layer "In5.Cu")
		(net "XM_ADDR_19")
	)
	(segment
		(start 176.612804 -62.407038)
		(end 176.471072 -62.26556)
		(width 0.127)
		(layer "In5.Cu")
		(net "XM_ADDR_19")
	)
	(segment
		(start 173.368716 -64.9351)
		(end 173.495716 -65.0621)
		(width 0.127)
		(layer "In5.Cu")
		(net "XM_ADDR_19")
	)
	(segment
		(start 180.615082 -57.899808)
		(end 180.703982 -57.988708)
		(width 0.0889)
		(layer "In5.Cu")
		(net "XM_ADDR_19")
	)
	(segment
		(start 181.415182 -57.988708)
		(end 181.415182 -58.3692)
		(width 0.0889)
		(layer "In5.Cu")
		(net "XM_ADDR_19")
	)
	(segment
		(start 177.4063 -61.792866)
		(end 177.4063 -60.926472)
		(width 0.127)
		(layer "In5.Cu")
		(net "XM_ADDR_19")
	)
	(segment
		(start 181.059582 -57.988708)
		(end 181.148482 -57.899808)
		(width 0.0889)
		(layer "In5.Cu")
		(net "XM_ADDR_19")
	)
	(segment
		(start 181.770782 -58.3692)
		(end 181.770782 -57.988708)
		(width 0.0889)
		(layer "In5.Cu")
		(net "XM_ADDR_19")
	)
	(segment
		(start 174.264066 -64.9351)
		(end 176.612804 -62.586362)
		(width 0.127)
		(layer "In5.Cu")
		(net "XM_ADDR_19")
	)
	(segment
		(start 181.148482 -57.899808)
		(end 181.326282 -57.899808)
		(width 0.0889)
		(layer "In5.Cu")
		(net "XM_ADDR_19")
	)
	(segment
		(start 181.681882 -58.4581)
		(end 181.770782 -58.3692)
		(width 0.0889)
		(layer "In5.Cu")
		(net "XM_ADDR_19")
	)
	(segment
		(start 176.830482 -61.90615)
		(end 176.972214 -62.047628)
		(width 0.127)
		(layer "In5.Cu")
		(net "XM_ADDR_19")
	)
	(segment
		(start 178.067716 -59.10834)
		(end 178.247548 -59.10834)
		(width 0.127)
		(layer "In5.Cu")
		(net "XM_ADDR_19")
	)
	(segment
		(start 173.495716 -65.3161)
		(end 173.368716 -65.4431)
		(width 0.127)
		(layer "In5.Cu")
		(net "XM_ADDR_19")
	)
	(segment
		(start 176.6316 -60.799472)
		(end 176.5046 -60.672472)
		(width 0.127)
		(layer "In5.Cu")
		(net "XM_ADDR_19")
	)
	(segment
		(start 169.587926 -66.931794)
		(end 170.56862 -65.9511)
		(width 0.127)
		(layer "In5.Cu")
		(net "XM_ADDR_19")
	)
	(segment
		(start 176.651158 -61.90615)
		(end 176.830482 -61.90615)
		(width 0.127)
		(layer "In5.Cu")
		(net "XM_ADDR_19")
	)
	(segment
		(start 177.2793 -60.799472)
		(end 176.6316 -60.799472)
		(width 0.127)
		(layer "In5.Cu")
		(net "XM_ADDR_19")
	)
	(segment
		(start 176.6316 -60.291472)
		(end 177.2793 -60.291472)
		(width 0.127)
		(layer "In5.Cu")
		(net "XM_ADDR_19")
	)
	(segment
		(start 178.520344 -58.835544)
		(end 178.804316 -58.551572)
		(width 0.0889)
		(layer "In5.Cu")
		(net "XM_ADDR_19")
	)
	(segment
		(start 181.770782 -57.988708)
		(end 181.859682 -57.899808)
		(width 0.0889)
		(layer "In5.Cu")
		(net "XM_ADDR_19")
	)
	(segment
		(start 176.471072 -62.086236)
		(end 176.651158 -61.90615)
		(width 0.127)
		(layer "In5.Cu")
		(net "XM_ADDR_19")
	)
	(segment
		(start 176.5046 -60.672472)
		(end 176.5046 -60.418472)
		(width 0.127)
		(layer "In5.Cu")
		(net "XM_ADDR_19")
	)
	(segment
		(start 177.747422 -58.967878)
		(end 177.927254 -58.967878)
		(width 0.127)
		(layer "In5.Cu")
		(net "XM_ADDR_19")
	)
	(segment
		(start 181.415182 -58.3692)
		(end 181.504082 -58.4581)
		(width 0.0889)
		(layer "In5.Cu")
		(net "XM_ADDR_19")
	)
	(segment
		(start 177.4063 -59.949588)
		(end 177.708306 -59.647582)
		(width 0.127)
		(layer "In5.Cu")
		(net "XM_ADDR_19")
	)
	(segment
		(start 177.151538 -62.047628)
		(end 177.4063 -61.792866)
		(width 0.127)
		(layer "In5.Cu")
		(net "XM_ADDR_19")
	)
	(segment
		(start 171.541948 -64.8081)
		(end 171.668948 -64.9351)
		(width 0.127)
		(layer "In5.Cu")
		(net "XM_ADDR_19")
	)
	(segment
		(start 179.750466 -59.350656)
		(end 180.949346 -59.350656)
		(width 0.127)
		(layer "F.Cu")
		(net "XM_ADDR_18")
	)
	(segment
		(start 180.949346 -59.350656)
		(end 181.200044 -59.099958)
		(width 0.127)
		(layer "F.Cu")
		(net "XM_ADDR_18")
	)
	(via
		(at 167.005 -71.501)
		(size 0.6604)
		(drill 0.254)
		(layers "F.Cu" "B.Cu")
		(net "XM_ADDR_18")
	)
	(via
		(at 179.750466 -59.350656)
		(size 0.508)
		(drill 0.254)
		(layers "F.Cu" "B.Cu")
		(net "XM_ADDR_18")
	)
	(segment
		(start 167.005 -71.501)
		(end 166.99484 -71.51116)
		(width 0.127)
		(layer "B.Cu")
		(net "XM_ADDR_18")
	)
	(segment
		(start 166.99484 -71.51116)
		(end 166.99484 -72.8853)
		(width 0.127)
		(layer "B.Cu")
		(net "XM_ADDR_18")
	)
	(segment
		(start 181.2925 -64.501014)
		(end 181.1655 -64.628014)
		(width 0.127)
		(layer "In5.Cu")
		(net "XM_ADDR_18")
	)
	(segment
		(start 180.34 -66.598546)
		(end 179.095146 -67.8434)
		(width 0.127)
		(layer "In5.Cu")
		(net "XM_ADDR_18")
	)
	(segment
		(start 180.34 -63.739014)
		(end 180.34 -63.993014)
		(width 0.127)
		(layer "In5.Cu")
		(net "XM_ADDR_18")
	)
	(segment
		(start 174.3964 -72.1614)
		(end 174.2694 -72.2884)
		(width 0.127)
		(layer "In5.Cu")
		(net "XM_ADDR_18")
	)
	(segment
		(start 177.28438 -69.1261)
		(end 177.284126 -69.126354)
		(width 0.127)
		(layer "In5.Cu")
		(net "XM_ADDR_18")
	)
	(segment
		(start 180.34 -63.993014)
		(end 180.467 -64.120014)
		(width 0.127)
		(layer "In5.Cu")
		(net "XM_ADDR_18")
	)
	(segment
		(start 180.34 -65.009014)
		(end 180.467 -65.136014)
		(width 0.127)
		(layer "In5.Cu")
		(net "XM_ADDR_18")
	)
	(segment
		(start 174.3964 -71.9074)
		(end 174.3964 -72.1614)
		(width 0.127)
		(layer "In5.Cu")
		(net "XM_ADDR_18")
	)
	(segment
		(start 177.286412 -69.1261)
		(end 177.28438 -69.1261)
		(width 0.127)
		(layer "In5.Cu")
		(net "XM_ADDR_18")
	)
	(segment
		(start 180.467 -63.612014)
		(end 180.34 -63.739014)
		(width 0.127)
		(layer "In5.Cu")
		(net "XM_ADDR_18")
	)
	(segment
		(start 167.2336 -71.2724)
		(end 167.005 -71.501)
		(width 0.127)
		(layer "In5.Cu")
		(net "XM_ADDR_18")
	)
	(segment
		(start 174.2694 -72.2884)
		(end 167.856916 -72.2884)
		(width 0.127)
		(layer "In5.Cu")
		(net "XM_ADDR_18")
	)
	(segment
		(start 181.1655 -64.628014)
		(end 180.467 -64.628014)
		(width 0.127)
		(layer "In5.Cu")
		(net "XM_ADDR_18")
	)
	(segment
		(start 181.1655 -65.136014)
		(end 181.2925 -65.263014)
		(width 0.127)
		(layer "In5.Cu")
		(net "XM_ADDR_18")
	)
	(segment
		(start 180.467 -64.628014)
		(end 180.34 -64.755014)
		(width 0.127)
		(layer "In5.Cu")
		(net "XM_ADDR_18")
	)
	(segment
		(start 174.2694 -71.7804)
		(end 174.3964 -71.9074)
		(width 0.127)
		(layer "In5.Cu")
		(net "XM_ADDR_18")
	)
	(segment
		(start 181.1655 -64.120014)
		(end 181.2925 -64.247014)
		(width 0.127)
		(layer "In5.Cu")
		(net "XM_ADDR_18")
	)
	(segment
		(start 179.750466 -59.350656)
		(end 179.839366 -59.439556)
		(width 0.127)
		(layer "In5.Cu")
		(net "XM_ADDR_18")
	)
	(segment
		(start 181.2925 -63.231014)
		(end 181.2925 -63.485014)
		(width 0.127)
		(layer "In5.Cu")
		(net "XM_ADDR_18")
	)
	(segment
		(start 180.34 -65.771014)
		(end 180.34 -66.598546)
		(width 0.127)
		(layer "In5.Cu")
		(net "XM_ADDR_18")
	)
	(segment
		(start 181.1655 -63.612014)
		(end 180.467 -63.612014)
		(width 0.127)
		(layer "In5.Cu")
		(net "XM_ADDR_18")
	)
	(segment
		(start 168.364916 -71.2724)
		(end 168.237916 -71.3994)
		(width 0.127)
		(layer "In5.Cu")
		(net "XM_ADDR_18")
	)
	(segment
		(start 167.729916 -71.3994)
		(end 167.602916 -71.2724)
		(width 0.127)
		(layer "In5.Cu")
		(net "XM_ADDR_18")
	)
	(segment
		(start 177.284126 -69.126354)
		(end 177.051462 -69.126354)
		(width 0.127)
		(layer "In5.Cu")
		(net "XM_ADDR_18")
	)
	(segment
		(start 180.467 -64.120014)
		(end 181.1655 -64.120014)
		(width 0.127)
		(layer "In5.Cu")
		(net "XM_ADDR_18")
	)
	(segment
		(start 181.2925 -63.485014)
		(end 181.1655 -63.612014)
		(width 0.127)
		(layer "In5.Cu")
		(net "XM_ADDR_18")
	)
	(segment
		(start 179.095146 -67.8434)
		(end 178.569112 -67.8434)
		(width 0.127)
		(layer "In5.Cu")
		(net "XM_ADDR_18")
	)
	(segment
		(start 181.1655 -63.104014)
		(end 181.2925 -63.231014)
		(width 0.127)
		(layer "In5.Cu")
		(net "XM_ADDR_18")
	)
	(segment
		(start 178.569112 -67.8434)
		(end 177.286412 -69.1261)
		(width 0.127)
		(layer "In5.Cu")
		(net "XM_ADDR_18")
	)
	(segment
		(start 177.051462 -69.126354)
		(end 174.905416 -71.2724)
		(width 0.127)
		(layer "In5.Cu")
		(net "XM_ADDR_18")
	)
	(segment
		(start 180.467 -65.136014)
		(end 181.1655 -65.136014)
		(width 0.127)
		(layer "In5.Cu")
		(net "XM_ADDR_18")
	)
	(segment
		(start 181.2925 -65.517014)
		(end 181.1655 -65.644014)
		(width 0.127)
		(layer "In5.Cu")
		(net "XM_ADDR_18")
	)
	(segment
		(start 179.839366 -60.921392)
		(end 180.34 -61.422026)
		(width 0.127)
		(layer "In5.Cu")
		(net "XM_ADDR_18")
	)
	(segment
		(start 180.34 -62.977014)
		(end 180.467 -63.104014)
		(width 0.127)
		(layer "In5.Cu")
		(net "XM_ADDR_18")
	)
	(segment
		(start 168.237916 -71.6534)
		(end 168.364916 -71.7804)
		(width 0.127)
		(layer "In5.Cu")
		(net "XM_ADDR_18")
	)
	(segment
		(start 179.839366 -59.439556)
		(end 179.839366 -60.921392)
		(width 0.127)
		(layer "In5.Cu")
		(net "XM_ADDR_18")
	)
	(segment
		(start 168.364916 -71.7804)
		(end 174.2694 -71.7804)
		(width 0.127)
		(layer "In5.Cu")
		(net "XM_ADDR_18")
	)
	(segment
		(start 181.2925 -64.247014)
		(end 181.2925 -64.501014)
		(width 0.127)
		(layer "In5.Cu")
		(net "XM_ADDR_18")
	)
	(segment
		(start 180.34 -61.422026)
		(end 180.34 -62.977014)
		(width 0.127)
		(layer "In5.Cu")
		(net "XM_ADDR_18")
	)
	(segment
		(start 180.467 -65.644014)
		(end 180.34 -65.771014)
		(width 0.127)
		(layer "In5.Cu")
		(net "XM_ADDR_18")
	)
	(segment
		(start 167.729916 -72.1614)
		(end 167.729916 -71.3994)
		(width 0.127)
		(layer "In5.Cu")
		(net "XM_ADDR_18")
	)
	(segment
		(start 167.856916 -72.2884)
		(end 167.729916 -72.1614)
		(width 0.127)
		(layer "In5.Cu")
		(net "XM_ADDR_18")
	)
	(segment
		(start 180.467 -63.104014)
		(end 181.1655 -63.104014)
		(width 0.127)
		(layer "In5.Cu")
		(net "XM_ADDR_18")
	)
	(segment
		(start 168.237916 -71.3994)
		(end 168.237916 -71.6534)
		(width 0.127)
		(layer "In5.Cu")
		(net "XM_ADDR_18")
	)
	(segment
		(start 174.905416 -71.2724)
		(end 168.364916 -71.2724)
		(width 0.127)
		(layer "In5.Cu")
		(net "XM_ADDR_18")
	)
	(segment
		(start 181.1655 -65.644014)
		(end 180.467 -65.644014)
		(width 0.127)
		(layer "In5.Cu")
		(net "XM_ADDR_18")
	)
	(segment
		(start 180.34 -64.755014)
		(end 180.34 -65.009014)
		(width 0.127)
		(layer "In5.Cu")
		(net "XM_ADDR_18")
	)
	(segment
		(start 167.602916 -71.2724)
		(end 167.2336 -71.2724)
		(width 0.127)
		(layer "In5.Cu")
		(net "XM_ADDR_18")
	)
	(segment
		(start 181.2925 -65.263014)
		(end 181.2925 -65.517014)
		(width 0.127)
		(layer "In5.Cu")
		(net "XM_ADDR_18")
	)
	(segment
		(start 180.888386 -55.900066)
		(end 180.316886 -55.328566)
		(width 0.127)
		(layer "F.Cu")
		(net "XM_ADDR_17")
	)
	(segment
		(start 179.719224 -55.328566)
		(end 179.617624 -55.226966)
		(width 0.127)
		(layer "F.Cu")
		(net "XM_ADDR_17")
	)
	(segment
		(start 178.5366 -54.45379)
		(end 178.5366 -53.9369)
		(width 0.127)
		(layer "F.Cu")
		(net "XM_ADDR_17")
	)
	(segment
		(start 180.316886 -55.328566)
		(end 179.719224 -55.328566)
		(width 0.127)
		(layer "F.Cu")
		(net "XM_ADDR_17")
	)
	(segment
		(start 181.200044 -55.900066)
		(end 180.888386 -55.900066)
		(width 0.127)
		(layer "F.Cu")
		(net "XM_ADDR_17")
	)
	(segment
		(start 179.309776 -55.226966)
		(end 178.5366 -54.45379)
		(width 0.127)
		(layer "F.Cu")
		(net "XM_ADDR_17")
	)
	(segment
		(start 179.617624 -55.226966)
		(end 179.309776 -55.226966)
		(width 0.127)
		(layer "F.Cu")
		(net "XM_ADDR_17")
	)
	(via
		(at 178.5366 -53.9369)
		(size 0.508)
		(drill 0.254)
		(layers "F.Cu" "B.Cu")
		(net "XM_ADDR_17")
	)
	(via
		(at 158.8897 -61.1505)
		(size 0.508)
		(drill 0.254)
		(layers "F.Cu" "B.Cu")
		(net "XM_ADDR_17")
	)
	(segment
		(start 158.99384 -55.45582)
		(end 158.86684 -55.58282)
		(width 0.127)
		(layer "B.Cu")
		(net "XM_ADDR_17")
	)
	(segment
		(start 160.1216 -56.09082)
		(end 160.2486 -56.21782)
		(width 0.127)
		(layer "B.Cu")
		(net "XM_ADDR_17")
	)
	(segment
		(start 160.3121 -57.48782)
		(end 160.1851 -57.61482)
		(width 0.127)
		(layer "B.Cu")
		(net "XM_ADDR_17")
	)
	(segment
		(start 157.5816 -55.70982)
		(end 157.5816 -55.96382)
		(width 0.127)
		(layer "B.Cu")
		(net "XM_ADDR_17")
	)
	(segment
		(start 160.1216 -56.59882)
		(end 157.7721 -56.59882)
		(width 0.127)
		(layer "B.Cu")
		(net "XM_ADDR_17")
	)
	(segment
		(start 157.6451 -56.97982)
		(end 157.7721 -57.10682)
		(width 0.127)
		(layer "B.Cu")
		(net "XM_ADDR_17")
	)
	(segment
		(start 160.1851 -57.10682)
		(end 160.3121 -57.23382)
		(width 0.127)
		(layer "B.Cu")
		(net "XM_ADDR_17")
	)
	(segment
		(start 160.3121 -57.23382)
		(end 160.3121 -57.48782)
		(width 0.127)
		(layer "B.Cu")
		(net "XM_ADDR_17")
	)
	(segment
		(start 157.7086 -56.09082)
		(end 160.1216 -56.09082)
		(width 0.127)
		(layer "B.Cu")
		(net "XM_ADDR_17")
	)
	(segment
		(start 158.86684 -55.58282)
		(end 157.7086 -55.58282)
		(width 0.127)
		(layer "B.Cu")
		(net "XM_ADDR_17")
	)
	(segment
		(start 158.99384 -53.6575)
		(end 158.99384 -55.45582)
		(width 0.127)
		(layer "B.Cu")
		(net "XM_ADDR_17")
	)
	(segment
		(start 160.2486 -56.21782)
		(end 160.2486 -56.47182)
		(width 0.127)
		(layer "B.Cu")
		(net "XM_ADDR_17")
	)
	(segment
		(start 157.7721 -56.59882)
		(end 157.6451 -56.72582)
		(width 0.127)
		(layer "B.Cu")
		(net "XM_ADDR_17")
	)
	(segment
		(start 159.12084 -57.61482)
		(end 158.99384 -57.74182)
		(width 0.127)
		(layer "B.Cu")
		(net "XM_ADDR_17")
	)
	(segment
		(start 158.2674 -60.5282)
		(end 158.8897 -61.1505)
		(width 0.127)
		(layer "B.Cu")
		(net "XM_ADDR_17")
	)
	(segment
		(start 157.6451 -56.72582)
		(end 157.6451 -56.97982)
		(width 0.127)
		(layer "B.Cu")
		(net "XM_ADDR_17")
	)
	(segment
		(start 157.7721 -57.10682)
		(end 160.1851 -57.10682)
		(width 0.127)
		(layer "B.Cu")
		(net "XM_ADDR_17")
	)
	(segment
		(start 160.2486 -56.47182)
		(end 160.1216 -56.59882)
		(width 0.127)
		(layer "B.Cu")
		(net "XM_ADDR_17")
	)
	(segment
		(start 158.99384 -57.74182)
		(end 158.99384 -58.91276)
		(width 0.127)
		(layer "B.Cu")
		(net "XM_ADDR_17")
	)
	(segment
		(start 160.1851 -57.61482)
		(end 159.12084 -57.61482)
		(width 0.127)
		(layer "B.Cu")
		(net "XM_ADDR_17")
	)
	(segment
		(start 158.99384 -58.91276)
		(end 158.2674 -59.6392)
		(width 0.127)
		(layer "B.Cu")
		(net "XM_ADDR_17")
	)
	(segment
		(start 157.7086 -55.58282)
		(end 157.5816 -55.70982)
		(width 0.127)
		(layer "B.Cu")
		(net "XM_ADDR_17")
	)
	(segment
		(start 158.2674 -59.6392)
		(end 158.2674 -60.5282)
		(width 0.127)
		(layer "B.Cu")
		(net "XM_ADDR_17")
	)
	(segment
		(start 157.5816 -55.96382)
		(end 157.7086 -56.09082)
		(width 0.127)
		(layer "B.Cu")
		(net "XM_ADDR_17")
	)
	(segment
		(start 159.7152 -61.976)
		(end 161.634932 -61.976)
		(width 0.127)
		(layer "In5.Cu")
		(net "XM_ADDR_17")
	)
	(segment
		(start 173.044866 -55.8546)
		(end 174.606966 -54.2925)
		(width 0.127)
		(layer "In5.Cu")
		(net "XM_ADDR_17")
	)
	(segment
		(start 174.606966 -54.2925)
		(end 175.8061 -54.2925)
		(width 0.127)
		(layer "In5.Cu")
		(net "XM_ADDR_17")
	)
	(segment
		(start 175.8061 -54.2925)
		(end 176.1617 -53.9369)
		(width 0.127)
		(layer "In5.Cu")
		(net "XM_ADDR_17")
	)
	(segment
		(start 158.8897 -61.1505)
		(end 159.7152 -61.976)
		(width 0.127)
		(layer "In5.Cu")
		(net "XM_ADDR_17")
	)
	(segment
		(start 161.634932 -61.976)
		(end 162.765232 -60.8457)
		(width 0.127)
		(layer "In5.Cu")
		(net "XM_ADDR_17")
	)
	(segment
		(start 166.820596 -60.8457)
		(end 171.811696 -55.8546)
		(width 0.127)
		(layer "In5.Cu")
		(net "XM_ADDR_17")
	)
	(segment
		(start 176.1617 -53.9369)
		(end 178.5366 -53.9369)
		(width 0.127)
		(layer "In5.Cu")
		(net "XM_ADDR_17")
	)
	(segment
		(start 171.811696 -55.8546)
		(end 173.044866 -55.8546)
		(width 0.127)
		(layer "In5.Cu")
		(net "XM_ADDR_17")
	)
	(segment
		(start 162.765232 -60.8457)
		(end 166.820596 -60.8457)
		(width 0.127)
		(layer "In5.Cu")
		(net "XM_ADDR_17")
	)
	(segment
		(start 179.232814 -58.100976)
		(end 179.467764 -57.866026)
		(width 0.127)
		(layer "F.Cu")
		(net "XM_ADDR_16")
	)
	(segment
		(start 176.8602 -54.8005)
		(end 176.878742 -54.819042)
		(width 0.127)
		(layer "F.Cu")
		(net "XM_ADDR_16")
	)
	(segment
		(start 178.56835 -58.100976)
		(end 179.232814 -58.100976)
		(width 0.127)
		(layer "F.Cu")
		(net "XM_ADDR_16")
	)
	(segment
		(start 176.878742 -56.411368)
		(end 178.56835 -58.100976)
		(width 0.127)
		(layer "F.Cu")
		(net "XM_ADDR_16")
	)
	(segment
		(start 176.878742 -54.819042)
		(end 176.878742 -56.411368)
		(width 0.127)
		(layer "F.Cu")
		(net "XM_ADDR_16")
	)
	(segment
		(start 179.467764 -57.866026)
		(end 181.633876 -57.866026)
		(width 0.127)
		(layer "F.Cu")
		(net "XM_ADDR_16")
	)
	(segment
		(start 181.633876 -57.866026)
		(end 181.99989 -57.500012)
		(width 0.127)
		(layer "F.Cu")
		(net "XM_ADDR_16")
	)
	(via
		(at 176.8602 -54.8005)
		(size 0.508)
		(drill 0.254)
		(layers "F.Cu" "B.Cu")
		(net "XM_ADDR_16")
	)
	(via
		(at 158.8897 -62.0141)
		(size 0.508)
		(drill 0.254)
		(layers "F.Cu" "B.Cu")
		(net "XM_ADDR_16")
	)
	(segment
		(start 157.3657 -63.5762)
		(end 157.3657 -63.8302)
		(width 0.127)
		(layer "B.Cu")
		(net "XM_ADDR_16")
	)
	(segment
		(start 158.5722 -64.4652)
		(end 157.4927 -64.4652)
		(width 0.127)
		(layer "B.Cu")
		(net "XM_ADDR_16")
	)
	(segment
		(start 158.1404 -65.1002)
		(end 158.1404 -67.2592)
		(width 0.127)
		(layer "B.Cu")
		(net "XM_ADDR_16")
	)
	(segment
		(start 157.3657 -63.8302)
		(end 157.4927 -63.9572)
		(width 0.127)
		(layer "B.Cu")
		(net "XM_ADDR_16")
	)
	(segment
		(start 157.4927 -64.4652)
		(end 157.3657 -64.5922)
		(width 0.127)
		(layer "B.Cu")
		(net "XM_ADDR_16")
	)
	(segment
		(start 158.8897 -62.0141)
		(end 158.8262 -62.0141)
		(width 0.127)
		(layer "B.Cu")
		(net "XM_ADDR_16")
	)
	(segment
		(start 158.1404 -63.3222)
		(end 158.0134 -63.4492)
		(width 0.127)
		(layer "B.Cu")
		(net "XM_ADDR_16")
	)
	(segment
		(start 158.48584 -70.667372)
		(end 158.99384 -71.175372)
		(width 0.127)
		(layer "B.Cu")
		(net "XM_ADDR_16")
	)
	(segment
		(start 157.3657 -64.5922)
		(end 157.3657 -64.8462)
		(width 0.127)
		(layer "B.Cu")
		(net "XM_ADDR_16")
	)
	(segment
		(start 157.4927 -63.9572)
		(end 158.5722 -63.9572)
		(width 0.127)
		(layer "B.Cu")
		(net "XM_ADDR_16")
	)
	(segment
		(start 158.48584 -67.60464)
		(end 158.48584 -70.667372)
		(width 0.127)
		(layer "B.Cu")
		(net "XM_ADDR_16")
	)
	(segment
		(start 158.5722 -63.9572)
		(end 158.6992 -64.0842)
		(width 0.127)
		(layer "B.Cu")
		(net "XM_ADDR_16")
	)
	(segment
		(start 158.99384 -71.175372)
		(end 158.99384 -72.8853)
		(width 0.127)
		(layer "B.Cu")
		(net "XM_ADDR_16")
	)
	(segment
		(start 158.0134 -64.9732)
		(end 158.1404 -65.1002)
		(width 0.127)
		(layer "B.Cu")
		(net "XM_ADDR_16")
	)
	(segment
		(start 157.3657 -64.8462)
		(end 157.4927 -64.9732)
		(width 0.127)
		(layer "B.Cu")
		(net "XM_ADDR_16")
	)
	(segment
		(start 158.8262 -62.0141)
		(end 158.1404 -62.6999)
		(width 0.127)
		(layer "B.Cu")
		(net "XM_ADDR_16")
	)
	(segment
		(start 157.4927 -63.4492)
		(end 157.3657 -63.5762)
		(width 0.127)
		(layer "B.Cu")
		(net "XM_ADDR_16")
	)
	(segment
		(start 158.6992 -64.3382)
		(end 158.5722 -64.4652)
		(width 0.127)
		(layer "B.Cu")
		(net "XM_ADDR_16")
	)
	(segment
		(start 158.0134 -63.4492)
		(end 157.4927 -63.4492)
		(width 0.127)
		(layer "B.Cu")
		(net "XM_ADDR_16")
	)
	(segment
		(start 157.4927 -64.9732)
		(end 158.0134 -64.9732)
		(width 0.127)
		(layer "B.Cu")
		(net "XM_ADDR_16")
	)
	(segment
		(start 158.1404 -62.6999)
		(end 158.1404 -63.3222)
		(width 0.127)
		(layer "B.Cu")
		(net "XM_ADDR_16")
	)
	(segment
		(start 158.6992 -64.0842)
		(end 158.6992 -64.3382)
		(width 0.127)
		(layer "B.Cu")
		(net "XM_ADDR_16")
	)
	(segment
		(start 158.1404 -67.2592)
		(end 158.48584 -67.60464)
		(width 0.127)
		(layer "B.Cu")
		(net "XM_ADDR_16")
	)
	(segment
		(start 158.8897 -62.0141)
		(end 159.034734 -62.0141)
		(width 0.127)
		(layer "In5.Cu")
		(net "XM_ADDR_16")
	)
	(segment
		(start 167.031162 -61.3537)
		(end 172.022262 -56.3626)
		(width 0.127)
		(layer "In5.Cu")
		(net "XM_ADDR_16")
	)
	(segment
		(start 172.022262 -56.3626)
		(end 173.255432 -56.3626)
		(width 0.127)
		(layer "In5.Cu")
		(net "XM_ADDR_16")
	)
	(segment
		(start 173.255432 -56.3626)
		(end 174.817532 -54.8005)
		(width 0.127)
		(layer "In5.Cu")
		(net "XM_ADDR_16")
	)
	(segment
		(start 174.817532 -54.8005)
		(end 176.8602 -54.8005)
		(width 0.127)
		(layer "In5.Cu")
		(net "XM_ADDR_16")
	)
	(segment
		(start 161.845498 -62.484)
		(end 162.975798 -61.3537)
		(width 0.127)
		(layer "In5.Cu")
		(net "XM_ADDR_16")
	)
	(segment
		(start 159.504634 -62.484)
		(end 161.845498 -62.484)
		(width 0.127)
		(layer "In5.Cu")
		(net "XM_ADDR_16")
	)
	(segment
		(start 159.034734 -62.0141)
		(end 159.504634 -62.484)
		(width 0.127)
		(layer "In5.Cu")
		(net "XM_ADDR_16")
	)
	(segment
		(start 162.975798 -61.3537)
		(end 167.031162 -61.3537)
		(width 0.127)
		(layer "In5.Cu")
		(net "XM_ADDR_16")
	)
	(segment
		(start 182.79999 -58.299858)
		(end 182.400194 -58.699654)
		(width 0.127)
		(layer "F.Cu")
		(net "XM_ADDR_15")
	)
	(via
		(at 182.400194 -58.699654)
		(size 0.508)
		(drill 0.254)
		(layers "F.Cu" "B.Cu")
		(net "XM_ADDR_15")
	)
	(via
		(at 158.8135 -67.1195)
		(size 0.508)
		(drill 0.254)
		(layers "F.Cu" "B.Cu")
		(net "XM_ADDR_15")
	)
	(segment
		(start 158.99384 -70.456806)
		(end 159.314134 -70.7771)
		(width 0.127)
		(layer "B.Cu")
		(net "XM_ADDR_15")
	)
	(segment
		(start 159.314134 -70.7771)
		(end 159.37484 -70.7771)
		(width 0.127)
		(layer "B.Cu")
		(net "XM_ADDR_15")
	)
	(segment
		(start 158.8135 -67.1195)
		(end 158.99384 -67.29984)
		(width 0.127)
		(layer "B.Cu")
		(net "XM_ADDR_15")
	)
	(segment
		(start 159.49422 -71.434706)
		(end 159.49422 -72.8853)
		(width 0.127)
		(layer "B.Cu")
		(net "XM_ADDR_15")
	)
	(segment
		(start 158.99384 -67.29984)
		(end 158.99384 -70.456806)
		(width 0.127)
		(layer "B.Cu")
		(net "XM_ADDR_15")
	)
	(segment
		(start 159.37484 -70.7771)
		(end 159.50184 -70.9041)
		(width 0.127)
		(layer "B.Cu")
		(net "XM_ADDR_15")
	)
	(segment
		(start 159.50184 -71.427086)
		(end 159.49422 -71.434706)
		(width 0.127)
		(layer "B.Cu")
		(net "XM_ADDR_15")
	)
	(segment
		(start 159.50184 -70.9041)
		(end 159.50184 -71.427086)
		(width 0.127)
		(layer "B.Cu")
		(net "XM_ADDR_15")
	)
	(segment
		(start 159.878014 -69.773546)
		(end 160.057338 -69.773546)
		(width 0.127)
		(layer "In5.Cu")
		(net "XM_ADDR_15")
	)
	(segment
		(start 159.610298 -70.041516)
		(end 159.878014 -69.773546)
		(width 0.127)
		(layer "In5.Cu")
		(net "XM_ADDR_15")
	)
	(segment
		(start 168.3639 -69.7484)
		(end 171.0309 -67.0814)
		(width 0.127)
		(layer "In5.Cu")
		(net "XM_ADDR_15")
	)
	(segment
		(start 160.237424 -69.953632)
		(end 160.237424 -70.132956)
		(width 0.127)
		(layer "In5.Cu")
		(net "XM_ADDR_15")
	)
	(segment
		(start 166.522654 -69.7484)
		(end 168.3639 -69.7484)
		(width 0.127)
		(layer "In5.Cu")
		(net "XM_ADDR_15")
	)
	(segment
		(start 179.690522 -58.799222)
		(end 180.432202 -58.799222)
		(width 0.127)
		(layer "In5.Cu")
		(net "XM_ADDR_15")
	)
	(segment
		(start 178.3334 -60.156344)
		(end 179.690522 -58.799222)
		(width 0.127)
		(layer "In5.Cu")
		(net "XM_ADDR_15")
	)
	(segment
		(start 178.02479 -65.1256)
		(end 178.6255 -64.52489)
		(width 0.127)
		(layer "In5.Cu")
		(net "XM_ADDR_15")
	)
	(segment
		(start 175.424846 -67.0814)
		(end 175.945546 -67.6021)
		(width 0.127)
		(layer "In5.Cu")
		(net "XM_ADDR_15")
	)
	(segment
		(start 159.969708 -70.400926)
		(end 159.969708 -70.58025)
		(width 0.127)
		(layer "In5.Cu")
		(net "XM_ADDR_15")
	)
	(segment
		(start 181.067202 -58.926222)
		(end 181.29377 -58.699654)
		(width 0.127)
		(layer "In5.Cu")
		(net "XM_ADDR_15")
	)
	(segment
		(start 163.748466 -70.3326)
		(end 165.938454 -70.3326)
		(width 0.127)
		(layer "In5.Cu")
		(net "XM_ADDR_15")
	)
	(segment
		(start 176.420018 -67.6021)
		(end 178.02479 -65.997328)
		(width 0.127)
		(layer "In5.Cu")
		(net "XM_ADDR_15")
	)
	(segment
		(start 180.432202 -58.799222)
		(end 180.559202 -58.926222)
		(width 0.127)
		(layer "In5.Cu")
		(net "XM_ADDR_15")
	)
	(segment
		(start 160.057338 -69.773546)
		(end 160.237424 -69.953632)
		(width 0.127)
		(layer "In5.Cu")
		(net "XM_ADDR_15")
	)
	(segment
		(start 159.969708 -70.58025)
		(end 160.458658 -71.0692)
		(width 0.127)
		(layer "In5.Cu")
		(net "XM_ADDR_15")
	)
	(segment
		(start 180.559202 -58.926222)
		(end 180.559202 -59.2709)
		(width 0.127)
		(layer "In5.Cu")
		(net "XM_ADDR_15")
	)
	(segment
		(start 175.945546 -67.6021)
		(end 176.420018 -67.6021)
		(width 0.127)
		(layer "In5.Cu")
		(net "XM_ADDR_15")
	)
	(segment
		(start 178.6255 -62.611254)
		(end 178.3334 -62.319154)
		(width 0.127)
		(layer "In5.Cu")
		(net "XM_ADDR_15")
	)
	(segment
		(start 180.940202 -59.3979)
		(end 181.067202 -59.2709)
		(width 0.127)
		(layer "In5.Cu")
		(net "XM_ADDR_15")
	)
	(segment
		(start 158.6611 -67.2719)
		(end 158.6611 -69.271642)
		(width 0.127)
		(layer "In5.Cu")
		(net "XM_ADDR_15")
	)
	(segment
		(start 181.29377 -58.699654)
		(end 182.400194 -58.699654)
		(width 0.127)
		(layer "In5.Cu")
		(net "XM_ADDR_15")
	)
	(segment
		(start 163.011866 -71.0692)
		(end 163.748466 -70.3326)
		(width 0.127)
		(layer "In5.Cu")
		(net "XM_ADDR_15")
	)
	(segment
		(start 178.6255 -64.52489)
		(end 178.6255 -62.611254)
		(width 0.127)
		(layer "In5.Cu")
		(net "XM_ADDR_15")
	)
	(segment
		(start 160.458658 -71.0692)
		(end 163.011866 -71.0692)
		(width 0.127)
		(layer "In5.Cu")
		(net "XM_ADDR_15")
	)
	(segment
		(start 160.237424 -70.132956)
		(end 159.969708 -70.400926)
		(width 0.127)
		(layer "In5.Cu")
		(net "XM_ADDR_15")
	)
	(segment
		(start 180.686202 -59.3979)
		(end 180.940202 -59.3979)
		(width 0.127)
		(layer "In5.Cu")
		(net "XM_ADDR_15")
	)
	(segment
		(start 181.067202 -59.2709)
		(end 181.067202 -58.926222)
		(width 0.127)
		(layer "In5.Cu")
		(net "XM_ADDR_15")
	)
	(segment
		(start 178.02479 -65.997328)
		(end 178.02479 -65.1256)
		(width 0.127)
		(layer "In5.Cu")
		(net "XM_ADDR_15")
	)
	(segment
		(start 158.6611 -69.271642)
		(end 159.430974 -70.041516)
		(width 0.127)
		(layer "In5.Cu")
		(net "XM_ADDR_15")
	)
	(segment
		(start 180.559202 -59.2709)
		(end 180.686202 -59.3979)
		(width 0.127)
		(layer "In5.Cu")
		(net "XM_ADDR_15")
	)
	(segment
		(start 159.430974 -70.041516)
		(end 159.610298 -70.041516)
		(width 0.127)
		(layer "In5.Cu")
		(net "XM_ADDR_15")
	)
	(segment
		(start 178.3334 -62.319154)
		(end 178.3334 -60.156344)
		(width 0.127)
		(layer "In5.Cu")
		(net "XM_ADDR_15")
	)
	(segment
		(start 171.0309 -67.0814)
		(end 175.424846 -67.0814)
		(width 0.127)
		(layer "In5.Cu")
		(net "XM_ADDR_15")
	)
	(segment
		(start 165.938454 -70.3326)
		(end 166.522654 -69.7484)
		(width 0.127)
		(layer "In5.Cu")
		(net "XM_ADDR_15")
	)
	(segment
		(start 158.8135 -67.1195)
		(end 158.6611 -67.2719)
		(width 0.127)
		(layer "In5.Cu")
		(net "XM_ADDR_15")
	)
	(segment
		(start 181.200044 -56.699912)
		(end 180.24221 -56.699912)
		(width 0.127)
		(layer "F.Cu")
		(net "XM_ADDR_14")
	)
	(via
		(at 180.24221 -56.699912)
		(size 0.508)
		(drill 0.254)
		(layers "F.Cu" "B.Cu")
		(net "XM_ADDR_14")
	)
	(via
		(at 159.3088 -64.4017)
		(size 0.508)
		(drill 0.254)
		(layers "F.Cu" "B.Cu")
		(net "XM_ADDR_14")
	)
	(segment
		(start 159.3215 -64.4271)
		(end 159.3215 -64.483488)
		(width 0.127)
		(layer "B.Cu")
		(net "XM_ADDR_14")
	)
	(segment
		(start 159.3469 -64.4017)
		(end 159.3215 -64.4271)
		(width 0.127)
		(layer "B.Cu")
		(net "XM_ADDR_14")
	)
	(segment
		(start 159.9946 -70.685152)
		(end 159.9946 -72.8853)
		(width 0.127)
		(layer "B.Cu")
		(net "XM_ADDR_14")
	)
	(segment
		(start 159.50184 -64.663828)
		(end 159.50184 -70.24624)
		(width 0.127)
		(layer "B.Cu")
		(net "XM_ADDR_14")
	)
	(segment
		(start 159.5247 -70.2691)
		(end 159.578548 -70.2691)
		(width 0.127)
		(layer "B.Cu")
		(net "XM_ADDR_14")
	)
	(segment
		(start 159.50184 -70.24624)
		(end 159.5247 -70.2691)
		(width 0.127)
		(layer "B.Cu")
		(net "XM_ADDR_14")
	)
	(segment
		(start 159.3088 -64.4017)
		(end 159.3469 -64.4017)
		(width 0.127)
		(layer "B.Cu")
		(net "XM_ADDR_14")
	)
	(segment
		(start 159.578548 -70.2691)
		(end 159.9946 -70.685152)
		(width 0.127)
		(layer "B.Cu")
		(net "XM_ADDR_14")
	)
	(segment
		(start 159.3215 -64.483488)
		(end 159.50184 -64.663828)
		(width 0.127)
		(layer "B.Cu")
		(net "XM_ADDR_14")
	)
	(segment
		(start 159.942276 -65.138808)
		(end 159.942276 -64.958976)
		(width 0.127)
		(layer "In5.Cu")
		(net "XM_ADDR_14")
	)
	(segment
		(start 174.271432 -59.037982)
		(end 174.271432 -60.212986)
		(width 0.127)
		(layer "In5.Cu")
		(net "XM_ADDR_14")
	)
	(segment
		(start 167.159178 -65.659)
		(end 166.266368 -65.659)
		(width 0.127)
		(layer "In5.Cu")
		(net "XM_ADDR_14")
	)
	(segment
		(start 159.148018 -66.651886)
		(end 158.968186 -66.651886)
		(width 0.127)
		(layer "In5.Cu")
		(net "XM_ADDR_14")
	)
	(segment
		(start 175.930814 -57.3786)
		(end 174.271432 -59.037982)
		(width 0.127)
		(layer "In5.Cu")
		(net "XM_ADDR_14")
	)
	(segment
		(start 170.717972 -62.100206)
		(end 167.159178 -65.659)
		(width 0.127)
		(layer "In5.Cu")
		(net "XM_ADDR_14")
	)
	(segment
		(start 172.994066 -60.7441)
		(end 171.63796 -62.100206)
		(width 0.127)
		(layer "In5.Cu")
		(net "XM_ADDR_14")
	)
	(segment
		(start 166.266368 -65.659)
		(end 165.428168 -66.4972)
		(width 0.127)
		(layer "In5.Cu")
		(net "XM_ADDR_14")
	)
	(segment
		(start 161.020506 -66.217038)
		(end 159.866838 -67.370706)
		(width 0.127)
		(layer "In5.Cu")
		(net "XM_ADDR_14")
	)
	(segment
		(start 177.945034 -57.254648)
		(end 177.821082 -57.3786)
		(width 0.0889)
		(layer "In5.Cu")
		(net "XM_ADDR_14")
	)
	(segment
		(start 159.385 -64.4017)
		(end 159.3088 -64.4017)
		(width 0.127)
		(layer "In5.Cu")
		(net "XM_ADDR_14")
	)
	(segment
		(start 159.942276 -64.958976)
		(end 159.385 -64.4017)
		(width 0.127)
		(layer "In5.Cu")
		(net "XM_ADDR_14")
	)
	(segment
		(start 159.507428 -67.011296)
		(end 161.226246 -65.292478)
		(width 0.127)
		(layer "In5.Cu")
		(net "XM_ADDR_14")
	)
	(segment
		(start 158.968186 -66.651886)
		(end 158.788608 -66.472308)
		(width 0.127)
		(layer "In5.Cu")
		(net "XM_ADDR_14")
	)
	(segment
		(start 174.271432 -60.212986)
		(end 173.740318 -60.7441)
		(width 0.127)
		(layer "In5.Cu")
		(net "XM_ADDR_14")
	)
	(segment
		(start 160.866836 -64.933068)
		(end 159.148018 -66.651886)
		(width 0.127)
		(layer "In5.Cu")
		(net "XM_ADDR_14")
	)
	(segment
		(start 161.226246 -65.112646)
		(end 161.046668 -64.933068)
		(width 0.127)
		(layer "In5.Cu")
		(net "XM_ADDR_14")
	)
	(segment
		(start 171.63796 -62.100206)
		(end 170.717972 -62.100206)
		(width 0.127)
		(layer "In5.Cu")
		(net "XM_ADDR_14")
	)
	(segment
		(start 159.866838 -67.370706)
		(end 159.687006 -67.370706)
		(width 0.127)
		(layer "In5.Cu")
		(net "XM_ADDR_14")
	)
	(segment
		(start 161.4805 -66.4972)
		(end 161.200338 -66.217038)
		(width 0.127)
		(layer "In5.Cu")
		(net "XM_ADDR_14")
	)
	(segment
		(start 177.821082 -57.3786)
		(end 177.5714 -57.3786)
		(width 0.0889)
		(layer "In5.Cu")
		(net "XM_ADDR_14")
	)
	(segment
		(start 158.788608 -66.292476)
		(end 159.942276 -65.138808)
		(width 0.127)
		(layer "In5.Cu")
		(net "XM_ADDR_14")
	)
	(segment
		(start 161.226246 -65.292478)
		(end 161.226246 -65.112646)
		(width 0.127)
		(layer "In5.Cu")
		(net "XM_ADDR_14")
	)
	(segment
		(start 180.24221 -56.699912)
		(end 178.789838 -56.699912)
		(width 0.0889)
		(layer "In5.Cu")
		(net "XM_ADDR_14")
	)
	(segment
		(start 159.687006 -67.370706)
		(end 159.507428 -67.191128)
		(width 0.127)
		(layer "In5.Cu")
		(net "XM_ADDR_14")
	)
	(segment
		(start 159.507428 -67.191128)
		(end 159.507428 -67.011296)
		(width 0.127)
		(layer "In5.Cu")
		(net "XM_ADDR_14")
	)
	(segment
		(start 158.788608 -66.472308)
		(end 158.788608 -66.292476)
		(width 0.127)
		(layer "In5.Cu")
		(net "XM_ADDR_14")
	)
	(segment
		(start 173.740318 -60.7441)
		(end 172.994066 -60.7441)
		(width 0.127)
		(layer "In5.Cu")
		(net "XM_ADDR_14")
	)
	(segment
		(start 165.428168 -66.4972)
		(end 161.4805 -66.4972)
		(width 0.127)
		(layer "In5.Cu")
		(net "XM_ADDR_14")
	)
	(segment
		(start 161.046668 -64.933068)
		(end 160.866836 -64.933068)
		(width 0.127)
		(layer "In5.Cu")
		(net "XM_ADDR_14")
	)
	(segment
		(start 178.789838 -56.699912)
		(end 178.235102 -57.254648)
		(width 0.0889)
		(layer "In5.Cu")
		(net "XM_ADDR_14")
	)
	(segment
		(start 178.235102 -57.254648)
		(end 177.945034 -57.254648)
		(width 0.0889)
		(layer "In5.Cu")
		(net "XM_ADDR_14")
	)
	(segment
		(start 161.200338 -66.217038)
		(end 161.020506 -66.217038)
		(width 0.127)
		(layer "In5.Cu")
		(net "XM_ADDR_14")
	)
	(segment
		(start 177.5714 -57.3786)
		(end 175.930814 -57.3786)
		(width 0.127)
		(layer "In5.Cu")
		(net "XM_ADDR_14")
	)
	(segment
		(start 179.813966 -55.099966)
		(end 181.200044 -55.099966)
		(width 0.127)
		(layer "F.Cu")
		(net "XM_ADDR_13")
	)
	(segment
		(start 179.451 -53.8861)
		(end 179.451 -54.737)
		(width 0.127)
		(layer "F.Cu")
		(net "XM_ADDR_13")
	)
	(segment
		(start 179.451 -54.737)
		(end 179.813966 -55.099966)
		(width 0.127)
		(layer "F.Cu")
		(net "XM_ADDR_13")
	)
	(via
		(at 158.985204 -62.87262)
		(size 0.508)
		(drill 0.254)
		(layers "F.Cu" "B.Cu")
		(net "XM_ADDR_13")
	)
	(via
		(at 179.451 -53.8861)
		(size 0.508)
		(drill 0.254)
		(layers "F.Cu" "B.Cu")
		(net "XM_ADDR_13")
	)
	(segment
		(start 158.985204 -62.87262)
		(end 160.00984 -63.897256)
		(width 0.127)
		(layer "B.Cu")
		(net "XM_ADDR_13")
	)
	(segment
		(start 160.49498 -70.243446)
		(end 160.49498 -72.8853)
		(width 0.127)
		(layer "B.Cu")
		(net "XM_ADDR_13")
	)
	(segment
		(start 160.00984 -63.897256)
		(end 160.00984 -69.758306)
		(width 0.127)
		(layer "B.Cu")
		(net "XM_ADDR_13")
	)
	(segment
		(start 160.00984 -69.758306)
		(end 160.49498 -70.243446)
		(width 0.127)
		(layer "B.Cu")
		(net "XM_ADDR_13")
	)
	(segment
		(start 177.070766 -55.3085)
		(end 175.028098 -55.3085)
		(width 0.127)
		(layer "In5.Cu")
		(net "XM_ADDR_13")
	)
	(segment
		(start 159.174688 -62.87262)
		(end 158.985204 -62.87262)
		(width 0.127)
		(layer "In5.Cu")
		(net "XM_ADDR_13")
	)
	(segment
		(start 179.197 -54.4449)
		(end 178.685698 -54.4449)
		(width 0.127)
		(layer "In5.Cu")
		(net "XM_ADDR_13")
	)
	(segment
		(start 177.3682 -55.011066)
		(end 177.070766 -55.3085)
		(width 0.127)
		(layer "In5.Cu")
		(net "XM_ADDR_13")
	)
	(segment
		(start 173.465998 -56.8706)
		(end 172.232828 -56.8706)
		(width 0.127)
		(layer "In5.Cu")
		(net "XM_ADDR_13")
	)
	(segment
		(start 165.9001 -62.242954)
		(end 165.9001 -61.988954)
		(width 0.127)
		(layer "In5.Cu")
		(net "XM_ADDR_13")
	)
	(segment
		(start 172.232828 -56.8706)
		(end 166.225474 -62.877954)
		(width 0.127)
		(layer "In5.Cu")
		(net "XM_ADDR_13")
	)
	(segment
		(start 163.449 -62.369954)
		(end 165.7731 -62.369954)
		(width 0.127)
		(layer "In5.Cu")
		(net "XM_ADDR_13")
	)
	(segment
		(start 179.451 -53.8861)
		(end 179.451 -54.1909)
		(width 0.127)
		(layer "In5.Cu")
		(net "XM_ADDR_13")
	)
	(segment
		(start 178.558698 -54.6481)
		(end 178.431698 -54.7751)
		(width 0.127)
		(layer "In5.Cu")
		(net "XM_ADDR_13")
	)
	(segment
		(start 178.050698 -54.5719)
		(end 177.923698 -54.4449)
		(width 0.127)
		(layer "In5.Cu")
		(net "XM_ADDR_13")
	)
	(segment
		(start 163.322 -62.750954)
		(end 163.322 -62.496954)
		(width 0.127)
		(layer "In5.Cu")
		(net "XM_ADDR_13")
	)
	(segment
		(start 177.923698 -54.4449)
		(end 177.513234 -54.4449)
		(width 0.127)
		(layer "In5.Cu")
		(net "XM_ADDR_13")
	)
	(segment
		(start 178.431698 -54.7751)
		(end 178.177698 -54.7751)
		(width 0.127)
		(layer "In5.Cu")
		(net "XM_ADDR_13")
	)
	(segment
		(start 178.050698 -54.6481)
		(end 178.050698 -54.5719)
		(width 0.127)
		(layer "In5.Cu")
		(net "XM_ADDR_13")
	)
	(segment
		(start 178.558698 -54.5719)
		(end 178.558698 -54.6481)
		(width 0.127)
		(layer "In5.Cu")
		(net "XM_ADDR_13")
	)
	(segment
		(start 166.225474 -62.877954)
		(end 163.449 -62.877954)
		(width 0.127)
		(layer "In5.Cu")
		(net "XM_ADDR_13")
	)
	(segment
		(start 165.7731 -61.861954)
		(end 163.18611 -61.861954)
		(width 0.127)
		(layer "In5.Cu")
		(net "XM_ADDR_13")
	)
	(segment
		(start 162.056064 -62.992)
		(end 159.294068 -62.992)
		(width 0.127)
		(layer "In5.Cu")
		(net "XM_ADDR_13")
	)
	(segment
		(start 165.9001 -61.988954)
		(end 165.7731 -61.861954)
		(width 0.127)
		(layer "In5.Cu")
		(net "XM_ADDR_13")
	)
	(segment
		(start 178.685698 -54.4449)
		(end 178.558698 -54.5719)
		(width 0.127)
		(layer "In5.Cu")
		(net "XM_ADDR_13")
	)
	(segment
		(start 177.513234 -54.4449)
		(end 177.3682 -54.589934)
		(width 0.127)
		(layer "In5.Cu")
		(net "XM_ADDR_13")
	)
	(segment
		(start 163.322 -62.496954)
		(end 163.449 -62.369954)
		(width 0.127)
		(layer "In5.Cu")
		(net "XM_ADDR_13")
	)
	(segment
		(start 177.3682 -54.589934)
		(end 177.3682 -55.011066)
		(width 0.127)
		(layer "In5.Cu")
		(net "XM_ADDR_13")
	)
	(segment
		(start 163.18611 -61.861954)
		(end 162.056064 -62.992)
		(width 0.127)
		(layer "In5.Cu")
		(net "XM_ADDR_13")
	)
	(segment
		(start 178.177698 -54.7751)
		(end 178.050698 -54.6481)
		(width 0.127)
		(layer "In5.Cu")
		(net "XM_ADDR_13")
	)
	(segment
		(start 165.7731 -62.369954)
		(end 165.9001 -62.242954)
		(width 0.127)
		(layer "In5.Cu")
		(net "XM_ADDR_13")
	)
	(segment
		(start 163.449 -62.877954)
		(end 163.322 -62.750954)
		(width 0.127)
		(layer "In5.Cu")
		(net "XM_ADDR_13")
	)
	(segment
		(start 179.451 -54.1909)
		(end 179.197 -54.4449)
		(width 0.127)
		(layer "In5.Cu")
		(net "XM_ADDR_13")
	)
	(segment
		(start 175.028098 -55.3085)
		(end 173.465998 -56.8706)
		(width 0.127)
		(layer "In5.Cu")
		(net "XM_ADDR_13")
	)
	(segment
		(start 159.294068 -62.992)
		(end 159.174688 -62.87262)
		(width 0.127)
		(layer "In5.Cu")
		(net "XM_ADDR_13")
	)
	(segment
		(start 182.79999 -56.699912)
		(end 182.400194 -57.099708)
		(width 0.127)
		(layer "F.Cu")
		(net "XM_ADDR_12")
	)
	(via
		(at 160.8836 -69.7484)
		(size 0.508)
		(drill 0.254)
		(layers "F.Cu" "B.Cu")
		(net "XM_ADDR_12")
	)
	(via
		(at 182.400194 -57.099708)
		(size 0.508)
		(drill 0.254)
		(layers "F.Cu" "B.Cu")
		(net "XM_ADDR_12")
	)
	(segment
		(start 160.8836 -69.821806)
		(end 160.99409 -69.932296)
		(width 0.127)
		(layer "B.Cu")
		(net "XM_ADDR_12")
	)
	(segment
		(start 160.99409 -69.932296)
		(end 160.99409 -72.8853)
		(width 0.127)
		(layer "B.Cu")
		(net "XM_ADDR_12")
	)
	(segment
		(start 160.8836 -69.7484)
		(end 160.8836 -69.821806)
		(width 0.127)
		(layer "B.Cu")
		(net "XM_ADDR_12")
	)
	(segment
		(start 159.2961 -68.680076)
		(end 159.1691 -68.807076)
		(width 0.127)
		(layer "In5.Cu")
		(net "XM_ADDR_12")
	)
	(segment
		(start 162.335972 -67.5513)
		(end 162.081972 -67.5513)
		(width 0.127)
		(layer "In5.Cu")
		(net "XM_ADDR_12")
	)
	(segment
		(start 179.461668 -57.172606)
		(end 178.721004 -57.172606)
		(width 0.0889)
		(layer "In5.Cu")
		(net "XM_ADDR_12")
	)
	(segment
		(start 178.486816 -57.406794)
		(end 178.486816 -57.593484)
		(width 0.0889)
		(layer "In5.Cu")
		(net "XM_ADDR_12")
	)
	(segment
		(start 162.462972 -67.4243)
		(end 162.335972 -67.5513)
		(width 0.127)
		(layer "In5.Cu")
		(net "XM_ADDR_12")
	)
	(segment
		(start 161.954972 -67.1576)
		(end 161.827972 -67.0306)
		(width 0.127)
		(layer "In5.Cu")
		(net "XM_ADDR_12")
	)
	(segment
		(start 159.1691 -69.061076)
		(end 159.2961 -69.188076)
		(width 0.127)
		(layer "In5.Cu")
		(net "XM_ADDR_12")
	)
	(segment
		(start 161.954972 -67.4243)
		(end 161.954972 -67.1576)
		(width 0.127)
		(layer "In5.Cu")
		(net "XM_ADDR_12")
	)
	(segment
		(start 180.528468 -57.5691)
		(end 180.350668 -57.5691)
		(width 0.0889)
		(layer "In5.Cu")
		(net "XM_ADDR_12")
	)
	(segment
		(start 163.356036 -68.7578)
		(end 163.229036 -68.6308)
		(width 0.127)
		(layer "In5.Cu")
		(net "XM_ADDR_12")
	)
	(segment
		(start 179.906168 -57.261506)
		(end 179.906168 -57.4802)
		(width 0.0889)
		(layer "In5.Cu")
		(net "XM_ADDR_12")
	)
	(segment
		(start 181.417468 -57.172606)
		(end 181.328568 -57.261506)
		(width 0.0889)
		(layer "In5.Cu")
		(net "XM_ADDR_12")
	)
	(segment
		(start 163.864036 -67.5513)
		(end 163.737036 -67.6783)
		(width 0.127)
		(layer "In5.Cu")
		(net "XM_ADDR_12")
	)
	(segment
		(start 179.550568 -57.4802)
		(end 179.550568 -57.261506)
		(width 0.0889)
		(layer "In5.Cu")
		(net "XM_ADDR_12")
	)
	(segment
		(start 181.328568 -57.261506)
		(end 181.328568 -57.4802)
		(width 0.0889)
		(layer "In5.Cu")
		(net "XM_ADDR_12")
	)
	(segment
		(start 163.610036 -68.7578)
		(end 163.356036 -68.7578)
		(width 0.127)
		(layer "In5.Cu")
		(net "XM_ADDR_12")
	)
	(segment
		(start 180.972968 -57.261506)
		(end 180.884068 -57.172606)
		(width 0.0889)
		(layer "In5.Cu")
		(net "XM_ADDR_12")
	)
	(segment
		(start 180.706268 -57.172606)
		(end 180.617368 -57.261506)
		(width 0.0889)
		(layer "In5.Cu")
		(net "XM_ADDR_12")
	)
	(segment
		(start 180.972968 -57.4802)
		(end 180.972968 -57.261506)
		(width 0.0889)
		(layer "In5.Cu")
		(net "XM_ADDR_12")
	)
	(segment
		(start 161.319972 -67.5513)
		(end 160.4264 -67.5513)
		(width 0.127)
		(layer "In5.Cu")
		(net "XM_ADDR_12")
	)
	(segment
		(start 178.486816 -57.593484)
		(end 178.1937 -57.8866)
		(width 0.0889)
		(layer "In5.Cu")
		(net "XM_ADDR_12")
	)
	(segment
		(start 177.6349 -57.8866)
		(end 176.8729 -57.8866)
		(width 0.127)
		(layer "In5.Cu")
		(net "XM_ADDR_12")
	)
	(segment
		(start 163.737036 -68.6308)
		(end 163.610036 -68.7578)
		(width 0.127)
		(layer "In5.Cu")
		(net "XM_ADDR_12")
	)
	(segment
		(start 179.995068 -57.172606)
		(end 179.906168 -57.261506)
		(width 0.0889)
		(layer "In5.Cu")
		(net "XM_ADDR_12")
	)
	(segment
		(start 160.2994 -67.6783)
		(end 160.2994 -68.045076)
		(width 0.127)
		(layer "In5.Cu")
		(net "XM_ADDR_12")
	)
	(segment
		(start 160.8836 -69.315076)
		(end 160.8836 -69.7484)
		(width 0.127)
		(layer "In5.Cu")
		(net "XM_ADDR_12")
	)
	(segment
		(start 179.550568 -57.261506)
		(end 179.461668 -57.172606)
		(width 0.0889)
		(layer "In5.Cu")
		(net "XM_ADDR_12")
	)
	(segment
		(start 181.239668 -57.5691)
		(end 181.061868 -57.5691)
		(width 0.0889)
		(layer "In5.Cu")
		(net "XM_ADDR_12")
	)
	(segment
		(start 163.229036 -67.191636)
		(end 163.068 -67.0306)
		(width 0.127)
		(layer "In5.Cu")
		(net "XM_ADDR_12")
	)
	(segment
		(start 161.446972 -67.1576)
		(end 161.446972 -67.4243)
		(width 0.127)
		(layer "In5.Cu")
		(net "XM_ADDR_12")
	)
	(segment
		(start 160.2994 -68.045076)
		(end 160.4264 -68.172076)
		(width 0.127)
		(layer "In5.Cu")
		(net "XM_ADDR_12")
	)
	(segment
		(start 181.328568 -57.4802)
		(end 181.239668 -57.5691)
		(width 0.0889)
		(layer "In5.Cu")
		(net "XM_ADDR_12")
	)
	(segment
		(start 160.4264 -67.5513)
		(end 160.2994 -67.6783)
		(width 0.127)
		(layer "In5.Cu")
		(net "XM_ADDR_12")
	)
	(segment
		(start 179.906168 -57.4802)
		(end 179.817268 -57.5691)
		(width 0.0889)
		(layer "In5.Cu")
		(net "XM_ADDR_12")
	)
	(segment
		(start 180.884068 -57.172606)
		(end 180.706268 -57.172606)
		(width 0.0889)
		(layer "In5.Cu")
		(net "XM_ADDR_12")
	)
	(segment
		(start 172.643546 -62.6999)
		(end 170.836844 -62.6999)
		(width 0.127)
		(layer "In5.Cu")
		(net "XM_ADDR_12")
	)
	(segment
		(start 160.7566 -69.188076)
		(end 160.8836 -69.315076)
		(width 0.127)
		(layer "In5.Cu")
		(net "XM_ADDR_12")
	)
	(segment
		(start 163.068 -67.0306)
		(end 162.589972 -67.0306)
		(width 0.127)
		(layer "In5.Cu")
		(net "XM_ADDR_12")
	)
	(segment
		(start 162.4711 -68.680076)
		(end 159.2961 -68.680076)
		(width 0.127)
		(layer "In5.Cu")
		(net "XM_ADDR_12")
	)
	(segment
		(start 162.5981 -68.553076)
		(end 162.4711 -68.680076)
		(width 0.127)
		(layer "In5.Cu")
		(net "XM_ADDR_12")
	)
	(segment
		(start 174.9425 -60.400946)
		(end 172.643546 -62.6999)
		(width 0.127)
		(layer "In5.Cu")
		(net "XM_ADDR_12")
	)
	(segment
		(start 176.8729 -57.8866)
		(end 174.9425 -59.817)
		(width 0.127)
		(layer "In5.Cu")
		(net "XM_ADDR_12")
	)
	(segment
		(start 170.836844 -62.6999)
		(end 167.369744 -66.167)
		(width 0.127)
		(layer "In5.Cu")
		(net "XM_ADDR_12")
	)
	(segment
		(start 180.261768 -57.4802)
		(end 180.261768 -57.261506)
		(width 0.0889)
		(layer "In5.Cu")
		(net "XM_ADDR_12")
	)
	(segment
		(start 163.229036 -68.6308)
		(end 163.229036 -67.191636)
		(width 0.127)
		(layer "In5.Cu")
		(net "XM_ADDR_12")
	)
	(segment
		(start 159.2961 -69.188076)
		(end 160.7566 -69.188076)
		(width 0.127)
		(layer "In5.Cu")
		(net "XM_ADDR_12")
	)
	(segment
		(start 179.639468 -57.5691)
		(end 179.550568 -57.4802)
		(width 0.0889)
		(layer "In5.Cu")
		(net "XM_ADDR_12")
	)
	(segment
		(start 160.4264 -68.172076)
		(end 162.4711 -68.172076)
		(width 0.127)
		(layer "In5.Cu")
		(net "XM_ADDR_12")
	)
	(segment
		(start 162.589972 -67.0306)
		(end 162.462972 -67.1576)
		(width 0.127)
		(layer "In5.Cu")
		(net "XM_ADDR_12")
	)
	(segment
		(start 167.369744 -66.167)
		(end 166.476934 -66.167)
		(width 0.127)
		(layer "In5.Cu")
		(net "XM_ADDR_12")
	)
	(segment
		(start 180.617368 -57.261506)
		(end 180.617368 -57.4802)
		(width 0.0889)
		(layer "In5.Cu")
		(net "XM_ADDR_12")
	)
	(segment
		(start 159.1691 -68.807076)
		(end 159.1691 -69.061076)
		(width 0.127)
		(layer "In5.Cu")
		(net "XM_ADDR_12")
	)
	(segment
		(start 165.092634 -67.5513)
		(end 163.864036 -67.5513)
		(width 0.127)
		(layer "In5.Cu")
		(net "XM_ADDR_12")
	)
	(segment
		(start 180.172868 -57.172606)
		(end 179.995068 -57.172606)
		(width 0.0889)
		(layer "In5.Cu")
		(net "XM_ADDR_12")
	)
	(segment
		(start 161.446972 -67.4243)
		(end 161.319972 -67.5513)
		(width 0.127)
		(layer "In5.Cu")
		(net "XM_ADDR_12")
	)
	(segment
		(start 180.617368 -57.4802)
		(end 180.528468 -57.5691)
		(width 0.0889)
		(layer "In5.Cu")
		(net "XM_ADDR_12")
	)
	(segment
		(start 178.721004 -57.172606)
		(end 178.486816 -57.406794)
		(width 0.0889)
		(layer "In5.Cu")
		(net "XM_ADDR_12")
	)
	(segment
		(start 174.9425 -59.817)
		(end 174.9425 -60.400946)
		(width 0.127)
		(layer "In5.Cu")
		(net "XM_ADDR_12")
	)
	(segment
		(start 182.327296 -57.172606)
		(end 181.417468 -57.172606)
		(width 0.0889)
		(layer "In5.Cu")
		(net "XM_ADDR_12")
	)
	(segment
		(start 178.1937 -57.8866)
		(end 177.6349 -57.8866)
		(width 0.0889)
		(layer "In5.Cu")
		(net "XM_ADDR_12")
	)
	(segment
		(start 166.476934 -66.167)
		(end 165.092634 -67.5513)
		(width 0.127)
		(layer "In5.Cu")
		(net "XM_ADDR_12")
	)
	(segment
		(start 162.4711 -68.172076)
		(end 162.5981 -68.299076)
		(width 0.127)
		(layer "In5.Cu")
		(net "XM_ADDR_12")
	)
	(segment
		(start 181.061868 -57.5691)
		(end 180.972968 -57.4802)
		(width 0.0889)
		(layer "In5.Cu")
		(net "XM_ADDR_12")
	)
	(segment
		(start 162.081972 -67.5513)
		(end 161.954972 -67.4243)
		(width 0.127)
		(layer "In5.Cu")
		(net "XM_ADDR_12")
	)
	(segment
		(start 163.737036 -67.6783)
		(end 163.737036 -68.6308)
		(width 0.127)
		(layer "In5.Cu")
		(net "XM_ADDR_12")
	)
	(segment
		(start 162.462972 -67.1576)
		(end 162.462972 -67.4243)
		(width 0.127)
		(layer "In5.Cu")
		(net "XM_ADDR_12")
	)
	(segment
		(start 179.817268 -57.5691)
		(end 179.639468 -57.5691)
		(width 0.0889)
		(layer "In5.Cu")
		(net "XM_ADDR_12")
	)
	(segment
		(start 161.827972 -67.0306)
		(end 161.573972 -67.0306)
		(width 0.127)
		(layer "In5.Cu")
		(net "XM_ADDR_12")
	)
	(segment
		(start 180.350668 -57.5691)
		(end 180.261768 -57.4802)
		(width 0.0889)
		(layer "In5.Cu")
		(net "XM_ADDR_12")
	)
	(segment
		(start 162.5981 -68.299076)
		(end 162.5981 -68.553076)
		(width 0.127)
		(layer "In5.Cu")
		(net "XM_ADDR_12")
	)
	(segment
		(start 182.400194 -57.099708)
		(end 182.327296 -57.172606)
		(width 0.0889)
		(layer "In5.Cu")
		(net "XM_ADDR_12")
	)
	(segment
		(start 161.573972 -67.0306)
		(end 161.446972 -67.1576)
		(width 0.127)
		(layer "In5.Cu")
		(net "XM_ADDR_12")
	)
	(segment
		(start 180.261768 -57.261506)
		(end 180.172868 -57.172606)
		(width 0.0889)
		(layer "In5.Cu")
		(net "XM_ADDR_12")
	)
	(segment
		(start 180.765196 -54.483)
		(end 180.963062 -54.680866)
		(width 0.127)
		(layer "F.Cu")
		(net "XM_ADDR_11")
	)
	(segment
		(start 181.330092 -54.680866)
		(end 181.749192 -55.099966)
		(width 0.127)
		(layer "F.Cu")
		(net "XM_ADDR_11")
	)
	(segment
		(start 177.9524 -52.9971)
		(end 179.154836 -52.9971)
		(width 0.127)
		(layer "F.Cu")
		(net "XM_ADDR_11")
	)
	(segment
		(start 180.0606 -53.902864)
		(end 180.0606 -54.483)
		(width 0.127)
		(layer "F.Cu")
		(net "XM_ADDR_11")
	)
	(segment
		(start 177.6857 -53.758084)
		(end 177.661062 -53.782722)
		(width 0.127)
		(layer "F.Cu")
		(net "XM_ADDR_11")
	)
	(segment
		(start 179.154836 -52.9971)
		(end 180.0606 -53.902864)
		(width 0.127)
		(layer "F.Cu")
		(net "XM_ADDR_11")
	)
	(segment
		(start 180.963062 -54.680866)
		(end 181.330092 -54.680866)
		(width 0.127)
		(layer "F.Cu")
		(net "XM_ADDR_11")
	)
	(segment
		(start 177.6857 -52.7304)
		(end 177.9524 -52.9971)
		(width 0.127)
		(layer "F.Cu")
		(net "XM_ADDR_11")
	)
	(segment
		(start 177.6857 -52.7304)
		(end 177.6857 -53.758084)
		(width 0.127)
		(layer "F.Cu")
		(net "XM_ADDR_11")
	)
	(segment
		(start 180.0606 -54.483)
		(end 180.765196 -54.483)
		(width 0.127)
		(layer "F.Cu")
		(net "XM_ADDR_11")
	)
	(segment
		(start 181.749192 -55.099966)
		(end 181.99989 -55.099966)
		(width 0.127)
		(layer "F.Cu")
		(net "XM_ADDR_11")
	)
	(via
		(at 160.4137 -63.4619)
		(size 0.508)
		(drill 0.254)
		(layers "F.Cu" "B.Cu")
		(net "XM_ADDR_11")
	)
	(via
		(at 180.0606 -54.483)
		(size 0.508)
		(drill 0.254)
		(layers "F.Cu" "B.Cu")
		(net "XM_ADDR_11")
	)
	(segment
		(start 161.49447 -69.924676)
		(end 161.49447 -72.8853)
		(width 0.127)
		(layer "B.Cu")
		(net "XM_ADDR_11")
	)
	(segment
		(start 160.5661 -68.5292)
		(end 161.47796 -69.44106)
		(width 0.127)
		(layer "B.Cu")
		(net "XM_ADDR_11")
	)
	(segment
		(start 160.4137 -63.4619)
		(end 160.5661 -63.6143)
		(width 0.127)
		(layer "B.Cu")
		(net "XM_ADDR_11")
	)
	(segment
		(start 161.47796 -69.44106)
		(end 161.47796 -69.908166)
		(width 0.127)
		(layer "B.Cu")
		(net "XM_ADDR_11")
	)
	(segment
		(start 161.47796 -69.908166)
		(end 161.49447 -69.924676)
		(width 0.127)
		(layer "B.Cu")
		(net "XM_ADDR_11")
	)
	(segment
		(start 160.5661 -63.6143)
		(end 160.5661 -68.5292)
		(width 0.127)
		(layer "B.Cu")
		(net "XM_ADDR_11")
	)
	(segment
		(start 167.97147 -62.391544)
		(end 167.97147 -62.571376)
		(width 0.127)
		(layer "In5.Cu")
		(net "XM_ADDR_11")
	)
	(segment
		(start 164.162994 -63.627)
		(end 164.162994 -63.9445)
		(width 0.127)
		(layer "In5.Cu")
		(net "XM_ADDR_11")
	)
	(segment
		(start 164.670994 -63.9445)
		(end 164.670994 -63.627)
		(width 0.127)
		(layer "In5.Cu")
		(net "XM_ADDR_11")
	)
	(segment
		(start 162.638994 -63.627)
		(end 162.511994 -63.5)
		(width 0.127)
		(layer "In5.Cu")
		(net "XM_ADDR_11")
	)
	(segment
		(start 165.813994 -64.0715)
		(end 165.686994 -63.9445)
		(width 0.127)
		(layer "In5.Cu")
		(net "XM_ADDR_11")
	)
	(segment
		(start 167.790876 -62.031118)
		(end 167.790876 -62.21095)
		(width 0.127)
		(layer "In5.Cu")
		(net "XM_ADDR_11")
	)
	(segment
		(start 168.689274 -61.13272)
		(end 168.509696 -61.312298)
		(width 0.127)
		(layer "In5.Cu")
		(net "XM_ADDR_11")
	)
	(segment
		(start 172.103796 -57.89803)
		(end 172.28439 -58.078624)
		(width 0.127)
		(layer "In5.Cu")
		(net "XM_ADDR_11")
	)
	(segment
		(start 171.56557 -58.797444)
		(end 171.56557 -58.977276)
		(width 0.127)
		(layer "In5.Cu")
		(net "XM_ADDR_11")
	)
	(segment
		(start 168.69029 -61.852556)
		(end 168.510712 -62.032134)
		(width 0.127)
		(layer "In5.Cu")
		(net "XM_ADDR_11")
	)
	(segment
		(start 164.162994 -63.9445)
		(end 164.035994 -64.0715)
		(width 0.127)
		(layer "In5.Cu")
		(net "XM_ADDR_11")
	)
	(segment
		(start 166.532814 -63.28918)
		(end 166.194994 -63.627)
		(width 0.127)
		(layer "In5.Cu")
		(net "XM_ADDR_11")
	)
	(segment
		(start 170.12793 -60.414916)
		(end 169.948352 -60.594494)
		(width 0.127)
		(layer "In5.Cu")
		(net "XM_ADDR_11")
	)
	(segment
		(start 167.073072 -63.469774)
		(end 166.89324 -63.469774)
		(width 0.127)
		(layer "In5.Cu")
		(net "XM_ADDR_11")
	)
	(segment
		(start 171.385992 -59.156854)
		(end 171.20616 -59.156854)
		(width 0.127)
		(layer "In5.Cu")
		(net "XM_ADDR_11")
	)
	(segment
		(start 172.104812 -58.438034)
		(end 171.92498 -58.438034)
		(width 0.127)
		(layer "In5.Cu")
		(net "XM_ADDR_11")
	)
	(segment
		(start 168.69029 -61.672724)
		(end 168.69029 -61.852556)
		(width 0.127)
		(layer "In5.Cu")
		(net "XM_ADDR_11")
	)
	(segment
		(start 165.178994 -63.627)
		(end 165.178994 -63.9445)
		(width 0.127)
		(layer "In5.Cu")
		(net "XM_ADDR_11")
	)
	(segment
		(start 170.84675 -59.516264)
		(end 170.84675 -59.696096)
		(width 0.127)
		(layer "In5.Cu")
		(net "XM_ADDR_11")
	)
	(segment
		(start 169.947336 -60.05449)
		(end 170.12793 -60.235084)
		(width 0.127)
		(layer "In5.Cu")
		(net "XM_ADDR_11")
	)
	(segment
		(start 167.431466 -62.57036)
		(end 167.251634 -62.57036)
		(width 0.127)
		(layer "In5.Cu")
		(net "XM_ADDR_11")
	)
	(segment
		(start 163.781994 -64.0715)
		(end 163.654994 -63.9445)
		(width 0.127)
		(layer "In5.Cu")
		(net "XM_ADDR_11")
	)
	(segment
		(start 177.814732 -55.2831)
		(end 177.281332 -55.8165)
		(width 0.127)
		(layer "In5.Cu")
		(net "XM_ADDR_11")
	)
	(segment
		(start 166.194994 -63.627)
		(end 166.194994 -63.9445)
		(width 0.127)
		(layer "In5.Cu")
		(net "XM_ADDR_11")
	)
	(segment
		(start 171.025566 -58.97626)
		(end 170.845734 -58.97626)
		(width 0.127)
		(layer "In5.Cu")
		(net "XM_ADDR_11")
	)
	(segment
		(start 164.543994 -63.5)
		(end 164.289994 -63.5)
		(width 0.127)
		(layer "In5.Cu")
		(net "XM_ADDR_11")
	)
	(segment
		(start 169.229532 -61.313314)
		(end 169.0497 -61.313314)
		(width 0.127)
		(layer "In5.Cu")
		(net "XM_ADDR_11")
	)
	(segment
		(start 166.194994 -63.9445)
		(end 166.067994 -64.0715)
		(width 0.127)
		(layer "In5.Cu")
		(net "XM_ADDR_11")
	)
	(segment
		(start 169.76852 -60.594494)
		(end 169.587926 -60.4139)
		(width 0.127)
		(layer "In5.Cu")
		(net "XM_ADDR_11")
	)
	(segment
		(start 168.510712 -62.032134)
		(end 168.33088 -62.032134)
		(width 0.127)
		(layer "In5.Cu")
		(net "XM_ADDR_11")
	)
	(segment
		(start 171.56557 -58.977276)
		(end 171.385992 -59.156854)
		(width 0.127)
		(layer "In5.Cu")
		(net "XM_ADDR_11")
	)
	(segment
		(start 168.869106 -61.13272)
		(end 168.689274 -61.13272)
		(width 0.127)
		(layer "In5.Cu")
		(net "XM_ADDR_11")
	)
	(segment
		(start 171.20616 -59.156854)
		(end 171.025566 -58.97626)
		(width 0.127)
		(layer "In5.Cu")
		(net "XM_ADDR_11")
	)
	(segment
		(start 165.305994 -63.5)
		(end 165.178994 -63.627)
		(width 0.127)
		(layer "In5.Cu")
		(net "XM_ADDR_11")
	)
	(segment
		(start 163.273994 -63.5)
		(end 163.146994 -63.627)
		(width 0.127)
		(layer "In5.Cu")
		(net "XM_ADDR_11")
	)
	(segment
		(start 170.666156 -59.33567)
		(end 170.84675 -59.516264)
		(width 0.127)
		(layer "In5.Cu")
		(net "XM_ADDR_11")
	)
	(segment
		(start 170.306746 -59.69508)
		(end 170.126914 -59.69508)
		(width 0.127)
		(layer "In5.Cu")
		(net "XM_ADDR_11")
	)
	(segment
		(start 165.051994 -64.0715)
		(end 164.797994 -64.0715)
		(width 0.127)
		(layer "In5.Cu")
		(net "XM_ADDR_11")
	)
	(segment
		(start 167.072056 -62.749938)
		(end 167.072056 -62.92977)
		(width 0.127)
		(layer "In5.Cu")
		(net "XM_ADDR_11")
	)
	(segment
		(start 170.12793 -60.235084)
		(end 170.12793 -60.414916)
		(width 0.127)
		(layer "In5.Cu")
		(net "XM_ADDR_11")
	)
	(segment
		(start 171.384976 -58.437018)
		(end 171.384976 -58.61685)
		(width 0.127)
		(layer "In5.Cu")
		(net "XM_ADDR_11")
	)
	(segment
		(start 169.228516 -60.77331)
		(end 169.40911 -60.953904)
		(width 0.127)
		(layer "In5.Cu")
		(net "XM_ADDR_11")
	)
	(segment
		(start 162.765994 -64.0715)
		(end 162.638994 -63.9445)
		(width 0.127)
		(layer "In5.Cu")
		(net "XM_ADDR_11")
	)
	(segment
		(start 172.28439 -58.258456)
		(end 172.104812 -58.438034)
		(width 0.127)
		(layer "In5.Cu")
		(net "XM_ADDR_11")
	)
	(segment
		(start 167.97147 -62.571376)
		(end 167.791892 -62.750954)
		(width 0.127)
		(layer "In5.Cu")
		(net "XM_ADDR_11")
	)
	(segment
		(start 166.712646 -63.28918)
		(end 166.532814 -63.28918)
		(width 0.127)
		(layer "In5.Cu")
		(net "XM_ADDR_11")
	)
	(segment
		(start 178.931824 -54.7878)
		(end 178.436524 -55.2831)
		(width 0.127)
		(layer "In5.Cu")
		(net "XM_ADDR_11")
	)
	(segment
		(start 163.527994 -63.5)
		(end 163.273994 -63.5)
		(width 0.127)
		(layer "In5.Cu")
		(net "XM_ADDR_11")
	)
	(segment
		(start 166.89324 -63.469774)
		(end 166.712646 -63.28918)
		(width 0.127)
		(layer "In5.Cu")
		(net "XM_ADDR_11")
	)
	(segment
		(start 170.48734 -59.875674)
		(end 170.306746 -59.69508)
		(width 0.127)
		(layer "In5.Cu")
		(net "XM_ADDR_11")
	)
	(segment
		(start 180.0606 -54.483)
		(end 179.7558 -54.7878)
		(width 0.127)
		(layer "In5.Cu")
		(net "XM_ADDR_11")
	)
	(segment
		(start 168.509696 -61.49213)
		(end 168.69029 -61.672724)
		(width 0.127)
		(layer "In5.Cu")
		(net "XM_ADDR_11")
	)
	(segment
		(start 171.744386 -58.25744)
		(end 171.564554 -58.25744)
		(width 0.127)
		(layer "In5.Cu")
		(net "XM_ADDR_11")
	)
	(segment
		(start 171.92498 -58.438034)
		(end 171.744386 -58.25744)
		(width 0.127)
		(layer "In5.Cu")
		(net "XM_ADDR_11")
	)
	(segment
		(start 179.7558 -54.7878)
		(end 178.931824 -54.7878)
		(width 0.127)
		(layer "In5.Cu")
		(net "XM_ADDR_11")
	)
	(segment
		(start 168.33088 -62.032134)
		(end 168.150286 -61.85154)
		(width 0.127)
		(layer "In5.Cu")
		(net "XM_ADDR_11")
	)
	(segment
		(start 169.228516 -60.593478)
		(end 169.228516 -60.77331)
		(width 0.127)
		(layer "In5.Cu")
		(net "XM_ADDR_11")
	)
	(segment
		(start 169.408094 -60.4139)
		(end 169.228516 -60.593478)
		(width 0.127)
		(layer "In5.Cu")
		(net "XM_ADDR_11")
	)
	(segment
		(start 162.638994 -63.9445)
		(end 162.638994 -63.627)
		(width 0.127)
		(layer "In5.Cu")
		(net "XM_ADDR_11")
	)
	(segment
		(start 167.072056 -62.92977)
		(end 167.25265 -63.110364)
		(width 0.127)
		(layer "In5.Cu")
		(net "XM_ADDR_11")
	)
	(segment
		(start 169.947336 -59.874658)
		(end 169.947336 -60.05449)
		(width 0.127)
		(layer "In5.Cu")
		(net "XM_ADDR_11")
	)
	(segment
		(start 170.667172 -59.875674)
		(end 170.48734 -59.875674)
		(width 0.127)
		(layer "In5.Cu")
		(net "XM_ADDR_11")
	)
	(segment
		(start 163.654994 -63.627)
		(end 163.527994 -63.5)
		(width 0.127)
		(layer "In5.Cu")
		(net "XM_ADDR_11")
	)
	(segment
		(start 167.25265 -63.110364)
		(end 167.25265 -63.290196)
		(width 0.127)
		(layer "In5.Cu")
		(net "XM_ADDR_11")
	)
	(segment
		(start 162.511994 -63.5)
		(end 160.4518 -63.5)
		(width 0.127)
		(layer "In5.Cu")
		(net "XM_ADDR_11")
	)
	(segment
		(start 177.281332 -55.8165)
		(end 175.238664 -55.8165)
		(width 0.127)
		(layer "In5.Cu")
		(net "XM_ADDR_11")
	)
	(segment
		(start 167.791892 -62.750954)
		(end 167.61206 -62.750954)
		(width 0.127)
		(layer "In5.Cu")
		(net "XM_ADDR_11")
	)
	(segment
		(start 160.4518 -63.5)
		(end 160.4137 -63.4619)
		(width 0.127)
		(layer "In5.Cu")
		(net "XM_ADDR_11")
	)
	(segment
		(start 175.238664 -55.8165)
		(end 173.676564 -57.3786)
		(width 0.127)
		(layer "In5.Cu")
		(net "XM_ADDR_11")
	)
	(segment
		(start 164.289994 -63.5)
		(end 164.162994 -63.627)
		(width 0.127)
		(layer "In5.Cu")
		(net "XM_ADDR_11")
	)
	(segment
		(start 163.654994 -63.9445)
		(end 163.654994 -63.627)
		(width 0.127)
		(layer "In5.Cu")
		(net "XM_ADDR_11")
	)
	(segment
		(start 173.676564 -57.3786)
		(end 172.443394 -57.3786)
		(width 0.127)
		(layer "In5.Cu")
		(net "XM_ADDR_11")
	)
	(segment
		(start 165.686994 -63.9445)
		(end 165.686994 -63.627)
		(width 0.127)
		(layer "In5.Cu")
		(net "XM_ADDR_11")
	)
	(segment
		(start 163.019994 -64.0715)
		(end 162.765994 -64.0715)
		(width 0.127)
		(layer "In5.Cu")
		(net "XM_ADDR_11")
	)
	(segment
		(start 168.509696 -61.312298)
		(end 168.509696 -61.49213)
		(width 0.127)
		(layer "In5.Cu")
		(net "XM_ADDR_11")
	)
	(segment
		(start 166.067994 -64.0715)
		(end 165.813994 -64.0715)
		(width 0.127)
		(layer "In5.Cu")
		(net "XM_ADDR_11")
	)
	(segment
		(start 170.126914 -59.69508)
		(end 169.947336 -59.874658)
		(width 0.127)
		(layer "In5.Cu")
		(net "XM_ADDR_11")
	)
	(segment
		(start 167.25265 -63.290196)
		(end 167.073072 -63.469774)
		(width 0.127)
		(layer "In5.Cu")
		(net "XM_ADDR_11")
	)
	(segment
		(start 165.686994 -63.627)
		(end 165.559994 -63.5)
		(width 0.127)
		(layer "In5.Cu")
		(net "XM_ADDR_11")
	)
	(segment
		(start 164.670994 -63.627)
		(end 164.543994 -63.5)
		(width 0.127)
		(layer "In5.Cu")
		(net "XM_ADDR_11")
	)
	(segment
		(start 169.587926 -60.4139)
		(end 169.408094 -60.4139)
		(width 0.127)
		(layer "In5.Cu")
		(net "XM_ADDR_11")
	)
	(segment
		(start 172.103796 -57.718198)
		(end 172.103796 -57.89803)
		(width 0.127)
		(layer "In5.Cu")
		(net "XM_ADDR_11")
	)
	(segment
		(start 167.61206 -62.750954)
		(end 167.431466 -62.57036)
		(width 0.127)
		(layer "In5.Cu")
		(net "XM_ADDR_11")
	)
	(segment
		(start 169.40911 -60.953904)
		(end 169.40911 -61.133736)
		(width 0.127)
		(layer "In5.Cu")
		(net "XM_ADDR_11")
	)
	(segment
		(start 167.790876 -62.21095)
		(end 167.97147 -62.391544)
		(width 0.127)
		(layer "In5.Cu")
		(net "XM_ADDR_11")
	)
	(segment
		(start 164.035994 -64.0715)
		(end 163.781994 -64.0715)
		(width 0.127)
		(layer "In5.Cu")
		(net "XM_ADDR_11")
	)
	(segment
		(start 168.150286 -61.85154)
		(end 167.970454 -61.85154)
		(width 0.127)
		(layer "In5.Cu")
		(net "XM_ADDR_11")
	)
	(segment
		(start 170.84675 -59.696096)
		(end 170.667172 -59.875674)
		(width 0.127)
		(layer "In5.Cu")
		(net "XM_ADDR_11")
	)
	(segment
		(start 163.146994 -63.627)
		(end 163.146994 -63.9445)
		(width 0.127)
		(layer "In5.Cu")
		(net "XM_ADDR_11")
	)
	(segment
		(start 172.28439 -58.078624)
		(end 172.28439 -58.258456)
		(width 0.127)
		(layer "In5.Cu")
		(net "XM_ADDR_11")
	)
	(segment
		(start 163.146994 -63.9445)
		(end 163.019994 -64.0715)
		(width 0.127)
		(layer "In5.Cu")
		(net "XM_ADDR_11")
	)
	(segment
		(start 171.564554 -58.25744)
		(end 171.384976 -58.437018)
		(width 0.127)
		(layer "In5.Cu")
		(net "XM_ADDR_11")
	)
	(segment
		(start 171.384976 -58.61685)
		(end 171.56557 -58.797444)
		(width 0.127)
		(layer "In5.Cu")
		(net "XM_ADDR_11")
	)
	(segment
		(start 167.970454 -61.85154)
		(end 167.790876 -62.031118)
		(width 0.127)
		(layer "In5.Cu")
		(net "XM_ADDR_11")
	)
	(segment
		(start 169.0497 -61.313314)
		(end 168.869106 -61.13272)
		(width 0.127)
		(layer "In5.Cu")
		(net "XM_ADDR_11")
	)
	(segment
		(start 172.443394 -57.3786)
		(end 172.103796 -57.718198)
		(width 0.127)
		(layer "In5.Cu")
		(net "XM_ADDR_11")
	)
	(segment
		(start 165.178994 -63.9445)
		(end 165.051994 -64.0715)
		(width 0.127)
		(layer "In5.Cu")
		(net "XM_ADDR_11")
	)
	(segment
		(start 167.251634 -62.57036)
		(end 167.072056 -62.749938)
		(width 0.127)
		(layer "In5.Cu")
		(net "XM_ADDR_11")
	)
	(segment
		(start 170.666156 -59.155838)
		(end 170.666156 -59.33567)
		(width 0.127)
		(layer "In5.Cu")
		(net "XM_ADDR_11")
	)
	(segment
		(start 165.559994 -63.5)
		(end 165.305994 -63.5)
		(width 0.127)
		(layer "In5.Cu")
		(net "XM_ADDR_11")
	)
	(segment
		(start 169.948352 -60.594494)
		(end 169.76852 -60.594494)
		(width 0.127)
		(layer "In5.Cu")
		(net "XM_ADDR_11")
	)
	(segment
		(start 164.797994 -64.0715)
		(end 164.670994 -63.9445)
		(width 0.127)
		(layer "In5.Cu")
		(net "XM_ADDR_11")
	)
	(segment
		(start 178.436524 -55.2831)
		(end 177.814732 -55.2831)
		(width 0.127)
		(layer "In5.Cu")
		(net "XM_ADDR_11")
	)
	(segment
		(start 170.845734 -58.97626)
		(end 170.666156 -59.155838)
		(width 0.127)
		(layer "In5.Cu")
		(net "XM_ADDR_11")
	)
	(segment
		(start 169.40911 -61.133736)
		(end 169.229532 -61.313314)
		(width 0.127)
		(layer "In5.Cu")
		(net "XM_ADDR_11")
	)
	(segment
		(start 180.777896 -56.277764)
		(end 181.622192 -56.277764)
		(width 0.127)
		(layer "F.Cu")
		(net "XM_ADDR_10")
	)
	(segment
		(start 181.622192 -56.277764)
		(end 181.99989 -55.900066)
		(width 0.127)
		(layer "F.Cu")
		(net "XM_ADDR_10")
	)
	(segment
		(start 180.320442 -55.82031)
		(end 180.777896 -56.277764)
		(width 0.127)
		(layer "F.Cu")
		(net "XM_ADDR_10")
	)
	(segment
		(start 179.812442 -55.82031)
		(end 180.320442 -55.82031)
		(width 0.127)
		(layer "F.Cu")
		(net "XM_ADDR_10")
	)
	(via
		(at 161.1503 -64.0334)
		(size 0.508)
		(drill 0.254)
		(layers "F.Cu" "B.Cu")
		(net "XM_ADDR_10")
	)
	(via
		(at 179.812442 -55.82031)
		(size 0.508)
		(drill 0.254)
		(layers "F.Cu" "B.Cu")
		(net "XM_ADDR_10")
	)
	(segment
		(start 161.98596 -66.591942)
		(end 161.85896 -66.464942)
		(width 0.127)
		(layer "B.Cu")
		(net "XM_ADDR_10")
	)
	(segment
		(start 161.99485 -72.8853)
		(end 161.99485 -69.917056)
		(width 0.127)
		(layer "B.Cu")
		(net "XM_ADDR_10")
	)
	(segment
		(start 161.85896 -66.464942)
		(end 161.2138 -66.464942)
		(width 0.127)
		(layer "B.Cu")
		(net "XM_ADDR_10")
	)
	(segment
		(start 161.85896 -66.972942)
		(end 161.98596 -66.845942)
		(width 0.127)
		(layer "B.Cu")
		(net "XM_ADDR_10")
	)
	(segment
		(start 161.85896 -64.940942)
		(end 161.98596 -64.813942)
		(width 0.127)
		(layer "B.Cu")
		(net "XM_ADDR_10")
	)
	(segment
		(start 161.3154 -68.496942)
		(end 161.1884 -68.369942)
		(width 0.127)
		(layer "B.Cu")
		(net "XM_ADDR_10")
	)
	(segment
		(start 161.85896 -67.480942)
		(end 161.1884 -67.480942)
		(width 0.127)
		(layer "B.Cu")
		(net "XM_ADDR_10")
	)
	(segment
		(start 161.98596 -69.908166)
		(end 161.98596 -68.623942)
		(width 0.127)
		(layer "B.Cu")
		(net "XM_ADDR_10")
	)
	(segment
		(start 161.98596 -65.575942)
		(end 161.85896 -65.448942)
		(width 0.127)
		(layer "B.Cu")
		(net "XM_ADDR_10")
	)
	(segment
		(start 161.98596 -64.813942)
		(end 161.98596 -64.181228)
		(width 0.127)
		(layer "B.Cu")
		(net "XM_ADDR_10")
	)
	(segment
		(start 161.0741 -67.366642)
		(end 161.0741 -67.087242)
		(width 0.127)
		(layer "B.Cu")
		(net "XM_ADDR_10")
	)
	(segment
		(start 161.1376 -66.388742)
		(end 161.1376 -66.033142)
		(width 0.127)
		(layer "B.Cu")
		(net "XM_ADDR_10")
	)
	(segment
		(start 161.0741 -65.372742)
		(end 161.0741 -65.017142)
		(width 0.127)
		(layer "B.Cu")
		(net "XM_ADDR_10")
	)
	(segment
		(start 161.838132 -64.0334)
		(end 161.1503 -64.0334)
		(width 0.127)
		(layer "B.Cu")
		(net "XM_ADDR_10")
	)
	(segment
		(start 161.1884 -67.480942)
		(end 161.0741 -67.366642)
		(width 0.127)
		(layer "B.Cu")
		(net "XM_ADDR_10")
	)
	(segment
		(start 161.98596 -66.845942)
		(end 161.98596 -66.591942)
		(width 0.127)
		(layer "B.Cu")
		(net "XM_ADDR_10")
	)
	(segment
		(start 161.98596 -68.623942)
		(end 161.85896 -68.496942)
		(width 0.127)
		(layer "B.Cu")
		(net "XM_ADDR_10")
	)
	(segment
		(start 161.0741 -67.087242)
		(end 161.1884 -66.972942)
		(width 0.127)
		(layer "B.Cu")
		(net "XM_ADDR_10")
	)
	(segment
		(start 161.1503 -65.448942)
		(end 161.0741 -65.372742)
		(width 0.127)
		(layer "B.Cu")
		(net "XM_ADDR_10")
	)
	(segment
		(start 161.1884 -68.115942)
		(end 161.3154 -67.988942)
		(width 0.127)
		(layer "B.Cu")
		(net "XM_ADDR_10")
	)
	(segment
		(start 161.0741 -65.017142)
		(end 161.1503 -64.940942)
		(width 0.127)
		(layer "B.Cu")
		(net "XM_ADDR_10")
	)
	(segment
		(start 161.98596 -67.607942)
		(end 161.85896 -67.480942)
		(width 0.127)
		(layer "B.Cu")
		(net "XM_ADDR_10")
	)
	(segment
		(start 161.98596 -65.829942)
		(end 161.98596 -65.575942)
		(width 0.127)
		(layer "B.Cu")
		(net "XM_ADDR_10")
	)
	(segment
		(start 161.98596 -67.861942)
		(end 161.98596 -67.607942)
		(width 0.127)
		(layer "B.Cu")
		(net "XM_ADDR_10")
	)
	(segment
		(start 161.1884 -68.369942)
		(end 161.1884 -68.115942)
		(width 0.127)
		(layer "B.Cu")
		(net "XM_ADDR_10")
	)
	(segment
		(start 161.1376 -66.033142)
		(end 161.2138 -65.956942)
		(width 0.127)
		(layer "B.Cu")
		(net "XM_ADDR_10")
	)
	(segment
		(start 161.2138 -66.464942)
		(end 161.1376 -66.388742)
		(width 0.127)
		(layer "B.Cu")
		(net "XM_ADDR_10")
	)
	(segment
		(start 161.85896 -65.956942)
		(end 161.98596 -65.829942)
		(width 0.127)
		(layer "B.Cu")
		(net "XM_ADDR_10")
	)
	(segment
		(start 161.1884 -66.972942)
		(end 161.85896 -66.972942)
		(width 0.127)
		(layer "B.Cu")
		(net "XM_ADDR_10")
	)
	(segment
		(start 161.85896 -67.988942)
		(end 161.98596 -67.861942)
		(width 0.127)
		(layer "B.Cu")
		(net "XM_ADDR_10")
	)
	(segment
		(start 161.99485 -69.917056)
		(end 161.98596 -69.908166)
		(width 0.127)
		(layer "B.Cu")
		(net "XM_ADDR_10")
	)
	(segment
		(start 161.85896 -65.448942)
		(end 161.1503 -65.448942)
		(width 0.127)
		(layer "B.Cu")
		(net "XM_ADDR_10")
	)
	(segment
		(start 161.98596 -64.181228)
		(end 161.838132 -64.0334)
		(width 0.127)
		(layer "B.Cu")
		(net "XM_ADDR_10")
	)
	(segment
		(start 161.2138 -65.956942)
		(end 161.85896 -65.956942)
		(width 0.127)
		(layer "B.Cu")
		(net "XM_ADDR_10")
	)
	(segment
		(start 161.1503 -64.940942)
		(end 161.85896 -64.940942)
		(width 0.127)
		(layer "B.Cu")
		(net "XM_ADDR_10")
	)
	(segment
		(start 161.3154 -67.988942)
		(end 161.85896 -67.988942)
		(width 0.127)
		(layer "B.Cu")
		(net "XM_ADDR_10")
	)
	(segment
		(start 161.85896 -68.496942)
		(end 161.3154 -68.496942)
		(width 0.127)
		(layer "B.Cu")
		(net "XM_ADDR_10")
	)
	(segment
		(start 165.686486 -64.643)
		(end 165.841934 -64.643)
		(width 0.127)
		(layer "In5.Cu")
		(net "XM_ADDR_10")
	)
	(segment
		(start 163.019486 -65.1764)
		(end 163.146486 -65.3034)
		(width 0.127)
		(layer "In5.Cu")
		(net "XM_ADDR_10")
	)
	(segment
		(start 162.638486 -64.643)
		(end 162.892486 -64.643)
		(width 0.127)
		(layer "In5.Cu")
		(net "XM_ADDR_10")
	)
	(segment
		(start 165.410134 -65.0748)
		(end 165.559486 -64.925448)
		(width 0.127)
		(layer "In5.Cu")
		(net "XM_ADDR_10")
	)
	(segment
		(start 162.003486 -65.1764)
		(end 162.130486 -65.3034)
		(width 0.127)
		(layer "In5.Cu")
		(net "XM_ADDR_10")
	)
	(segment
		(start 164.035486 -65.1764)
		(end 164.162486 -65.3034)
		(width 0.127)
		(layer "In5.Cu")
		(net "XM_ADDR_10")
	)
	(segment
		(start 163.019486 -64.77)
		(end 163.019486 -65.1764)
		(width 0.127)
		(layer "In5.Cu")
		(net "XM_ADDR_10")
	)
	(segment
		(start 173.88713 -57.8866)
		(end 175.44923 -56.3245)
		(width 0.127)
		(layer "In5.Cu")
		(net "XM_ADDR_10")
	)
	(segment
		(start 165.559486 -64.925448)
		(end 165.559486 -64.77)
		(width 0.127)
		(layer "In5.Cu")
		(net "XM_ADDR_10")
	)
	(segment
		(start 163.527486 -65.1764)
		(end 163.527486 -64.77)
		(width 0.127)
		(layer "In5.Cu")
		(net "XM_ADDR_10")
	)
	(segment
		(start 162.003486 -64.77)
		(end 162.003486 -65.1764)
		(width 0.127)
		(layer "In5.Cu")
		(net "XM_ADDR_10")
	)
	(segment
		(start 165.841934 -64.643)
		(end 165.842188 -64.642746)
		(width 0.127)
		(layer "In5.Cu")
		(net "XM_ADDR_10")
	)
	(segment
		(start 163.654486 -64.643)
		(end 163.908486 -64.643)
		(width 0.127)
		(layer "In5.Cu")
		(net "XM_ADDR_10")
	)
	(segment
		(start 166.263066 -64.643)
		(end 166.738046 -64.643)
		(width 0.127)
		(layer "In5.Cu")
		(net "XM_ADDR_10")
	)
	(segment
		(start 164.035486 -64.77)
		(end 164.035486 -65.1764)
		(width 0.127)
		(layer "In5.Cu")
		(net "XM_ADDR_10")
	)
	(segment
		(start 161.876486 -64.643)
		(end 162.003486 -64.77)
		(width 0.127)
		(layer "In5.Cu")
		(net "XM_ADDR_10")
	)
	(segment
		(start 165.178486 -65.0748)
		(end 165.410134 -65.0748)
		(width 0.127)
		(layer "In5.Cu")
		(net "XM_ADDR_10")
	)
	(segment
		(start 164.543486 -64.77)
		(end 164.670486 -64.643)
		(width 0.127)
		(layer "In5.Cu")
		(net "XM_ADDR_10")
	)
	(segment
		(start 166.738046 -64.643)
		(end 173.494446 -57.8866)
		(width 0.127)
		(layer "In5.Cu")
		(net "XM_ADDR_10")
	)
	(segment
		(start 177.866802 -56.257698)
		(end 178.410616 -55.713884)
		(width 0.0889)
		(layer "In5.Cu")
		(net "XM_ADDR_10")
	)
	(segment
		(start 165.051486 -64.77)
		(end 165.051486 -64.9478)
		(width 0.127)
		(layer "In5.Cu")
		(net "XM_ADDR_10")
	)
	(segment
		(start 178.644804 -55.47868)
		(end 179.470812 -55.47868)
		(width 0.0889)
		(layer "In5.Cu")
		(net "XM_ADDR_10")
	)
	(segment
		(start 177.848768 -56.257698)
		(end 177.866802 -56.257698)
		(width 0.0889)
		(layer "In5.Cu")
		(net "XM_ADDR_10")
	)
	(segment
		(start 164.162486 -65.3034)
		(end 164.416486 -65.3034)
		(width 0.127)
		(layer "In5.Cu")
		(net "XM_ADDR_10")
	)
	(segment
		(start 163.146486 -65.3034)
		(end 163.400486 -65.3034)
		(width 0.127)
		(layer "In5.Cu")
		(net "XM_ADDR_10")
	)
	(segment
		(start 179.470812 -55.47868)
		(end 179.812442 -55.82031)
		(width 0.0889)
		(layer "In5.Cu")
		(net "XM_ADDR_10")
	)
	(segment
		(start 177.518822 -56.3245)
		(end 177.547524 -56.295798)
		(width 0.127)
		(layer "In5.Cu")
		(net "XM_ADDR_10")
	)
	(segment
		(start 162.384486 -65.3034)
		(end 162.511486 -65.1764)
		(width 0.127)
		(layer "In5.Cu")
		(net "XM_ADDR_10")
	)
	(segment
		(start 164.924486 -64.643)
		(end 165.051486 -64.77)
		(width 0.127)
		(layer "In5.Cu")
		(net "XM_ADDR_10")
	)
	(segment
		(start 164.416486 -65.3034)
		(end 164.543486 -65.1764)
		(width 0.127)
		(layer "In5.Cu")
		(net "XM_ADDR_10")
	)
	(segment
		(start 164.543486 -65.1764)
		(end 164.543486 -64.77)
		(width 0.127)
		(layer "In5.Cu")
		(net "XM_ADDR_10")
	)
	(segment
		(start 163.908486 -64.643)
		(end 164.035486 -64.77)
		(width 0.127)
		(layer "In5.Cu")
		(net "XM_ADDR_10")
	)
	(segment
		(start 161.1503 -64.0334)
		(end 161.7599 -64.643)
		(width 0.127)
		(layer "In5.Cu")
		(net "XM_ADDR_10")
	)
	(segment
		(start 165.842188 -64.642746)
		(end 166.262812 -64.642746)
		(width 0.127)
		(layer "In5.Cu")
		(net "XM_ADDR_10")
	)
	(segment
		(start 162.892486 -64.643)
		(end 163.019486 -64.77)
		(width 0.127)
		(layer "In5.Cu")
		(net "XM_ADDR_10")
	)
	(segment
		(start 162.511486 -65.1764)
		(end 162.511486 -64.77)
		(width 0.127)
		(layer "In5.Cu")
		(net "XM_ADDR_10")
	)
	(segment
		(start 161.7599 -64.643)
		(end 161.876486 -64.643)
		(width 0.127)
		(layer "In5.Cu")
		(net "XM_ADDR_10")
	)
	(segment
		(start 164.670486 -64.643)
		(end 164.924486 -64.643)
		(width 0.127)
		(layer "In5.Cu")
		(net "XM_ADDR_10")
	)
	(segment
		(start 177.810668 -56.295798)
		(end 177.848768 -56.257698)
		(width 0.127)
		(layer "In5.Cu")
		(net "XM_ADDR_10")
	)
	(segment
		(start 175.44923 -56.3245)
		(end 177.518822 -56.3245)
		(width 0.127)
		(layer "In5.Cu")
		(net "XM_ADDR_10")
	)
	(segment
		(start 162.130486 -65.3034)
		(end 162.384486 -65.3034)
		(width 0.127)
		(layer "In5.Cu")
		(net "XM_ADDR_10")
	)
	(segment
		(start 165.051486 -64.9478)
		(end 165.178486 -65.0748)
		(width 0.127)
		(layer "In5.Cu")
		(net "XM_ADDR_10")
	)
	(segment
		(start 165.559486 -64.77)
		(end 165.686486 -64.643)
		(width 0.127)
		(layer "In5.Cu")
		(net "XM_ADDR_10")
	)
	(segment
		(start 177.547524 -56.295798)
		(end 177.810668 -56.295798)
		(width 0.127)
		(layer "In5.Cu")
		(net "XM_ADDR_10")
	)
	(segment
		(start 178.410616 -55.713884)
		(end 178.410616 -55.712868)
		(width 0.0889)
		(layer "In5.Cu")
		(net "XM_ADDR_10")
	)
	(segment
		(start 163.527486 -64.77)
		(end 163.654486 -64.643)
		(width 0.127)
		(layer "In5.Cu")
		(net "XM_ADDR_10")
	)
	(segment
		(start 173.494446 -57.8866)
		(end 173.88713 -57.8866)
		(width 0.127)
		(layer "In5.Cu")
		(net "XM_ADDR_10")
	)
	(segment
		(start 162.511486 -64.77)
		(end 162.638486 -64.643)
		(width 0.127)
		(layer "In5.Cu")
		(net "XM_ADDR_10")
	)
	(segment
		(start 178.410616 -55.712868)
		(end 178.644804 -55.47868)
		(width 0.0889)
		(layer "In5.Cu")
		(net "XM_ADDR_10")
	)
	(segment
		(start 166.262812 -64.642746)
		(end 166.263066 -64.643)
		(width 0.127)
		(layer "In5.Cu")
		(net "XM_ADDR_10")
	)
	(segment
		(start 163.400486 -65.3034)
		(end 163.527486 -65.1764)
		(width 0.127)
		(layer "In5.Cu")
		(net "XM_ADDR_10")
	)
	(segment
		(start 184.268364 -51.008026)
		(end 184.268364 -51.300888)
		(width 0.127)
		(layer "F.Cu")
		(net "XM_ADDR_1")
	)
	(segment
		(start 184.268364 -51.008026)
		(end 183.388 -50.127662)
		(width 0.127)
		(layer "F.Cu")
		(net "XM_ADDR_1")
	)
	(segment
		(start 183.844438 -51.724814)
		(end 183.844438 -53.10886)
		(width 0.127)
		(layer "F.Cu")
		(net "XM_ADDR_1")
	)
	(segment
		(start 183.844438 -53.10886)
		(end 183.990488 -53.25491)
		(width 0.127)
		(layer "F.Cu")
		(net "XM_ADDR_1")
	)
	(segment
		(start 183.990488 -53.25491)
		(end 183.990488 -53.909468)
		(width 0.127)
		(layer "F.Cu")
		(net "XM_ADDR_1")
	)
	(segment
		(start 184.268364 -51.300888)
		(end 183.844438 -51.724814)
		(width 0.127)
		(layer "F.Cu")
		(net "XM_ADDR_1")
	)
	(segment
		(start 183.990488 -53.909468)
		(end 183.60009 -54.299866)
		(width 0.127)
		(layer "F.Cu")
		(net "XM_ADDR_1")
	)
	(segment
		(start 183.388 -50.127662)
		(end 183.388 -48.6283)
		(width 0.127)
		(layer "F.Cu")
		(net "XM_ADDR_1")
	)
	(segment
		(start 183.388 -48.6283)
		(end 183.4261 -48.5902)
		(width 0.127)
		(layer "F.Cu")
		(net "XM_ADDR_1")
	)
	(via
		(at 172.15358 -49.88814)
		(size 0.508)
		(drill 0.254)
		(layers "F.Cu" "B.Cu")
		(net "XM_ADDR_1")
	)
	(via
		(at 184.268364 -51.008026)
		(size 0.508)
		(drill 0.254)
		(layers "F.Cu" "B.Cu")
		(net "XM_ADDR_1")
	)
	(segment
		(start 172.15358 -50.96002)
		(end 170.49496 -52.61864)
		(width 0.127)
		(layer "B.Cu")
		(net "XM_ADDR_1")
	)
	(segment
		(start 170.49496 -52.61864)
		(end 170.49496 -53.6575)
		(width 0.127)
		(layer "B.Cu")
		(net "XM_ADDR_1")
	)
	(segment
		(start 185.6486 -49.62779)
		(end 184.268364 -51.008026)
		(width 0.127)
		(layer "B.Cu")
		(net "XM_ADDR_1")
	)
	(segment
		(start 172.15358 -49.88814)
		(end 172.15358 -50.96002)
		(width 0.127)
		(layer "B.Cu")
		(net "XM_ADDR_1")
	)
	(segment
		(start 185.6486 -49.4665)
		(end 185.6486 -49.62779)
		(width 0.127)
		(layer "B.Cu")
		(net "XM_ADDR_1")
	)
	(segment
		(start 174.9298 -46.7233)
		(end 175.0568 -46.5963)
		(width 0.127)
		(layer "In5.Cu")
		(net "XM_ADDR_1")
	)
	(segment
		(start 181.205632 -48.6283)
		(end 181.332632 -48.5013)
		(width 0.127)
		(layer "In5.Cu")
		(net "XM_ADDR_1")
	)
	(segment
		(start 173.41342 -48.6283)
		(end 181.205632 -48.6283)
		(width 0.127)
		(layer "In5.Cu")
		(net "XM_ADDR_1")
	)
	(segment
		(start 174.752 -47.9933)
		(end 174.752 -47.7393)
		(width 0.127)
		(layer "In5.Cu")
		(net "XM_ADDR_1")
	)
	(segment
		(start 174.752 -47.7393)
		(end 174.879 -47.6123)
		(width 0.127)
		(layer "In5.Cu")
		(net "XM_ADDR_1")
	)
	(segment
		(start 172.15358 -49.88814)
		(end 173.41342 -48.6283)
		(width 0.127)
		(layer "In5.Cu")
		(net "XM_ADDR_1")
	)
	(segment
		(start 178.093878 -47.1043)
		(end 175.0568 -47.1043)
		(width 0.127)
		(layer "In5.Cu")
		(net "XM_ADDR_1")
	)
	(segment
		(start 175.0568 -46.5963)
		(end 178.601878 -46.5963)
		(width 0.127)
		(layer "In5.Cu")
		(net "XM_ADDR_1")
	)
	(segment
		(start 181.332632 -48.2473)
		(end 181.205632 -48.1203)
		(width 0.127)
		(layer "In5.Cu")
		(net "XM_ADDR_1")
	)
	(segment
		(start 178.728878 -46.7233)
		(end 178.728878 -47.4853)
		(width 0.127)
		(layer "In5.Cu")
		(net "XM_ADDR_1")
	)
	(segment
		(start 178.855878 -47.6123)
		(end 181.713632 -47.6123)
		(width 0.127)
		(layer "In5.Cu")
		(net "XM_ADDR_1")
	)
	(segment
		(start 175.0568 -47.1043)
		(end 174.9298 -46.9773)
		(width 0.127)
		(layer "In5.Cu")
		(net "XM_ADDR_1")
	)
	(segment
		(start 181.205632 -48.1203)
		(end 174.879 -48.1203)
		(width 0.127)
		(layer "In5.Cu")
		(net "XM_ADDR_1")
	)
	(segment
		(start 174.879 -48.1203)
		(end 174.752 -47.9933)
		(width 0.127)
		(layer "In5.Cu")
		(net "XM_ADDR_1")
	)
	(segment
		(start 184.268364 -50.929032)
		(end 184.268364 -51.008026)
		(width 0.127)
		(layer "In5.Cu")
		(net "XM_ADDR_1")
	)
	(segment
		(start 178.220878 -47.4853)
		(end 178.220878 -47.2313)
		(width 0.127)
		(layer "In5.Cu")
		(net "XM_ADDR_1")
	)
	(segment
		(start 181.332632 -48.5013)
		(end 181.332632 -48.2473)
		(width 0.127)
		(layer "In5.Cu")
		(net "XM_ADDR_1")
	)
	(segment
		(start 181.840632 -48.5013)
		(end 184.268364 -50.929032)
		(width 0.127)
		(layer "In5.Cu")
		(net "XM_ADDR_1")
	)
	(segment
		(start 178.220878 -47.2313)
		(end 178.093878 -47.1043)
		(width 0.127)
		(layer "In5.Cu")
		(net "XM_ADDR_1")
	)
	(segment
		(start 181.840632 -47.7393)
		(end 181.840632 -48.5013)
		(width 0.127)
		(layer "In5.Cu")
		(net "XM_ADDR_1")
	)
	(segment
		(start 174.879 -47.6123)
		(end 178.093878 -47.6123)
		(width 0.127)
		(layer "In5.Cu")
		(net "XM_ADDR_1")
	)
	(segment
		(start 174.9298 -46.9773)
		(end 174.9298 -46.7233)
		(width 0.127)
		(layer "In5.Cu")
		(net "XM_ADDR_1")
	)
	(segment
		(start 178.728878 -47.4853)
		(end 178.855878 -47.6123)
		(width 0.127)
		(layer "In5.Cu")
		(net "XM_ADDR_1")
	)
	(segment
		(start 178.601878 -46.5963)
		(end 178.728878 -46.7233)
		(width 0.127)
		(layer "In5.Cu")
		(net "XM_ADDR_1")
	)
	(segment
		(start 178.093878 -47.6123)
		(end 178.220878 -47.4853)
		(width 0.127)
		(layer "In5.Cu")
		(net "XM_ADDR_1")
	)
	(segment
		(start 181.713632 -47.6123)
		(end 181.840632 -47.7393)
		(width 0.127)
		(layer "In5.Cu")
		(net "XM_ADDR_1")
	)
	(segment
		(start 184.1119 -46.5709)
		(end 184.1119 -48.006)
		(width 0.127)
		(layer "F.Cu")
		(net "XM_ADDR_0")
	)
	(segment
		(start 185.42 -52.2478)
		(end 185.42 -49.9872)
		(width 0.127)
		(layer "F.Cu")
		(net "XM_ADDR_0")
	)
	(segment
		(start 185.7883 -52.6161)
		(end 185.42 -52.2478)
		(width 0.127)
		(layer "F.Cu")
		(net "XM_ADDR_0")
	)
	(segment
		(start 185.6232 -53.876702)
		(end 185.6232 -53.352954)
		(width 0.127)
		(layer "F.Cu")
		(net "XM_ADDR_0")
	)
	(segment
		(start 184.354216 -46.328584)
		(end 184.1119 -46.5709)
		(width 0.127)
		(layer "F.Cu")
		(net "XM_ADDR_0")
	)
	(segment
		(start 185.7883 -53.187854)
		(end 185.7883 -52.6161)
		(width 0.127)
		(layer "F.Cu")
		(net "XM_ADDR_0")
	)
	(segment
		(start 186.443112 -46.328584)
		(end 184.354216 -46.328584)
		(width 0.127)
		(layer "F.Cu")
		(net "XM_ADDR_0")
	)
	(segment
		(start 184.6961 -48.5902)
		(end 185.42 -49.3141)
		(width 0.127)
		(layer "F.Cu")
		(net "XM_ADDR_0")
	)
	(segment
		(start 185.42 -49.3141)
		(end 185.42 -49.9872)
		(width 0.127)
		(layer "F.Cu")
		(net "XM_ADDR_0")
	)
	(segment
		(start 184.1119 -48.006)
		(end 184.6961 -48.5902)
		(width 0.127)
		(layer "F.Cu")
		(net "XM_ADDR_0")
	)
	(segment
		(start 185.200036 -54.299866)
		(end 185.6232 -53.876702)
		(width 0.127)
		(layer "F.Cu")
		(net "XM_ADDR_0")
	)
	(segment
		(start 185.6232 -53.352954)
		(end 185.7883 -53.187854)
		(width 0.127)
		(layer "F.Cu")
		(net "XM_ADDR_0")
	)
	(via
		(at 194.8942 -120.3198)
		(size 0.6604)
		(drill 0.3302)
		(layers "F.Cu" "B.Cu")
		(net "VT235_VX")
	)
	(segment
		(start 191.600074 -129.049526)
		(end 191.8462 -128.8034)
		(width 0.254)
		(layer "F.Cu")
		(net "VT235_VREF")
	)
	(segment
		(start 189.9666 -127.1397)
		(end 189.9666 -125.275086)
		(width 0.254)
		(layer "F.Cu")
		(net "VT235_VREF")
	)
	(segment
		(start 189.68085 -124.989336)
		(end 189.68085 -124.146564)
		(width 0.254)
		(layer "F.Cu")
		(net "VT235_VREF")
	)
	(segment
		(start 190.7667 -128.0795)
		(end 189.9285 -127.2413)
		(width 0.254)
		(layer "F.Cu")
		(net "VT235_VREF")
	)
	(segment
		(start 189.9285 -127.2413)
		(end 189.865 -127.2413)
		(width 0.254)
		(layer "F.Cu")
		(net "VT235_VREF")
	)
	(segment
		(start 190.8556 -128.0795)
		(end 190.7667 -128.0795)
		(width 0.254)
		(layer "F.Cu")
		(net "VT235_VREF")
	)
	(segment
		(start 191.8462 -128.8034)
		(end 191.8462 -128.0795)
		(width 0.254)
		(layer "F.Cu")
		(net "VT235_VREF")
	)
	(segment
		(start 191.152526 -129.049526)
		(end 191.393826 -129.049526)
		(width 0.254)
		(layer "F.Cu")
		(net "VT235_VREF")
	)
	(segment
		(start 189.9666 -125.275086)
		(end 189.68085 -124.989336)
		(width 0.254)
		(layer "F.Cu")
		(net "VT235_VREF")
	)
	(segment
		(start 190.8556 -128.7526)
		(end 191.152526 -129.049526)
		(width 0.254)
		(layer "F.Cu")
		(net "VT235_VREF")
	)
	(segment
		(start 191.393826 -129.049526)
		(end 191.600074 -129.049526)
		(width 0.254)
		(layer "F.Cu")
		(net "VT235_VREF")
	)
	(segment
		(start 190.8556 -128.0795)
		(end 190.8556 -128.7526)
		(width 0.254)
		(layer "F.Cu")
		(net "VT235_VREF")
	)
	(segment
		(start 189.865 -127.2413)
		(end 189.9666 -127.1397)
		(width 0.254)
		(layer "F.Cu")
		(net "VT235_VREF")
	)
	(segment
		(start 188.8617 -127.3302)
		(end 189.7761 -127.3302)
		(width 0.254)
		(layer "F.Cu")
		(net "VT235_VREF")
	)
	(segment
		(start 189.7761 -127.3302)
		(end 189.865 -127.2413)
		(width 0.254)
		(layer "F.Cu")
		(net "VT235_VREF")
	)
	(via
		(at 191.393826 -129.049526)
		(size 0.6604)
		(drill 0.3302)
		(layers "F.Cu" "B.Cu")
		(net "VT235_VREF")
	)
	(segment
		(start 192.802002 -124.095002)
		(end 192.854326 -124.147326)
		(width 0.254)
		(layer "F.Cu")
		(net "VT235_VFB")
	)
	(segment
		(start 192.760854 -124.095002)
		(end 192.802002 -124.095002)
		(width 0.254)
		(layer "F.Cu")
		(net "VT235_VFB")
	)
	(segment
		(start 192.854326 -124.147326)
		(end 194.005454 -124.147326)
		(width 0.254)
		(layer "F.Cu")
		(net "VT235_VFB")
	)
	(segment
		(start 191.06642 -123.260866)
		(end 191.926718 -123.260866)
		(width 0.254)
		(layer "F.Cu")
		(net "VT235_VFB")
	)
	(segment
		(start 194.962526 -124.154946)
		(end 195.495926 -123.621546)
		(width 0.254)
		(layer "F.Cu")
		(net "VT235_VFB")
	)
	(segment
		(start 194.005454 -124.147326)
		(end 194.945254 -124.147326)
		(width 0.254)
		(layer "F.Cu")
		(net "VT235_VFB")
	)
	(segment
		(start 196.760846 -123.621546)
		(end 197.358 -124.2187)
		(width 0.254)
		(layer "F.Cu")
		(net "VT235_VFB")
	)
	(segment
		(start 194.945254 -124.147326)
		(end 194.962526 -124.154946)
		(width 0.254)
		(layer "F.Cu")
		(net "VT235_VFB")
	)
	(segment
		(start 191.926718 -123.260866)
		(end 192.760854 -124.095002)
		(width 0.254)
		(layer "F.Cu")
		(net "VT235_VFB")
	)
	(segment
		(start 195.495926 -123.621546)
		(end 196.760846 -123.621546)
		(width 0.254)
		(layer "F.Cu")
		(net "VT235_VFB")
	)
	(via
		(at 192.760854 -124.095002)
		(size 0.6604)
		(drill 0.3302)
		(layers "F.Cu" "B.Cu")
		(net "VT235_VFB")
	)
	(segment
		(start 187.9346 -128.4478)
		(end 187.9346 -127.3683)
		(width 0.254)
		(layer "F.Cu")
		(net "VT235_VDES_RR")
	)
	(segment
		(start 187.9346 -127.3683)
		(end 187.9727 -127.3302)
		(width 0.254)
		(layer "F.Cu")
		(net "VT235_VDES_RR")
	)
	(segment
		(start 188.6712 -129.1844)
		(end 187.9346 -128.4478)
		(width 0.254)
		(layer "F.Cu")
		(net "VT235_VDES_RR")
	)
	(segment
		(start 188.9125 -129.1844)
		(end 188.6712 -129.1844)
		(width 0.254)
		(layer "F.Cu")
		(net "VT235_VDES_RR")
	)
	(via
		(at 187.9346 -128.4478)
		(size 0.6604)
		(drill 0.3302)
		(layers "F.Cu" "B.Cu")
		(net "VT235_VDES_RR")
	)
	(segment
		(start 190.5 -130.1496)
		(end 193.0654 -130.1496)
		(width 0.254)
		(layer "F.Cu")
		(net "VT235_VDES_RCC")
	)
	(segment
		(start 193.3448 -129.8702)
		(end 193.6496 -129.5654)
		(width 0.254)
		(layer "F.Cu")
		(net "VT235_VDES_RCC")
	)
	(segment
		(start 193.0654 -130.1496)
		(end 193.3448 -129.8702)
		(width 0.254)
		(layer "F.Cu")
		(net "VT235_VDES_RCC")
	)
	(segment
		(start 189.8015 -129.1844)
		(end 189.8015 -129.4511)
		(width 0.254)
		(layer "F.Cu")
		(net "VT235_VDES_RCC")
	)
	(segment
		(start 189.865 -129.1209)
		(end 189.8015 -129.1844)
		(width 0.254)
		(layer "F.Cu")
		(net "VT235_VDES_RCC")
	)
	(segment
		(start 193.6496 -127.158496)
		(end 193.839338 -126.968758)
		(width 0.254)
		(layer "F.Cu")
		(net "VT235_VDES_RCC")
	)
	(segment
		(start 189.8015 -129.4511)
		(end 190.5 -130.1496)
		(width 0.254)
		(layer "F.Cu")
		(net "VT235_VDES_RCC")
	)
	(segment
		(start 193.839338 -126.968758)
		(end 194.537838 -127.667258)
		(width 0.254)
		(layer "F.Cu")
		(net "VT235_VDES_RCC")
	)
	(segment
		(start 193.6496 -129.5654)
		(end 193.6496 -127.158496)
		(width 0.254)
		(layer "F.Cu")
		(net "VT235_VDES_RCC")
	)
	(segment
		(start 194.537838 -127.667258)
		(end 194.880738 -127.667258)
		(width 0.254)
		(layer "F.Cu")
		(net "VT235_VDES_RCC")
	)
	(segment
		(start 196.805042 -127.667258)
		(end 197.4088 -127.0635)
		(width 0.254)
		(layer "F.Cu")
		(net "VT235_VDES_RCC")
	)
	(segment
		(start 194.880738 -127.667258)
		(end 196.805042 -127.667258)
		(width 0.254)
		(layer "F.Cu")
		(net "VT235_VDES_RCC")
	)
	(segment
		(start 189.865 -128.1303)
		(end 189.865 -129.1209)
		(width 0.254)
		(layer "F.Cu")
		(net "VT235_VDES_RCC")
	)
	(via
		(at 193.3448 -129.8702)
		(size 0.6604)
		(drill 0.3302)
		(layers "F.Cu" "B.Cu")
		(net "VT235_VDES_RCC")
	)
	(segment
		(start 195.851526 -125.137926)
		(end 195.8848 -125.1712)
		(width 0.254)
		(layer "F.Cu")
		(net "VT235_VDES_RC")
	)
	(segment
		(start 195.851526 -124.154946)
		(end 195.851526 -125.137926)
		(width 0.254)
		(layer "F.Cu")
		(net "VT235_VDES_RC")
	)
	(segment
		(start 194.880738 -126.143258)
		(end 194.912742 -126.143258)
		(width 0.254)
		(layer "F.Cu")
		(net "VT235_VDES_RC")
	)
	(segment
		(start 194.912742 -126.143258)
		(end 195.8848 -125.1712)
		(width 0.254)
		(layer "F.Cu")
		(net "VT235_VDES_RC")
	)
	(via
		(at 195.8848 -125.1712)
		(size 0.6604)
		(drill 0.3302)
		(layers "F.Cu" "B.Cu")
		(net "VT235_VDES_RC")
	)
	(segment
		(start 194.005454 -125.036326)
		(end 193.839338 -125.202442)
		(width 0.254)
		(layer "F.Cu")
		(net "VT235_VDES")
	)
	(segment
		(start 190.8556 -127.1905)
		(end 190.692532 -127.027432)
		(width 0.254)
		(layer "F.Cu")
		(net "VT235_VDES")
	)
	(segment
		(start 190.692532 -127.027432)
		(end 190.692532 -126.379732)
		(width 0.254)
		(layer "F.Cu")
		(net "VT235_VDES")
	)
	(segment
		(start 193.092324 -126.079758)
		(end 192.828926 -126.343156)
		(width 0.254)
		(layer "F.Cu")
		(net "VT235_VDES")
	)
	(segment
		(start 190.6524 -126.3396)
		(end 190.6524 -125.294136)
		(width 0.254)
		(layer "F.Cu")
		(net "VT235_VDES")
	)
	(segment
		(start 193.839338 -125.202442)
		(end 193.839338 -126.079758)
		(width 0.254)
		(layer "F.Cu")
		(net "VT235_VDES")
	)
	(segment
		(start 190.180722 -124.822458)
		(end 190.180722 -124.146564)
		(width 0.254)
		(layer "F.Cu")
		(net "VT235_VDES")
	)
	(segment
		(start 190.692532 -126.379732)
		(end 190.6524 -126.3396)
		(width 0.254)
		(layer "F.Cu")
		(net "VT235_VDES")
	)
	(segment
		(start 193.839338 -126.079758)
		(end 193.092324 -126.079758)
		(width 0.254)
		(layer "F.Cu")
		(net "VT235_VDES")
	)
	(segment
		(start 190.6524 -125.294136)
		(end 190.180722 -124.822458)
		(width 0.254)
		(layer "F.Cu")
		(net "VT235_VDES")
	)
	(via
		(at 191.740282 -126.619)
		(size 0.6096)
		(drill 0.3048)
		(layers "F.Cu" "B.Cu")
		(net "VT235_VDES")
	)
	(via
		(at 192.828926 -126.343156)
		(size 0.508)
		(drill 0.254)
		(layers "F.Cu" "B.Cu")
		(net "VT235_VDES")
	)
	(via
		(at 190.6524 -126.3396)
		(size 0.508)
		(drill 0.254)
		(layers "F.Cu" "B.Cu")
		(net "VT235_VDES")
	)
	(segment
		(start 190.92926 -126.619)
		(end 190.6524 -126.34214)
		(width 0.254)
		(layer "B.Cu")
		(net "VT235_VDES")
	)
	(segment
		(start 191.740282 -126.619)
		(end 192.16497 -126.619)
		(width 0.254)
		(layer "B.Cu")
		(net "VT235_VDES")
	)
	(segment
		(start 190.6524 -126.34214)
		(end 190.6524 -126.3396)
		(width 0.254)
		(layer "B.Cu")
		(net "VT235_VDES")
	)
	(segment
		(start 191.740282 -126.619)
		(end 190.92926 -126.619)
		(width 0.254)
		(layer "B.Cu")
		(net "VT235_VDES")
	)
	(segment
		(start 192.16751 -126.62154)
		(end 192.550542 -126.62154)
		(width 0.254)
		(layer "B.Cu")
		(net "VT235_VDES")
	)
	(segment
		(start 192.16497 -126.619)
		(end 192.16751 -126.62154)
		(width 0.254)
		(layer "B.Cu")
		(net "VT235_VDES")
	)
	(segment
		(start 192.550542 -126.62154)
		(end 192.828926 -126.343156)
		(width 0.254)
		(layer "B.Cu")
		(net "VT235_VDES")
	)
	(segment
		(start 190.6524 -126.3396)
		(end 190.6524 -125.0569)
		(width 0.254)
		(layer "B.Cu")
		(net "VT235_VDES")
	)
	(segment
		(start 192.1764 -122.6566)
		(end 191.780668 -122.260868)
		(width 0.254)
		(layer "F.Cu")
		(net "VT235_VDDL")
	)
	(segment
		(start 193.0146 -122.8852)
		(end 192.786 -122.6566)
		(width 0.254)
		(layer "F.Cu")
		(net "VT235_VDDL")
	)
	(segment
		(start 193.675 -122.8852)
		(end 193.0146 -122.8852)
		(width 0.254)
		(layer "F.Cu")
		(net "VT235_VDDL")
	)
	(segment
		(start 192.786 -122.6566)
		(end 192.1764 -122.6566)
		(width 0.254)
		(layer "F.Cu")
		(net "VT235_VDDL")
	)
	(segment
		(start 191.780668 -122.260868)
		(end 191.06642 -122.260868)
		(width 0.254)
		(layer "F.Cu")
		(net "VT235_VDDL")
	)
	(via
		(at 191.7954 -122.4026)
		(size 0.6096)
		(drill 0.3048)
		(layers "F.Cu" "B.Cu")
		(net "VT235_VDDL")
	)
	(via
		(at 192.786 -122.6566)
		(size 0.508)
		(drill 0.254)
		(layers "F.Cu" "B.Cu")
		(net "VT235_VDDL")
	)
	(segment
		(start 192.0494 -122.6566)
		(end 192.786 -122.6566)
		(width 0.254)
		(layer "B.Cu")
		(net "VT235_VDDL")
	)
	(segment
		(start 191.7954 -122.4026)
		(end 192.0494 -122.6566)
		(width 0.254)
		(layer "B.Cu")
		(net "VT235_VDDL")
	)
	(segment
		(start 191.7954 -120.6246)
		(end 191.7954 -122.4026)
		(width 0.254)
		(layer "B.Cu")
		(net "VT235_VDDL")
	)
	(via
		(at 181.6608 -116.7384)
		(size 0.7112)
		(drill 0.4064)
		(layers "F.Cu" "B.Cu")
		(net "VT235_VDDH")
	)
	(via
		(at 181.6608 -118.11)
		(size 0.7112)
		(drill 0.4064)
		(layers "F.Cu" "B.Cu")
		(net "VT235_VDDH")
	)
	(via
		(at 181.5846 -115.2144)
		(size 0.7112)
		(drill 0.4064)
		(layers "F.Cu" "B.Cu")
		(net "VT235_VDDH")
	)
	(via
		(at 181.4068 -113.1316)
		(size 0.6604)
		(drill 0.3302)
		(layers "F.Cu" "B.Cu")
		(net "VT235_VDDH")
	)
	(segment
		(start 190.680848 -124.146564)
		(end 191.050164 -124.146564)
		(width 0.254)
		(layer "F.Cu")
		(net "VT235_PGIN")
	)
	(segment
		(start 191.8462 -127.1905)
		(end 191.8462 -126.3904)
		(width 0.254)
		(layer "F.Cu")
		(net "VT235_PGIN")
	)
	(segment
		(start 191.050164 -124.146564)
		(end 191.327532 -124.423932)
		(width 0.254)
		(layer "F.Cu")
		(net "VT235_PGIN")
	)
	(segment
		(start 191.8462 -126.3904)
		(end 191.633348 -126.177548)
		(width 0.254)
		(layer "F.Cu")
		(net "VT235_PGIN")
	)
	(segment
		(start 192.8368 -127.1905)
		(end 191.8462 -127.1905)
		(width 0.254)
		(layer "F.Cu")
		(net "VT235_PGIN")
	)
	(segment
		(start 191.327532 -125.871732)
		(end 191.633348 -126.177548)
		(width 0.254)
		(layer "F.Cu")
		(net "VT235_PGIN")
	)
	(segment
		(start 191.327532 -124.423932)
		(end 191.327532 -125.871732)
		(width 0.254)
		(layer "F.Cu")
		(net "VT235_PGIN")
	)
	(via
		(at 191.633348 -126.177548)
		(size 0.6604)
		(drill 0.3302)
		(layers "F.Cu" "B.Cu")
		(net "VT235_PGIN")
	)
	(segment
		(start 186.673236 -124.146564)
		(end 187.180728 -124.146564)
		(width 0.254)
		(layer "F.Cu")
		(net "VT235_IRIP")
	)
	(segment
		(start 185.5724 -125.2474)
		(end 186.673236 -124.146564)
		(width 0.254)
		(layer "F.Cu")
		(net "VT235_IRIP")
	)
	(via
		(at 186.5122 -125.984)
		(size 0.6096)
		(drill 0.3048)
		(layers "F.Cu" "B.Cu")
		(net "VT235_IRIP")
	)
	(via
		(at 185.5724 -125.2474)
		(size 0.508)
		(drill 0.254)
		(layers "F.Cu" "B.Cu")
		(net "VT235_IRIP")
	)
	(segment
		(start 186.309 -125.984)
		(end 185.5724 -125.2474)
		(width 0.254)
		(layer "B.Cu")
		(net "VT235_IRIP")
	)
	(segment
		(start 186.5122 -125.984)
		(end 186.309 -125.984)
		(width 0.254)
		(layer "B.Cu")
		(net "VT235_IRIP")
	)
	(segment
		(start 186.8424 -125.6538)
		(end 186.5122 -125.984)
		(width 0.254)
		(layer "B.Cu")
		(net "VT235_IRIP")
	)
	(segment
		(start 186.8424 -124.849636)
		(end 186.8424 -125.6538)
		(width 0.254)
		(layer "B.Cu")
		(net "VT235_IRIP")
	)
	(segment
		(start 188.3664 -126.2634)
		(end 188.3664 -125.2474)
		(width 0.254)
		(layer "F.Cu")
		(net "VT235_IMAX")
	)
	(segment
		(start 188.3664 -125.2474)
		(end 188.680852 -124.932948)
		(width 0.254)
		(layer "F.Cu")
		(net "VT235_IMAX")
	)
	(segment
		(start 188.5442 -126.5428)
		(end 188.5442 -126.4412)
		(width 0.254)
		(layer "F.Cu")
		(net "VT235_IMAX")
	)
	(segment
		(start 188.5442 -126.4412)
		(end 188.3664 -126.2634)
		(width 0.254)
		(layer "F.Cu")
		(net "VT235_IMAX")
	)
	(segment
		(start 188.680852 -124.932948)
		(end 188.680852 -124.146564)
		(width 0.254)
		(layer "F.Cu")
		(net "VT235_IMAX")
	)
	(via
		(at 187.7822 -125.984)
		(size 0.6096)
		(drill 0.3048)
		(layers "F.Cu" "B.Cu")
		(net "VT235_IMAX")
	)
	(via
		(at 188.5442 -126.5428)
		(size 0.508)
		(drill 0.254)
		(layers "F.Cu" "B.Cu")
		(net "VT235_IMAX")
	)
	(segment
		(start 188.341 -126.5428)
		(end 188.5442 -126.5428)
		(width 0.254)
		(layer "B.Cu")
		(net "VT235_IMAX")
	)
	(segment
		(start 187.7822 -125.984)
		(end 188.341 -126.5428)
		(width 0.254)
		(layer "B.Cu")
		(net "VT235_IMAX")
	)
	(segment
		(start 187.9854 -125.7808)
		(end 187.7822 -125.984)
		(width 0.254)
		(layer "B.Cu")
		(net "VT235_IMAX")
	)
	(segment
		(start 187.9854 -124.849636)
		(end 187.9854 -125.7808)
		(width 0.254)
		(layer "B.Cu")
		(net "VT235_IMAX")
	)
	(segment
		(start 188.980572 -131.289044)
		(end 186.5122 -128.820672)
		(width 0.254)
		(layer "F.Cu")
		(net "VT235_EN")
	)
	(segment
		(start 187.680854 -124.608082)
		(end 187.680854 -124.146564)
		(width 0.254)
		(layer "F.Cu")
		(net "VT235_EN")
	)
	(segment
		(start 188.980572 -131.289044)
		(end 188.980572 -131.58089)
		(width 0.254)
		(layer "F.Cu")
		(net "VT235_EN")
	)
	(segment
		(start 186.5122 -125.776736)
		(end 187.680854 -124.608082)
		(width 0.254)
		(layer "F.Cu")
		(net "VT235_EN")
	)
	(segment
		(start 191.287146 -132.846064)
		(end 191.261746 -132.820664)
		(width 0.254)
		(layer "F.Cu")
		(net "VT235_EN")
	)
	(segment
		(start 188.980572 -131.58089)
		(end 190.220346 -132.820664)
		(width 0.254)
		(layer "F.Cu")
		(net "VT235_EN")
	)
	(segment
		(start 192.303146 -132.846064)
		(end 191.287146 -132.846064)
		(width 0.254)
		(layer "F.Cu")
		(net "VT235_EN")
	)
	(segment
		(start 186.5122 -128.820672)
		(end 186.5122 -125.776736)
		(width 0.254)
		(layer "F.Cu")
		(net "VT235_EN")
	)
	(segment
		(start 191.261746 -132.820664)
		(end 190.220346 -132.820664)
		(width 0.254)
		(layer "F.Cu")
		(net "VT235_EN")
	)
	(via
		(at 188.980572 -131.289044)
		(size 0.6604)
		(drill 0.3302)
		(layers "F.Cu" "B.Cu")
		(net "VT235_EN")
	)
	(segment
		(start 191.9732 -121.458736)
		(end 192.5574 -121.458736)
		(width 0.508)
		(layer "F.Cu")
		(net "VT235_BST")
	)
	(segment
		(start 191.67094 -121.760996)
		(end 191.9732 -121.458736)
		(width 0.3048)
		(layer "F.Cu")
		(net "VT235_BST")
	)
	(segment
		(start 192.807336 -121.458736)
		(end 192.5574 -121.458736)
		(width 0.508)
		(layer "F.Cu")
		(net "VT235_BST")
	)
	(segment
		(start 193.6496 -121.6406)
		(end 192.9892 -121.6406)
		(width 0.508)
		(layer "F.Cu")
		(net "VT235_BST")
	)
	(segment
		(start 191.06642 -121.760996)
		(end 191.67094 -121.760996)
		(width 0.3048)
		(layer "F.Cu")
		(net "VT235_BST")
	)
	(segment
		(start 192.9892 -121.6406)
		(end 192.807336 -121.458736)
		(width 0.508)
		(layer "F.Cu")
		(net "VT235_BST")
	)
	(via
		(at 192.5574 -121.458736)
		(size 0.6604)
		(drill 0.3302)
		(layers "F.Cu" "B.Cu")
		(net "VT235_BST")
	)
	(segment
		(start 189.180724 -125.8189)
		(end 189.180724 -126.328424)
		(width 0.3556)
		(layer "F.Cu")
		(net "VT235_BIAS")
	)
	(segment
		(start 189.180724 -126.328424)
		(end 189.4078 -126.5555)
		(width 0.3556)
		(layer "F.Cu")
		(net "VT235_BIAS")
	)
	(segment
		(start 189.180724 -124.146564)
		(end 189.180724 -125.8189)
		(width 0.3556)
		(layer "F.Cu")
		(net "VT235_BIAS")
	)
	(via
		(at 189.4078 -126.5555)
		(size 0.508)
		(drill 0.254)
		(layers "F.Cu" "B.Cu")
		(net "VT235_BIAS")
	)
	(via
		(at 189.180724 -125.8189)
		(size 0.6604)
		(drill 0.3302)
		(layers "F.Cu" "B.Cu")
		(net "VT235_BIAS")
	)
	(segment
		(start 189.4078 -125.827536)
		(end 189.1284 -125.548136)
		(width 0.508)
		(layer "B.Cu")
		(net "VT235_BIAS")
	)
	(segment
		(start 189.4078 -126.5555)
		(end 189.4078 -125.827536)
		(width 0.508)
		(layer "B.Cu")
		(net "VT235_BIAS")
	)
	(segment
		(start 189.1284 -125.548136)
		(end 189.1284 -124.849636)
		(width 0.508)
		(layer "B.Cu")
		(net "VT235_BIAS")
	)
	(segment
		(start 190.011812 -122.332496)
		(end 190.004954 -122.332496)
		(width 0.3556)
		(layer "F.Cu")
		(net "VT235_AVDD")
	)
	(segment
		(start 189.933326 -122.260868)
		(end 186.795156 -122.260868)
		(width 0.3556)
		(layer "F.Cu")
		(net "VT235_AVDD")
	)
	(segment
		(start 190.35395 -122.681492)
		(end 190.35395 -122.674634)
		(width 0.3556)
		(layer "F.Cu")
		(net "VT235_AVDD")
	)
	(segment
		(start 191.06642 -122.760994)
		(end 190.433452 -122.760994)
		(width 0.3556)
		(layer "F.Cu")
		(net "VT235_AVDD")
	)
	(segment
		(start 185.824876 -122.65406)
		(end 186.218068 -122.260868)
		(width 0.3556)
		(layer "F.Cu")
		(net "VT235_AVDD")
	)
	(segment
		(start 190.433452 -122.760994)
		(end 190.35395 -122.681492)
		(width 0.3556)
		(layer "F.Cu")
		(net "VT235_AVDD")
	)
	(segment
		(start 184.457594 -122.839226)
		(end 184.64276 -122.65406)
		(width 0.508)
		(layer "F.Cu")
		(net "VT235_AVDD")
	)
	(segment
		(start 190.35395 -122.674634)
		(end 190.011812 -122.332496)
		(width 0.3556)
		(layer "F.Cu")
		(net "VT235_AVDD")
	)
	(segment
		(start 190.004954 -122.332496)
		(end 189.933326 -122.260868)
		(width 0.3556)
		(layer "F.Cu")
		(net "VT235_AVDD")
	)
	(segment
		(start 184.64276 -122.65406)
		(end 185.824876 -122.65406)
		(width 0.508)
		(layer "F.Cu")
		(net "VT235_AVDD")
	)
	(segment
		(start 184.1246 -123.952)
		(end 184.1246 -123.17222)
		(width 0.508)
		(layer "F.Cu")
		(net "VT235_AVDD")
	)
	(segment
		(start 184.1246 -123.17222)
		(end 184.457594 -122.839226)
		(width 0.508)
		(layer "F.Cu")
		(net "VT235_AVDD")
	)
	(segment
		(start 184.1246 -123.952)
		(end 182.9308 -123.952)
		(width 0.508)
		(layer "F.Cu")
		(net "VT235_AVDD")
	)
	(segment
		(start 186.218068 -122.260868)
		(end 186.795156 -122.260868)
		(width 0.3556)
		(layer "F.Cu")
		(net "VT235_AVDD")
	)
	(via
		(at 184.457594 -122.839226)
		(size 0.6604)
		(drill 0.3302)
		(layers "F.Cu" "B.Cu")
		(net "VT235_AVDD")
	)
	(segment
		(start 187.600082 -61.500004)
		(end 187.200286 -61.100208)
		(width 0.127)
		(layer "F.Cu")
		(net "VDDIO_15")
	)
	(via
		(at 187.49264 -50.66792)
		(size 0.508)
		(drill 0.254)
		(layers "F.Cu" "B.Cu")
		(net "VDDIO_15")
	)
	(via
		(at 187.200286 -61.100208)
		(size 0.508)
		(drill 0.254)
		(layers "F.Cu" "B.Cu")
		(net "VDDIO_15")
	)
	(segment
		(start 189.21984 -50.14722)
		(end 188.7474 -50.61966)
		(width 0.127)
		(layer "B.Cu")
		(net "VDDIO_15")
	)
	(segment
		(start 188.7474 -50.61966)
		(end 187.5409 -50.61966)
		(width 0.127)
		(layer "B.Cu")
		(net "VDDIO_15")
	)
	(segment
		(start 187.5409 -50.61966)
		(end 187.49264 -50.66792)
		(width 0.127)
		(layer "B.Cu")
		(net "VDDIO_15")
	)
	(segment
		(start 187.8457 -50.66792)
		(end 190.08598 -52.9082)
		(width 0.127)
		(layer "In5.Cu")
		(net "VDDIO_15")
	)
	(segment
		(start 189.95136 -55.52948)
		(end 188.177932 -55.52948)
		(width 0.127)
		(layer "In5.Cu")
		(net "VDDIO_15")
	)
	(segment
		(start 188.177932 -55.52948)
		(end 187.702698 -56.004714)
		(width 0.127)
		(layer "In5.Cu")
		(net "VDDIO_15")
	)
	(segment
		(start 190.08598 -55.39486)
		(end 189.95136 -55.52948)
		(width 0.127)
		(layer "In5.Cu")
		(net "VDDIO_15")
	)
	(segment
		(start 187.600336 -60.700158)
		(end 187.200286 -61.100208)
		(width 0.0889)
		(layer "In5.Cu")
		(net "VDDIO_15")
	)
	(segment
		(start 187.702698 -56.004714)
		(end 187.600082 -56.10733)
		(width 0.0889)
		(layer "In5.Cu")
		(net "VDDIO_15")
	)
	(segment
		(start 187.600082 -57.733946)
		(end 187.600336 -57.7342)
		(width 0.0889)
		(layer "In5.Cu")
		(net "VDDIO_15")
	)
	(segment
		(start 187.49264 -50.66792)
		(end 187.8457 -50.66792)
		(width 0.127)
		(layer "In5.Cu")
		(net "VDDIO_15")
	)
	(segment
		(start 187.600082 -56.10733)
		(end 187.600082 -57.733946)
		(width 0.0889)
		(layer "In5.Cu")
		(net "VDDIO_15")
	)
	(segment
		(start 190.08598 -52.9082)
		(end 190.08598 -55.39486)
		(width 0.127)
		(layer "In5.Cu")
		(net "VDDIO_15")
	)
	(segment
		(start 187.600336 -57.7342)
		(end 187.600336 -60.700158)
		(width 0.0889)
		(layer "In5.Cu")
		(net "VDDIO_15")
	)
	(segment
		(start 196.399912 -67.100196)
		(end 196.399912 -67.099942)
		(width 0.3556)
		(layer "F.Cu")
		(net "VDDA_SAS_REF_CLK")
	)
	(segment
		(start 196.799962 -67.500246)
		(end 196.399912 -67.100196)
		(width 0.3556)
		(layer "F.Cu")
		(net "VDDA_SAS_REF_CLK")
	)
	(via
		(at 196.799962 -67.500246)
		(size 0.508)
		(drill 0.254)
		(layers "F.Cu" "B.Cu")
		(net "VDDA_SAS_REF_CLK")
	)
	(via
		(at 198.4502 -52.7812)
		(size 0.508)
		(drill 0.254)
		(layers "F.Cu" "B.Cu")
		(net "VDDA_SAS_REF_CLK")
	)
	(via
		(at 199.1868 -52.6034)
		(size 0.6096)
		(drill 0.3048)
		(layers "F.Cu" "B.Cu")
		(net "VDDA_SAS_REF_CLK")
	)
	(segment
		(start 198.4502 -52.7812)
		(end 198.14286 -52.47386)
		(width 0.508)
		(layer "In2.Cu")
		(net "VDDA_SAS_REF_CLK")
	)
	(segment
		(start 195.2498 -60.579)
		(end 196.799962 -62.129162)
		(width 0.508)
		(layer "In2.Cu")
		(net "VDDA_SAS_REF_CLK")
	)
	(segment
		(start 195.31076 -52.47386)
		(end 194.818 -52.96662)
		(width 0.508)
		(layer "In2.Cu")
		(net "VDDA_SAS_REF_CLK")
	)
	(segment
		(start 198.14286 -52.47386)
		(end 195.31076 -52.47386)
		(width 0.508)
		(layer "In2.Cu")
		(net "VDDA_SAS_REF_CLK")
	)
	(segment
		(start 195.2498 -55.9435)
		(end 195.2498 -60.579)
		(width 0.508)
		(layer "In2.Cu")
		(net "VDDA_SAS_REF_CLK")
	)
	(segment
		(start 194.818 -52.96662)
		(end 194.818 -54.219856)
		(width 0.508)
		(layer "In2.Cu")
		(net "VDDA_SAS_REF_CLK")
	)
	(segment
		(start 194.590416 -54.44744)
		(end 194.590416 -55.284116)
		(width 0.508)
		(layer "In2.Cu")
		(net "VDDA_SAS_REF_CLK")
	)
	(segment
		(start 194.818 -54.219856)
		(end 194.590416 -54.44744)
		(width 0.508)
		(layer "In2.Cu")
		(net "VDDA_SAS_REF_CLK")
	)
	(segment
		(start 194.590416 -55.284116)
		(end 195.2498 -55.9435)
		(width 0.508)
		(layer "In2.Cu")
		(net "VDDA_SAS_REF_CLK")
	)
	(segment
		(start 196.799962 -62.129162)
		(end 196.799962 -67.500246)
		(width 0.508)
		(layer "In2.Cu")
		(net "VDDA_SAS_REF_CLK")
	)
	(segment
		(start 55.734458 -149.8346)
		(end 56.328818 -149.8346)
		(width 0.14605)
		(layer "F.Cu")
		(net "USB_P3_DP")
	)
	(segment
		(start 88.076024 -154.69997)
		(end 87.271352 -153.895298)
		(width 0.14605)
		(layer "F.Cu")
		(net "USB_P3_DP")
	)
	(segment
		(start 64.44615 -154.08275)
		(end 65.03035 -154.66695)
		(width 0.14605)
		(layer "F.Cu")
		(net "USB_P3_DP")
	)
	(segment
		(start 88.942926 -154.69997)
		(end 88.076024 -154.69997)
		(width 0.14605)
		(layer "F.Cu")
		(net "USB_P3_DP")
	)
	(segment
		(start 85.88121 -153.328878)
		(end 86.038182 -153.171906)
		(width 0.14605)
		(layer "F.Cu")
		(net "USB_P3_DP")
	)
	(segment
		(start 56.328818 -149.8346)
		(end 58.36285 -151.868632)
		(width 0.14605)
		(layer "F.Cu")
		(net "USB_P3_DP")
	)
	(segment
		(start 60.56884 -154.50312)
		(end 62.52972 -154.50312)
		(width 0.14605)
		(layer "F.Cu")
		(net "USB_P3_DP")
	)
	(segment
		(start 58.36285 -151.868632)
		(end 58.36285 -152.29713)
		(width 0.14605)
		(layer "F.Cu")
		(net "USB_P3_DP")
	)
	(segment
		(start 89.037414 -154.605482)
		(end 88.942926 -154.69997)
		(width 0.14605)
		(layer "F.Cu")
		(net "USB_P3_DP")
	)
	(segment
		(start 87.271352 -153.895298)
		(end 86.140036 -153.895298)
		(width 0.14605)
		(layer "F.Cu")
		(net "USB_P3_DP")
	)
	(segment
		(start 62.52972 -154.50312)
		(end 62.95009 -154.08275)
		(width 0.14605)
		(layer "F.Cu")
		(net "USB_P3_DP")
	)
	(segment
		(start 58.36285 -152.29713)
		(end 60.56884 -154.50312)
		(width 0.14605)
		(layer "F.Cu")
		(net "USB_P3_DP")
	)
	(segment
		(start 86.140036 -153.895298)
		(end 85.88121 -153.636472)
		(width 0.14605)
		(layer "F.Cu")
		(net "USB_P3_DP")
	)
	(segment
		(start 55.299864 -149.400006)
		(end 55.734458 -149.8346)
		(width 0.14605)
		(layer "F.Cu")
		(net "USB_P3_DP")
	)
	(segment
		(start 65.03035 -154.66695)
		(end 65.374266 -154.66695)
		(width 0.14605)
		(layer "F.Cu")
		(net "USB_P3_DP")
	)
	(segment
		(start 85.88121 -153.636472)
		(end 85.88121 -153.328878)
		(width 0.14605)
		(layer "F.Cu")
		(net "USB_P3_DP")
	)
	(segment
		(start 65.374266 -154.66695)
		(end 65.6717 -154.964384)
		(width 0.14605)
		(layer "F.Cu")
		(net "USB_P3_DP")
	)
	(segment
		(start 62.95009 -154.08275)
		(end 64.44615 -154.08275)
		(width 0.14605)
		(layer "F.Cu")
		(net "USB_P3_DP")
	)
	(segment
		(start 89.881456 -154.605482)
		(end 89.037414 -154.605482)
		(width 0.14605)
		(layer "F.Cu")
		(net "USB_P3_DP")
	)
	(via
		(at 65.6717 -154.964384)
		(size 0.508)
		(drill 0.254)
		(layers "F.Cu" "B.Cu")
		(net "USB_P3_DP")
	)
	(via
		(at 86.038182 -153.171906)
		(size 0.508)
		(drill 0.254)
		(layers "F.Cu" "B.Cu")
		(net "USB_P3_DP")
	)
	(segment
		(start 85.733636 -153.476452)
		(end 85.733636 -153.86177)
		(width 0.1397)
		(layer "In5.Cu")
		(net "USB_P3_DP")
	)
	(segment
		(start 86.038182 -153.171906)
		(end 85.733636 -153.476452)
		(width 0.1397)
		(layer "In5.Cu")
		(net "USB_P3_DP")
	)
	(segment
		(start 66.450718 -154.6606)
		(end 65.975738 -154.6606)
		(width 0.1397)
		(layer "In5.Cu")
		(net "USB_P3_DP")
	)
	(segment
		(start 65.975738 -154.6606)
		(end 65.6717 -154.964384)
		(width 0.1397)
		(layer "In5.Cu")
		(net "USB_P3_DP")
	)
	(segment
		(start 82.276188 -156.821632)
		(end 74.843894 -156.821632)
		(width 0.1397)
		(layer "In5.Cu")
		(net "USB_P3_DP")
	)
	(segment
		(start 84.79282 -154.305)
		(end 82.276188 -156.821632)
		(width 0.1397)
		(layer "In5.Cu")
		(net "USB_P3_DP")
	)
	(segment
		(start 67.034918 -154.0764)
		(end 66.450718 -154.6606)
		(width 0.1397)
		(layer "In5.Cu")
		(net "USB_P3_DP")
	)
	(segment
		(start 85.733636 -153.86177)
		(end 85.290406 -154.305)
		(width 0.1397)
		(layer "In5.Cu")
		(net "USB_P3_DP")
	)
	(segment
		(start 85.290406 -154.305)
		(end 84.79282 -154.305)
		(width 0.1397)
		(layer "In5.Cu")
		(net "USB_P3_DP")
	)
	(segment
		(start 72.098662 -154.0764)
		(end 67.034918 -154.0764)
		(width 0.1397)
		(layer "In5.Cu")
		(net "USB_P3_DP")
	)
	(segment
		(start 74.843894 -156.821632)
		(end 72.098662 -154.0764)
		(width 0.1397)
		(layer "In5.Cu")
		(net "USB_P3_DP")
	)
	(segment
		(start 88.942926 -155.01112)
		(end 87.946992 -155.01112)
		(width 0.14605)
		(layer "F.Cu")
		(net "USB_P3_DN")
	)
	(segment
		(start 89.03716 -155.105354)
		(end 88.942926 -155.01112)
		(width 0.14605)
		(layer "F.Cu")
		(net "USB_P3_DN")
	)
	(segment
		(start 86.011004 -154.206448)
		(end 85.413088 -153.608532)
		(width 0.14605)
		(layer "F.Cu")
		(net "USB_P3_DN")
	)
	(segment
		(start 87.14232 -154.206448)
		(end 86.011004 -154.206448)
		(width 0.14605)
		(layer "F.Cu")
		(net "USB_P3_DN")
	)
	(segment
		(start 62.400688 -154.19197)
		(end 62.821058 -153.7716)
		(width 0.14605)
		(layer "F.Cu")
		(net "USB_P3_DN")
	)
	(segment
		(start 85.413088 -153.608532)
		(end 85.413088 -153.48585)
		(width 0.14605)
		(layer "F.Cu")
		(net "USB_P3_DN")
	)
	(segment
		(start 65.159382 -154.3558)
		(end 65.373758 -154.3558)
		(width 0.14605)
		(layer "F.Cu")
		(net "USB_P3_DN")
	)
	(segment
		(start 85.413088 -153.48585)
		(end 85.099144 -153.171906)
		(width 0.14605)
		(layer "F.Cu")
		(net "USB_P3_DN")
	)
	(segment
		(start 64.575182 -153.7716)
		(end 65.159382 -154.3558)
		(width 0.14605)
		(layer "F.Cu")
		(net "USB_P3_DN")
	)
	(segment
		(start 65.373758 -154.3558)
		(end 65.6717 -154.057858)
		(width 0.14605)
		(layer "F.Cu")
		(net "USB_P3_DN")
	)
	(segment
		(start 89.881456 -155.105354)
		(end 89.03716 -155.105354)
		(width 0.14605)
		(layer "F.Cu")
		(net "USB_P3_DN")
	)
	(segment
		(start 58.674 -152.168098)
		(end 60.697872 -154.19197)
		(width 0.14605)
		(layer "F.Cu")
		(net "USB_P3_DN")
	)
	(segment
		(start 56.099964 -149.400006)
		(end 56.223408 -149.52345)
		(width 0.14605)
		(layer "F.Cu")
		(net "USB_P3_DN")
	)
	(segment
		(start 56.45785 -149.52345)
		(end 58.674 -151.7396)
		(width 0.14605)
		(layer "F.Cu")
		(net "USB_P3_DN")
	)
	(segment
		(start 58.674 -151.7396)
		(end 58.674 -152.168098)
		(width 0.14605)
		(layer "F.Cu")
		(net "USB_P3_DN")
	)
	(segment
		(start 87.946992 -155.01112)
		(end 87.14232 -154.206448)
		(width 0.14605)
		(layer "F.Cu")
		(net "USB_P3_DN")
	)
	(segment
		(start 60.697872 -154.19197)
		(end 62.400688 -154.19197)
		(width 0.14605)
		(layer "F.Cu")
		(net "USB_P3_DN")
	)
	(segment
		(start 56.223408 -149.52345)
		(end 56.45785 -149.52345)
		(width 0.14605)
		(layer "F.Cu")
		(net "USB_P3_DN")
	)
	(segment
		(start 62.821058 -153.7716)
		(end 64.575182 -153.7716)
		(width 0.14605)
		(layer "F.Cu")
		(net "USB_P3_DN")
	)
	(via
		(at 85.099144 -153.171906)
		(size 0.508)
		(drill 0.254)
		(layers "F.Cu" "B.Cu")
		(net "USB_P3_DN")
	)
	(via
		(at 65.6717 -154.057858)
		(size 0.508)
		(drill 0.254)
		(layers "F.Cu" "B.Cu")
		(net "USB_P3_DN")
	)
	(segment
		(start 84.108036 -154.271218)
		(end 84.359496 -154.271218)
		(width 0.1397)
		(layer "In5.Cu")
		(net "USB_P3_DN")
	)
	(segment
		(start 80.125824 -156.313632)
		(end 80.303624 -156.491432)
		(width 0.1397)
		(layer "In5.Cu")
		(net "USB_P3_DN")
	)
	(segment
		(start 66.898012 -153.7462)
		(end 72.235568 -153.7462)
		(width 0.1397)
		(layer "In5.Cu")
		(net "USB_P3_DN")
	)
	(segment
		(start 83.811872 -154.818842)
		(end 83.811872 -154.567382)
		(width 0.1397)
		(layer "In5.Cu")
		(net "USB_P3_DN")
	)
	(segment
		(start 81.497424 -156.491432)
		(end 82.139282 -156.491432)
		(width 0.1397)
		(layer "In5.Cu")
		(net "USB_P3_DN")
	)
	(segment
		(start 77.916024 -156.491432)
		(end 78.335124 -156.491432)
		(width 0.1397)
		(layer "In5.Cu")
		(net "USB_P3_DN")
	)
	(segment
		(start 72.235568 -153.7462)
		(end 74.9808 -156.491432)
		(width 0.1397)
		(layer "In5.Cu")
		(net "USB_P3_DN")
	)
	(segment
		(start 78.932024 -156.313632)
		(end 79.109824 -156.491432)
		(width 0.1397)
		(layer "In5.Cu")
		(net "USB_P3_DN")
	)
	(segment
		(start 84.655914 -153.9748)
		(end 85.1535 -153.9748)
		(width 0.1397)
		(layer "In5.Cu")
		(net "USB_P3_DN")
	)
	(segment
		(start 80.303624 -156.491432)
		(end 80.722724 -156.491432)
		(width 0.1397)
		(layer "In5.Cu")
		(net "USB_P3_DN")
	)
	(segment
		(start 77.738224 -156.313632)
		(end 77.916024 -156.491432)
		(width 0.1397)
		(layer "In5.Cu")
		(net "USB_P3_DN")
	)
	(segment
		(start 81.319624 -156.313632)
		(end 81.497424 -156.491432)
		(width 0.1397)
		(layer "In5.Cu")
		(net "USB_P3_DN")
	)
	(segment
		(start 80.900524 -156.313632)
		(end 81.319624 -156.313632)
		(width 0.1397)
		(layer "In5.Cu")
		(net "USB_P3_DN")
	)
	(segment
		(start 82.967576 -155.411678)
		(end 83.263994 -155.11526)
		(width 0.1397)
		(layer "In5.Cu")
		(net "USB_P3_DN")
	)
	(segment
		(start 66.313812 -154.3304)
		(end 66.898012 -153.7462)
		(width 0.1397)
		(layer "In5.Cu")
		(net "USB_P3_DN")
	)
	(segment
		(start 85.403436 -153.476198)
		(end 85.099144 -153.171906)
		(width 0.1397)
		(layer "In5.Cu")
		(net "USB_P3_DN")
	)
	(segment
		(start 80.722724 -156.491432)
		(end 80.900524 -156.313632)
		(width 0.1397)
		(layer "In5.Cu")
		(net "USB_P3_DN")
	)
	(segment
		(start 77.141324 -156.491432)
		(end 77.319124 -156.313632)
		(width 0.1397)
		(layer "In5.Cu")
		(net "USB_P3_DN")
	)
	(segment
		(start 65.6717 -154.057858)
		(end 65.944242 -154.3304)
		(width 0.1397)
		(layer "In5.Cu")
		(net "USB_P3_DN")
	)
	(segment
		(start 84.359496 -154.271218)
		(end 84.655914 -153.9748)
		(width 0.1397)
		(layer "In5.Cu")
		(net "USB_P3_DN")
	)
	(segment
		(start 79.109824 -156.491432)
		(end 79.528924 -156.491432)
		(width 0.1397)
		(layer "In5.Cu")
		(net "USB_P3_DN")
	)
	(segment
		(start 77.319124 -156.313632)
		(end 77.738224 -156.313632)
		(width 0.1397)
		(layer "In5.Cu")
		(net "USB_P3_DN")
	)
	(segment
		(start 82.139282 -156.491432)
		(end 82.967576 -155.663138)
		(width 0.1397)
		(layer "In5.Cu")
		(net "USB_P3_DN")
	)
	(segment
		(start 85.1535 -153.9748)
		(end 85.403436 -153.724864)
		(width 0.1397)
		(layer "In5.Cu")
		(net "USB_P3_DN")
	)
	(segment
		(start 74.9808 -156.491432)
		(end 77.141324 -156.491432)
		(width 0.1397)
		(layer "In5.Cu")
		(net "USB_P3_DN")
	)
	(segment
		(start 83.263994 -155.11526)
		(end 83.515454 -155.11526)
		(width 0.1397)
		(layer "In5.Cu")
		(net "USB_P3_DN")
	)
	(segment
		(start 79.528924 -156.491432)
		(end 79.706724 -156.313632)
		(width 0.1397)
		(layer "In5.Cu")
		(net "USB_P3_DN")
	)
	(segment
		(start 83.515454 -155.11526)
		(end 83.811872 -154.818842)
		(width 0.1397)
		(layer "In5.Cu")
		(net "USB_P3_DN")
	)
	(segment
		(start 78.512924 -156.313632)
		(end 78.932024 -156.313632)
		(width 0.1397)
		(layer "In5.Cu")
		(net "USB_P3_DN")
	)
	(segment
		(start 79.706724 -156.313632)
		(end 80.125824 -156.313632)
		(width 0.1397)
		(layer "In5.Cu")
		(net "USB_P3_DN")
	)
	(segment
		(start 78.335124 -156.491432)
		(end 78.512924 -156.313632)
		(width 0.1397)
		(layer "In5.Cu")
		(net "USB_P3_DN")
	)
	(segment
		(start 65.944242 -154.3304)
		(end 66.313812 -154.3304)
		(width 0.1397)
		(layer "In5.Cu")
		(net "USB_P3_DN")
	)
	(segment
		(start 82.967576 -155.663138)
		(end 82.967576 -155.411678)
		(width 0.1397)
		(layer "In5.Cu")
		(net "USB_P3_DN")
	)
	(segment
		(start 83.811872 -154.567382)
		(end 84.108036 -154.271218)
		(width 0.1397)
		(layer "In5.Cu")
		(net "USB_P3_DN")
	)
	(segment
		(start 85.403436 -153.724864)
		(end 85.403436 -153.476198)
		(width 0.1397)
		(layer "In5.Cu")
		(net "USB_P3_DN")
	)
	(segment
		(start 58.585608 -149.4536)
		(end 57.724294 -149.4536)
		(width 0.14605)
		(layer "F.Cu")
		(net "USB_P2_DP")
	)
	(segment
		(start 88.980264 -156.213302)
		(end 89.08796 -156.105606)
		(width 0.14605)
		(layer "F.Cu")
		(net "USB_P2_DP")
	)
	(segment
		(start 56.337962 -148.361908)
		(end 56.099964 -148.599906)
		(width 0.14605)
		(layer "F.Cu")
		(net "USB_P2_DP")
	)
	(segment
		(start 60.293758 -151.16175)
		(end 58.585608 -149.4536)
		(width 0.14605)
		(layer "F.Cu")
		(net "USB_P2_DP")
	)
	(segment
		(start 63.565278 -152.50795)
		(end 63.30315 -152.50795)
		(width 0.14605)
		(layer "F.Cu")
		(net "USB_P2_DP")
	)
	(segment
		(start 88.32088 -156.213302)
		(end 88.980264 -156.213302)
		(width 0.14605)
		(layer "F.Cu")
		(net "USB_P2_DP")
	)
	(segment
		(start 57.724294 -149.4536)
		(end 56.632602 -148.361908)
		(width 0.14605)
		(layer "F.Cu")
		(net "USB_P2_DP")
	)
	(segment
		(start 56.632602 -148.361908)
		(end 56.337962 -148.361908)
		(width 0.14605)
		(layer "F.Cu")
		(net "USB_P2_DP")
	)
	(segment
		(start 61.95695 -151.16175)
		(end 60.293758 -151.16175)
		(width 0.14605)
		(layer "F.Cu")
		(net "USB_P2_DP")
	)
	(segment
		(start 63.30315 -152.50795)
		(end 61.95695 -151.16175)
		(width 0.14605)
		(layer "F.Cu")
		(net "USB_P2_DP")
	)
	(segment
		(start 86.610698 -156.062934)
		(end 88.170512 -156.062934)
		(width 0.14605)
		(layer "F.Cu")
		(net "USB_P2_DP")
	)
	(segment
		(start 88.170512 -156.062934)
		(end 88.32088 -156.213302)
		(width 0.14605)
		(layer "F.Cu")
		(net "USB_P2_DP")
	)
	(segment
		(start 63.839852 -152.782524)
		(end 63.565278 -152.50795)
		(width 0.14605)
		(layer "F.Cu")
		(net "USB_P2_DP")
	)
	(segment
		(start 89.08796 -156.105606)
		(end 89.881456 -156.105606)
		(width 0.14605)
		(layer "F.Cu")
		(net "USB_P2_DP")
	)
	(segment
		(start 86.296754 -155.74899)
		(end 86.610698 -156.062934)
		(width 0.14605)
		(layer "F.Cu")
		(net "USB_P2_DP")
	)
	(via
		(at 86.296754 -155.74899)
		(size 0.508)
		(drill 0.254)
		(layers "F.Cu" "B.Cu")
		(net "USB_P2_DP")
	)
	(via
		(at 63.839852 -152.782524)
		(size 0.508)
		(drill 0.254)
		(layers "F.Cu" "B.Cu")
		(net "USB_P2_DP")
	)
	(segment
		(start 73.19391 -152.743662)
		(end 73.01611 -152.921462)
		(width 0.1397)
		(layer "In5.Cu")
		(net "USB_P2_DP")
	)
	(segment
		(start 80.592422 -155.1432)
		(end 79.593948 -155.1432)
		(width 0.1397)
		(layer "In5.Cu")
		(net "USB_P2_DP")
	)
	(segment
		(start 71.82231 -152.921462)
		(end 71.40321 -152.921462)
		(width 0.1397)
		(layer "In5.Cu")
		(net "USB_P2_DP")
	)
	(segment
		(start 72.00011 -152.743662)
		(end 71.82231 -152.921462)
		(width 0.1397)
		(layer "In5.Cu")
		(net "USB_P2_DP")
	)
	(segment
		(start 82.28076 -153.706322)
		(end 81.984342 -154.00274)
		(width 0.1397)
		(layer "In5.Cu")
		(net "USB_P2_DP")
	)
	(segment
		(start 80.88884 -154.846782)
		(end 80.592422 -155.1432)
		(width 0.1397)
		(layer "In5.Cu")
		(net "USB_P2_DP")
	)
	(segment
		(start 87.1982 -152.2984)
		(end 84.723224 -152.2984)
		(width 0.1397)
		(layer "In5.Cu")
		(net "USB_P2_DP")
	)
	(segment
		(start 76.609448 -155.321)
		(end 76.431648 -155.1432)
		(width 0.1397)
		(layer "In5.Cu")
		(net "USB_P2_DP")
	)
	(segment
		(start 71.22541 -152.743662)
		(end 69.377814 -152.743662)
		(width 0.1397)
		(layer "In5.Cu")
		(net "USB_P2_DP")
	)
	(segment
		(start 86.296754 -155.74899)
		(end 86.633558 -156.085794)
		(width 0.1397)
		(layer "In5.Cu")
		(net "USB_P2_DP")
	)
	(segment
		(start 72.59701 -152.921462)
		(end 72.41921 -152.743662)
		(width 0.1397)
		(layer "In5.Cu")
		(net "USB_P2_DP")
	)
	(segment
		(start 84.568538 -152.453086)
		(end 83.282536 -152.453086)
		(width 0.1397)
		(layer "In5.Cu")
		(net "USB_P2_DP")
	)
	(segment
		(start 78.819248 -155.1432)
		(end 78.400148 -155.1432)
		(width 0.1397)
		(layer "In5.Cu")
		(net "USB_P2_DP")
	)
	(segment
		(start 79.593948 -155.1432)
		(end 79.416148 -155.321)
		(width 0.1397)
		(layer "In5.Cu")
		(net "USB_P2_DP")
	)
	(segment
		(start 87.5538 -155.702)
		(end 87.5538 -152.654)
		(width 0.1397)
		(layer "In5.Cu")
		(net "USB_P2_DP")
	)
	(segment
		(start 84.723224 -152.2984)
		(end 84.568538 -152.453086)
		(width 0.1397)
		(layer "In5.Cu")
		(net "USB_P2_DP")
	)
	(segment
		(start 78.400148 -155.1432)
		(end 78.222348 -155.321)
		(width 0.1397)
		(layer "In5.Cu")
		(net "USB_P2_DP")
	)
	(segment
		(start 69.377814 -152.743662)
		(end 69.142102 -152.50795)
		(width 0.1397)
		(layer "In5.Cu")
		(net "USB_P2_DP")
	)
	(segment
		(start 81.732882 -154.00274)
		(end 81.436464 -154.299158)
		(width 0.1397)
		(layer "In5.Cu")
		(net "USB_P2_DP")
	)
	(segment
		(start 83.282536 -152.453086)
		(end 82.28076 -153.454862)
		(width 0.1397)
		(layer "In5.Cu")
		(net "USB_P2_DP")
	)
	(segment
		(start 76.012548 -155.1432)
		(end 73.61301 -152.743662)
		(width 0.1397)
		(layer "In5.Cu")
		(net "USB_P2_DP")
	)
	(segment
		(start 78.997048 -155.321)
		(end 78.819248 -155.1432)
		(width 0.1397)
		(layer "In5.Cu")
		(net "USB_P2_DP")
	)
	(segment
		(start 81.984342 -154.00274)
		(end 81.732882 -154.00274)
		(width 0.1397)
		(layer "In5.Cu")
		(net "USB_P2_DP")
	)
	(segment
		(start 86.633558 -156.085794)
		(end 87.170006 -156.085794)
		(width 0.1397)
		(layer "In5.Cu")
		(net "USB_P2_DP")
	)
	(segment
		(start 87.170006 -156.085794)
		(end 87.5538 -155.702)
		(width 0.1397)
		(layer "In5.Cu")
		(net "USB_P2_DP")
	)
	(segment
		(start 87.5538 -152.654)
		(end 87.1982 -152.2984)
		(width 0.1397)
		(layer "In5.Cu")
		(net "USB_P2_DP")
	)
	(segment
		(start 73.61301 -152.743662)
		(end 73.19391 -152.743662)
		(width 0.1397)
		(layer "In5.Cu")
		(net "USB_P2_DP")
	)
	(segment
		(start 72.41921 -152.743662)
		(end 72.00011 -152.743662)
		(width 0.1397)
		(layer "In5.Cu")
		(net "USB_P2_DP")
	)
	(segment
		(start 79.416148 -155.321)
		(end 78.997048 -155.321)
		(width 0.1397)
		(layer "In5.Cu")
		(net "USB_P2_DP")
	)
	(segment
		(start 76.431648 -155.1432)
		(end 76.012548 -155.1432)
		(width 0.1397)
		(layer "In5.Cu")
		(net "USB_P2_DP")
	)
	(segment
		(start 82.28076 -153.454862)
		(end 82.28076 -153.706322)
		(width 0.1397)
		(layer "In5.Cu")
		(net "USB_P2_DP")
	)
	(segment
		(start 69.142102 -152.50795)
		(end 64.114426 -152.50795)
		(width 0.1397)
		(layer "In5.Cu")
		(net "USB_P2_DP")
	)
	(segment
		(start 77.028548 -155.321)
		(end 76.609448 -155.321)
		(width 0.1397)
		(layer "In5.Cu")
		(net "USB_P2_DP")
	)
	(segment
		(start 81.436464 -154.299158)
		(end 81.436464 -154.550618)
		(width 0.1397)
		(layer "In5.Cu")
		(net "USB_P2_DP")
	)
	(segment
		(start 71.40321 -152.921462)
		(end 71.22541 -152.743662)
		(width 0.1397)
		(layer "In5.Cu")
		(net "USB_P2_DP")
	)
	(segment
		(start 77.625448 -155.1432)
		(end 77.206348 -155.1432)
		(width 0.1397)
		(layer "In5.Cu")
		(net "USB_P2_DP")
	)
	(segment
		(start 73.01611 -152.921462)
		(end 72.59701 -152.921462)
		(width 0.1397)
		(layer "In5.Cu")
		(net "USB_P2_DP")
	)
	(segment
		(start 64.114426 -152.50795)
		(end 63.839852 -152.782524)
		(width 0.1397)
		(layer "In5.Cu")
		(net "USB_P2_DP")
	)
	(segment
		(start 81.436464 -154.550618)
		(end 81.1403 -154.846782)
		(width 0.1397)
		(layer "In5.Cu")
		(net "USB_P2_DP")
	)
	(segment
		(start 81.1403 -154.846782)
		(end 80.88884 -154.846782)
		(width 0.1397)
		(layer "In5.Cu")
		(net "USB_P2_DP")
	)
	(segment
		(start 77.206348 -155.1432)
		(end 77.028548 -155.321)
		(width 0.1397)
		(layer "In5.Cu")
		(net "USB_P2_DP")
	)
	(segment
		(start 77.803248 -155.321)
		(end 77.625448 -155.1432)
		(width 0.1397)
		(layer "In5.Cu")
		(net "USB_P2_DP")
	)
	(segment
		(start 78.222348 -155.321)
		(end 77.803248 -155.321)
		(width 0.1397)
		(layer "In5.Cu")
		(net "USB_P2_DP")
	)
	(segment
		(start 56.761634 -148.050758)
		(end 56.350662 -148.050758)
		(width 0.14605)
		(layer "F.Cu")
		(net "USB_P2_DN")
	)
	(segment
		(start 88.945974 -156.524452)
		(end 89.027 -156.605478)
		(width 0.14605)
		(layer "F.Cu")
		(net "USB_P2_DN")
	)
	(segment
		(start 60.42279 -150.8506)
		(end 58.71464 -149.14245)
		(width 0.14605)
		(layer "F.Cu")
		(net "USB_P2_DN")
	)
	(segment
		(start 86.610698 -156.374084)
		(end 88.04148 -156.374084)
		(width 0.14605)
		(layer "F.Cu")
		(net "USB_P2_DN")
	)
	(segment
		(start 89.027 -156.605478)
		(end 89.881456 -156.605478)
		(width 0.14605)
		(layer "F.Cu")
		(net "USB_P2_DN")
	)
	(segment
		(start 88.191848 -156.524452)
		(end 88.945974 -156.524452)
		(width 0.14605)
		(layer "F.Cu")
		(net "USB_P2_DN")
	)
	(segment
		(start 88.04148 -156.374084)
		(end 88.191848 -156.524452)
		(width 0.14605)
		(layer "F.Cu")
		(net "USB_P2_DN")
	)
	(segment
		(start 63.55588 -152.1968)
		(end 63.432182 -152.1968)
		(width 0.14605)
		(layer "F.Cu")
		(net "USB_P2_DN")
	)
	(segment
		(start 57.853326 -149.14245)
		(end 56.761634 -148.050758)
		(width 0.14605)
		(layer "F.Cu")
		(net "USB_P2_DN")
	)
	(segment
		(start 62.085982 -150.8506)
		(end 60.42279 -150.8506)
		(width 0.14605)
		(layer "F.Cu")
		(net "USB_P2_DN")
	)
	(segment
		(start 56.350662 -148.050758)
		(end 56.099964 -147.80006)
		(width 0.14605)
		(layer "F.Cu")
		(net "USB_P2_DN")
	)
	(segment
		(start 86.296754 -156.688028)
		(end 86.610698 -156.374084)
		(width 0.14605)
		(layer "F.Cu")
		(net "USB_P2_DN")
	)
	(segment
		(start 58.71464 -149.14245)
		(end 57.853326 -149.14245)
		(width 0.14605)
		(layer "F.Cu")
		(net "USB_P2_DN")
	)
	(segment
		(start 63.432182 -152.1968)
		(end 62.085982 -150.8506)
		(width 0.14605)
		(layer "F.Cu")
		(net "USB_P2_DN")
	)
	(segment
		(start 63.833756 -151.918924)
		(end 63.55588 -152.1968)
		(width 0.14605)
		(layer "F.Cu")
		(net "USB_P2_DN")
	)
	(via
		(at 86.296754 -156.688028)
		(size 0.508)
		(drill 0.254)
		(layers "F.Cu" "B.Cu")
		(net "USB_P2_DN")
	)
	(via
		(at 63.833756 -151.918924)
		(size 0.508)
		(drill 0.254)
		(layers "F.Cu" "B.Cu")
		(net "USB_P2_DN")
	)
	(segment
		(start 64.092582 -152.17775)
		(end 63.833756 -151.918924)
		(width 0.1397)
		(layer "In5.Cu")
		(net "USB_P2_DN")
	)
	(segment
		(start 76.149454 -154.813)
		(end 73.749916 -152.413462)
		(width 0.1397)
		(layer "In5.Cu")
		(net "USB_P2_DN")
	)
	(segment
		(start 69.279008 -152.17775)
		(end 64.092582 -152.17775)
		(width 0.1397)
		(layer "In5.Cu")
		(net "USB_P2_DN")
	)
	(segment
		(start 84.431632 -152.122886)
		(end 83.14563 -152.122886)
		(width 0.1397)
		(layer "In5.Cu")
		(net "USB_P2_DN")
	)
	(segment
		(start 84.586318 -151.9682)
		(end 84.431632 -152.122886)
		(width 0.1397)
		(layer "In5.Cu")
		(net "USB_P2_DN")
	)
	(segment
		(start 87.335106 -151.9682)
		(end 84.586318 -151.9682)
		(width 0.1397)
		(layer "In5.Cu")
		(net "USB_P2_DN")
	)
	(segment
		(start 86.568788 -156.415994)
		(end 87.306912 -156.415994)
		(width 0.1397)
		(layer "In5.Cu")
		(net "USB_P2_DN")
	)
	(segment
		(start 87.306912 -156.415994)
		(end 87.884 -155.838906)
		(width 0.1397)
		(layer "In5.Cu")
		(net "USB_P2_DN")
	)
	(segment
		(start 86.296754 -156.688028)
		(end 86.568788 -156.415994)
		(width 0.1397)
		(layer "In5.Cu")
		(net "USB_P2_DN")
	)
	(segment
		(start 83.14563 -152.122886)
		(end 80.455516 -154.813)
		(width 0.1397)
		(layer "In5.Cu")
		(net "USB_P2_DN")
	)
	(segment
		(start 87.884 -152.517094)
		(end 87.335106 -151.9682)
		(width 0.1397)
		(layer "In5.Cu")
		(net "USB_P2_DN")
	)
	(segment
		(start 87.884 -155.838906)
		(end 87.884 -152.517094)
		(width 0.1397)
		(layer "In5.Cu")
		(net "USB_P2_DN")
	)
	(segment
		(start 73.749916 -152.413462)
		(end 69.51472 -152.413462)
		(width 0.1397)
		(layer "In5.Cu")
		(net "USB_P2_DN")
	)
	(segment
		(start 80.455516 -154.813)
		(end 76.149454 -154.813)
		(width 0.1397)
		(layer "In5.Cu")
		(net "USB_P2_DN")
	)
	(segment
		(start 69.51472 -152.413462)
		(end 69.279008 -152.17775)
		(width 0.1397)
		(layer "In5.Cu")
		(net "USB_P2_DN")
	)
	(segment
		(start 99.193858 -16.682466)
		(end 99.193858 -17.06626)
		(width 0.14605)
		(layer "F.Cu")
		(net "USB_P1_F_DP1")
	)
	(segment
		(start 89.59215 -16.920718)
		(end 89.334594 -16.920718)
		(width 0.14605)
		(layer "F.Cu")
		(net "USB_P1_F_DP1")
	)
	(segment
		(start 98.866706 -16.355314)
		(end 99.193858 -16.682466)
		(width 0.14605)
		(layer "F.Cu")
		(net "USB_P1_F_DP1")
	)
	(segment
		(start 98.866706 -15.849346)
		(end 98.866706 -16.355314)
		(width 0.14605)
		(layer "F.Cu")
		(net "USB_P1_F_DP1")
	)
	(segment
		(start 98.538538 -15.521178)
		(end 98.866706 -15.849346)
		(width 0.14605)
		(layer "F.Cu")
		(net "USB_P1_F_DP1")
	)
	(segment
		(start 94.488 -16.7005)
		(end 94.70771 -16.92021)
		(width 0.14605)
		(layer "F.Cu")
		(net "USB_P1_F_DP1")
	)
	(segment
		(start 89.334594 -16.920718)
		(end 88.542876 -17.712436)
		(width 0.14605)
		(layer "F.Cu")
		(net "USB_P1_F_DP1")
	)
	(segment
		(start 97.52584 -15.521178)
		(end 98.538538 -15.521178)
		(width 0.14605)
		(layer "F.Cu")
		(net "USB_P1_F_DP1")
	)
	(segment
		(start 94.488 -16.7005)
		(end 94.267528 -16.920972)
		(width 0.14605)
		(layer "F.Cu")
		(net "USB_P1_F_DP1")
	)
	(segment
		(start 94.267528 -16.920972)
		(end 89.592404 -16.920972)
		(width 0.14605)
		(layer "F.Cu")
		(net "USB_P1_F_DP1")
	)
	(segment
		(start 88.542876 -17.712436)
		(end 88.203532 -17.712436)
		(width 0.14605)
		(layer "F.Cu")
		(net "USB_P1_F_DP1")
	)
	(segment
		(start 88.203532 -17.712436)
		(end 88.000078 -17.508982)
		(width 0.14605)
		(layer "F.Cu")
		(net "USB_P1_F_DP1")
	)
	(segment
		(start 94.70771 -16.92021)
		(end 96.126808 -16.92021)
		(width 0.14605)
		(layer "F.Cu")
		(net "USB_P1_F_DP1")
	)
	(segment
		(start 88.000078 -17.508982)
		(end 88.000078 -16.9799)
		(width 0.14605)
		(layer "F.Cu")
		(net "USB_P1_F_DP1")
	)
	(segment
		(start 89.592404 -16.920972)
		(end 89.59215 -16.920718)
		(width 0.14605)
		(layer "F.Cu")
		(net "USB_P1_F_DP1")
	)
	(segment
		(start 96.126808 -16.92021)
		(end 97.52584 -15.521178)
		(width 0.14605)
		(layer "F.Cu")
		(net "USB_P1_F_DP1")
	)
	(segment
		(start 88.000078 -18.19529)
		(end 88.000078 -18.979896)
		(width 0.14605)
		(layer "F.Cu")
		(net "USB_P1_F_DN1")
	)
	(segment
		(start 96.25584 -17.23136)
		(end 96.392238 -17.094962)
		(width 0.14605)
		(layer "F.Cu")
		(net "USB_P1_F_DN1")
	)
	(segment
		(start 96.622108 -17.094962)
		(end 96.931988 -16.785082)
		(width 0.14605)
		(layer "F.Cu")
		(net "USB_P1_F_DN1")
	)
	(segment
		(start 92.085668 -17.232122)
		(end 91.923108 -17.394682)
		(width 0.14605)
		(layer "F.Cu")
		(net "USB_P1_F_DN1")
	)
	(segment
		(start 94.488 -17.4371)
		(end 94.69374 -17.23136)
		(width 0.14605)
		(layer "F.Cu")
		(net "USB_P1_F_DN1")
	)
	(segment
		(start 98.555556 -15.978378)
		(end 98.555556 -16.366998)
		(width 0.14605)
		(layer "F.Cu")
		(net "USB_P1_F_DN1")
	)
	(segment
		(start 98.555556 -16.366998)
		(end 98.228658 -16.693896)
		(width 0.14605)
		(layer "F.Cu")
		(net "USB_P1_F_DN1")
	)
	(segment
		(start 98.409506 -15.832328)
		(end 98.555556 -15.978378)
		(width 0.14605)
		(layer "F.Cu")
		(net "USB_P1_F_DN1")
	)
	(segment
		(start 88.671908 -18.023586)
		(end 88.171782 -18.023586)
		(width 0.14605)
		(layer "F.Cu")
		(net "USB_P1_F_DN1")
	)
	(segment
		(start 88.171782 -18.023586)
		(end 88.000078 -18.19529)
		(width 0.14605)
		(layer "F.Cu")
		(net "USB_P1_F_DN1")
	)
	(segment
		(start 91.484958 -17.394682)
		(end 91.322398 -17.232122)
		(width 0.14605)
		(layer "F.Cu")
		(net "USB_P1_F_DN1")
	)
	(segment
		(start 94.283022 -17.232122)
		(end 92.085668 -17.232122)
		(width 0.14605)
		(layer "F.Cu")
		(net "USB_P1_F_DN1")
	)
	(segment
		(start 91.923108 -17.394682)
		(end 91.484958 -17.394682)
		(width 0.14605)
		(layer "F.Cu")
		(net "USB_P1_F_DN1")
	)
	(segment
		(start 96.392238 -17.094962)
		(end 96.622108 -17.094962)
		(width 0.14605)
		(layer "F.Cu")
		(net "USB_P1_F_DN1")
	)
	(segment
		(start 96.931988 -16.785082)
		(end 96.931988 -16.555212)
		(width 0.14605)
		(layer "F.Cu")
		(net "USB_P1_F_DN1")
	)
	(segment
		(start 94.488 -17.4371)
		(end 94.283022 -17.232122)
		(width 0.14605)
		(layer "F.Cu")
		(net "USB_P1_F_DN1")
	)
	(segment
		(start 89.463372 -17.232122)
		(end 88.671908 -18.023586)
		(width 0.14605)
		(layer "F.Cu")
		(net "USB_P1_F_DN1")
	)
	(segment
		(start 91.322398 -17.232122)
		(end 89.463372 -17.232122)
		(width 0.14605)
		(layer "F.Cu")
		(net "USB_P1_F_DN1")
	)
	(segment
		(start 96.931988 -16.555212)
		(end 97.654872 -15.832328)
		(width 0.14605)
		(layer "F.Cu")
		(net "USB_P1_F_DN1")
	)
	(segment
		(start 97.654872 -15.832328)
		(end 98.409506 -15.832328)
		(width 0.14605)
		(layer "F.Cu")
		(net "USB_P1_F_DN1")
	)
	(segment
		(start 98.228658 -16.693896)
		(end 98.228658 -17.06626)
		(width 0.14605)
		(layer "F.Cu")
		(net "USB_P1_F_DN1")
	)
	(segment
		(start 94.69374 -17.23136)
		(end 96.25584 -17.23136)
		(width 0.14605)
		(layer "F.Cu")
		(net "USB_P1_F_DN1")
	)
	(segment
		(start 86.699344 -160.065974)
		(end 86.699344 -158.90367)
		(width 0.14605)
		(layer "F.Cu")
		(net "USB_P1_DP")
	)
	(segment
		(start 98.834956 -19.381724)
		(end 99.193858 -19.022822)
		(width 0.14605)
		(layer "F.Cu")
		(net "USB_P1_DP")
	)
	(segment
		(start 98.834956 -19.901154)
		(end 98.834956 -19.381724)
		(width 0.14605)
		(layer "F.Cu")
		(net "USB_P1_DP")
	)
	(segment
		(start 88.416892 -157.186122)
		(end 89.04351 -157.186122)
		(width 0.14605)
		(layer "F.Cu")
		(net "USB_P1_DP")
	)
	(segment
		(start 86.699344 -158.90367)
		(end 88.416892 -157.186122)
		(width 0.14605)
		(layer "F.Cu")
		(net "USB_P1_DP")
	)
	(segment
		(start 86.3854 -160.379918)
		(end 86.699344 -160.065974)
		(width 0.14605)
		(layer "F.Cu")
		(net "USB_P1_DP")
	)
	(segment
		(start 99.175824 -20.242022)
		(end 98.834956 -19.901154)
		(width 0.14605)
		(layer "F.Cu")
		(net "USB_P1_DP")
	)
	(segment
		(start 99.193858 -19.022822)
		(end 99.193858 -18.74266)
		(width 0.14605)
		(layer "F.Cu")
		(net "USB_P1_DP")
	)
	(segment
		(start 89.124028 -157.105604)
		(end 89.881456 -157.105604)
		(width 0.14605)
		(layer "F.Cu")
		(net "USB_P1_DP")
	)
	(segment
		(start 89.04351 -157.186122)
		(end 89.124028 -157.105604)
		(width 0.14605)
		(layer "F.Cu")
		(net "USB_P1_DP")
	)
	(via
		(at 86.3854 -160.379918)
		(size 0.508)
		(drill 0.254)
		(layers "F.Cu" "B.Cu")
		(net "USB_P1_DP")
	)
	(via
		(at 99.175824 -20.242022)
		(size 0.508)
		(drill 0.254)
		(layers "F.Cu" "B.Cu")
		(net "USB_P1_DP")
	)
	(segment
		(start 89.123012 -61.382402)
		(end 90.762582 -63.021972)
		(width 0.1397)
		(layer "In2.Cu")
		(net "USB_P1_DP")
	)
	(segment
		(start 87.58555 -157.41396)
		(end 86.69528 -158.30423)
		(width 0.1397)
		(layer "In2.Cu")
		(net "USB_P1_DP")
	)
	(segment
		(start 98.45167 -18.924016)
		(end 96.883728 -18.924016)
		(width 0.1397)
		(layer "In2.Cu")
		(net "USB_P1_DP")
	)
	(segment
		(start 86.3092 -134.264146)
		(end 87.323676 -135.278622)
		(width 0.1397)
		(layer "In2.Cu")
		(net "USB_P1_DP")
	)
	(segment
		(start 98.895408 -19.367754)
		(end 98.45167 -18.924016)
		(width 0.1397)
		(layer "In2.Cu")
		(net "USB_P1_DP")
	)
	(segment
		(start 87.323676 -138.707876)
		(end 85.97646 -140.055092)
		(width 0.1397)
		(layer "In2.Cu")
		(net "USB_P1_DP")
	)
	(segment
		(start 85.658198 -129.000504)
		(end 85.658198 -132.64515)
		(width 0.1397)
		(layer "In2.Cu")
		(net "USB_P1_DP")
	)
	(segment
		(start 94.309438 -23.712424)
		(end 90.65768 -27.364182)
		(width 0.1397)
		(layer "In2.Cu")
		(net "USB_P1_DP")
	)
	(segment
		(start 85.48497 -146.27733)
		(end 86.315804 -147.108164)
		(width 0.1397)
		(layer "In2.Cu")
		(net "USB_P1_DP")
	)
	(segment
		(start 98.895408 -19.961606)
		(end 98.895408 -19.367754)
		(width 0.1397)
		(layer "In2.Cu")
		(net "USB_P1_DP")
	)
	(segment
		(start 90.762582 -110.703868)
		(end 87.05215 -114.4143)
		(width 0.1397)
		(layer "In2.Cu")
		(net "USB_P1_DP")
	)
	(segment
		(start 86.02345 -124.404628)
		(end 86.02345 -128.635252)
		(width 0.1397)
		(layer "In2.Cu")
		(net "USB_P1_DP")
	)
	(segment
		(start 86.69528 -160.070038)
		(end 86.3854 -160.379918)
		(width 0.1397)
		(layer "In2.Cu")
		(net "USB_P1_DP")
	)
	(segment
		(start 86.02345 -128.635252)
		(end 85.658198 -129.000504)
		(width 0.1397)
		(layer "In2.Cu")
		(net "USB_P1_DP")
	)
	(segment
		(start 86.3092 -133.296152)
		(end 86.3092 -134.264146)
		(width 0.1397)
		(layer "In2.Cu")
		(net "USB_P1_DP")
	)
	(segment
		(start 94.309438 -21.498306)
		(end 94.309438 -23.712424)
		(width 0.1397)
		(layer "In2.Cu")
		(net "USB_P1_DP")
	)
	(segment
		(start 86.315804 -147.108164)
		(end 86.315804 -150.099014)
		(width 0.1397)
		(layer "In2.Cu")
		(net "USB_P1_DP")
	)
	(segment
		(start 89.123012 -50.719482)
		(end 89.123012 -61.382402)
		(width 0.1397)
		(layer "In2.Cu")
		(net "USB_P1_DP")
	)
	(segment
		(start 90.65768 -27.364182)
		(end 90.65768 -43.706034)
		(width 0.1397)
		(layer "In2.Cu")
		(net "USB_P1_DP")
	)
	(segment
		(start 87.58555 -151.36876)
		(end 87.58555 -157.41396)
		(width 0.1397)
		(layer "In2.Cu")
		(net "USB_P1_DP")
	)
	(segment
		(start 86.315804 -150.099014)
		(end 87.58555 -151.36876)
		(width 0.1397)
		(layer "In2.Cu")
		(net "USB_P1_DP")
	)
	(segment
		(start 89.775538 -50.066956)
		(end 89.123012 -50.719482)
		(width 0.1397)
		(layer "In2.Cu")
		(net "USB_P1_DP")
	)
	(segment
		(start 96.883728 -18.924016)
		(end 94.309438 -21.498306)
		(width 0.1397)
		(layer "In2.Cu")
		(net "USB_P1_DP")
	)
	(segment
		(start 86.69528 -158.30423)
		(end 86.69528 -160.070038)
		(width 0.1397)
		(layer "In2.Cu")
		(net "USB_P1_DP")
	)
	(segment
		(start 85.97646 -143.195802)
		(end 85.48497 -143.687292)
		(width 0.1397)
		(layer "In2.Cu")
		(net "USB_P1_DP")
	)
	(segment
		(start 85.97646 -140.055092)
		(end 85.97646 -143.195802)
		(width 0.1397)
		(layer "In2.Cu")
		(net "USB_P1_DP")
	)
	(segment
		(start 85.48497 -143.687292)
		(end 85.48497 -146.27733)
		(width 0.1397)
		(layer "In2.Cu")
		(net "USB_P1_DP")
	)
	(segment
		(start 87.05215 -114.4143)
		(end 87.05215 -123.375928)
		(width 0.1397)
		(layer "In2.Cu")
		(net "USB_P1_DP")
	)
	(segment
		(start 99.175824 -20.242022)
		(end 98.895408 -19.961606)
		(width 0.1397)
		(layer "In2.Cu")
		(net "USB_P1_DP")
	)
	(segment
		(start 89.775538 -44.588176)
		(end 89.775538 -50.066956)
		(width 0.1397)
		(layer "In2.Cu")
		(net "USB_P1_DP")
	)
	(segment
		(start 90.65768 -43.706034)
		(end 89.775538 -44.588176)
		(width 0.1397)
		(layer "In2.Cu")
		(net "USB_P1_DP")
	)
	(segment
		(start 90.762582 -63.021972)
		(end 90.762582 -110.703868)
		(width 0.1397)
		(layer "In2.Cu")
		(net "USB_P1_DP")
	)
	(segment
		(start 87.323676 -135.278622)
		(end 87.323676 -138.707876)
		(width 0.1397)
		(layer "In2.Cu")
		(net "USB_P1_DP")
	)
	(segment
		(start 85.658198 -132.64515)
		(end 86.3092 -133.296152)
		(width 0.1397)
		(layer "In2.Cu")
		(net "USB_P1_DP")
	)
	(segment
		(start 87.05215 -123.375928)
		(end 86.02345 -124.404628)
		(width 0.1397)
		(layer "In2.Cu")
		(net "USB_P1_DP")
	)
	(segment
		(start 88.545924 -157.497272)
		(end 89.031826 -157.497272)
		(width 0.14605)
		(layer "F.Cu")
		(net "USB_P1_DN")
	)
	(segment
		(start 98.523806 -19.306286)
		(end 98.228658 -19.011138)
		(width 0.14605)
		(layer "F.Cu")
		(net "USB_P1_DN")
	)
	(segment
		(start 89.14003 -157.605476)
		(end 89.792556 -157.605476)
		(width 0.14605)
		(layer "F.Cu")
		(net "USB_P1_DN")
	)
	(segment
		(start 87.324438 -160.379918)
		(end 87.010494 -160.065974)
		(width 0.14605)
		(layer "F.Cu")
		(net "USB_P1_DN")
	)
	(segment
		(start 87.010494 -159.032702)
		(end 88.545924 -157.497272)
		(width 0.14605)
		(layer "F.Cu")
		(net "USB_P1_DN")
	)
	(segment
		(start 87.010494 -160.065974)
		(end 87.010494 -159.032702)
		(width 0.14605)
		(layer "F.Cu")
		(net "USB_P1_DN")
	)
	(segment
		(start 98.523806 -19.955002)
		(end 98.523806 -19.306286)
		(width 0.14605)
		(layer "F.Cu")
		(net "USB_P1_DN")
	)
	(segment
		(start 98.236786 -20.242022)
		(end 98.523806 -19.955002)
		(width 0.14605)
		(layer "F.Cu")
		(net "USB_P1_DN")
	)
	(segment
		(start 98.228658 -19.011138)
		(end 98.228658 -18.74266)
		(width 0.14605)
		(layer "F.Cu")
		(net "USB_P1_DN")
	)
	(segment
		(start 89.031826 -157.497272)
		(end 89.14003 -157.605476)
		(width 0.14605)
		(layer "F.Cu")
		(net "USB_P1_DN")
	)
	(via
		(at 98.236786 -20.242022)
		(size 0.508)
		(drill 0.254)
		(layers "F.Cu" "B.Cu")
		(net "USB_P1_DN")
	)
	(via
		(at 87.324438 -160.379918)
		(size 0.508)
		(drill 0.254)
		(layers "F.Cu" "B.Cu")
		(net "USB_P1_DN")
	)
	(segment
		(start 94.639638 -21.635212)
		(end 94.639638 -23.84933)
		(width 0.1397)
		(layer "In2.Cu")
		(net "USB_P1_DN")
	)
	(segment
		(start 86.6394 -134.12724)
		(end 87.653876 -135.141716)
		(width 0.1397)
		(layer "In2.Cu")
		(net "USB_P1_DN")
	)
	(segment
		(start 90.98788 -40.98544)
		(end 91.16568 -41.16324)
		(width 0.1397)
		(layer "In2.Cu")
		(net "USB_P1_DN")
	)
	(segment
		(start 85.81517 -146.140424)
		(end 86.646004 -146.971258)
		(width 0.1397)
		(layer "In2.Cu")
		(net "USB_P1_DN")
	)
	(segment
		(start 94.936056 -21.338794)
		(end 94.639638 -21.635212)
		(width 0.1397)
		(layer "In2.Cu")
		(net "USB_P1_DN")
	)
	(segment
		(start 86.30666 -143.332708)
		(end 85.81517 -143.824198)
		(width 0.1397)
		(layer "In2.Cu")
		(net "USB_P1_DN")
	)
	(segment
		(start 87.91575 -152.425654)
		(end 87.91575 -152.844754)
		(width 0.1397)
		(layer "In2.Cu")
		(net "USB_P1_DN")
	)
	(segment
		(start 90.105738 -44.725082)
		(end 90.105738 -50.203862)
		(width 0.1397)
		(layer "In2.Cu")
		(net "USB_P1_DN")
	)
	(segment
		(start 88.09355 -153.022554)
		(end 88.09355 -153.441654)
		(width 0.1397)
		(layer "In2.Cu")
		(net "USB_P1_DN")
	)
	(segment
		(start 91.16568 -38.77564)
		(end 91.16568 -39.19474)
		(width 0.1397)
		(layer "In2.Cu")
		(net "USB_P1_DN")
	)
	(segment
		(start 86.6394 -133.159246)
		(end 86.6394 -134.12724)
		(width 0.1397)
		(layer "In2.Cu")
		(net "USB_P1_DN")
	)
	(segment
		(start 96.3422 -19.93265)
		(end 96.3422 -20.198588)
		(width 0.1397)
		(layer "In2.Cu")
		(net "USB_P1_DN")
	)
	(segment
		(start 87.91575 -154.038554)
		(end 88.09355 -154.216354)
		(width 0.1397)
		(layer "In2.Cu")
		(net "USB_P1_DN")
	)
	(segment
		(start 89.453212 -56.726074)
		(end 89.453212 -61.245496)
		(width 0.1397)
		(layer "In2.Cu")
		(net "USB_P1_DN")
	)
	(segment
		(start 85.988398 -132.508244)
		(end 86.6394 -133.159246)
		(width 0.1397)
		(layer "In2.Cu")
		(net "USB_P1_DN")
	)
	(segment
		(start 89.631012 -54.160674)
		(end 89.453212 -54.338474)
		(width 0.1397)
		(layer "In2.Cu")
		(net "USB_P1_DN")
	)
	(segment
		(start 90.105738 -50.203862)
		(end 89.453212 -50.856388)
		(width 0.1397)
		(layer "In2.Cu")
		(net "USB_P1_DN")
	)
	(segment
		(start 91.16568 -41.16324)
		(end 91.16568 -41.58234)
		(width 0.1397)
		(layer "In2.Cu")
		(net "USB_P1_DN")
	)
	(segment
		(start 88.09355 -154.635454)
		(end 87.91575 -154.813254)
		(width 0.1397)
		(layer "In2.Cu")
		(net "USB_P1_DN")
	)
	(segment
		(start 87.91575 -152.844754)
		(end 88.09355 -153.022554)
		(width 0.1397)
		(layer "In2.Cu")
		(net "USB_P1_DN")
	)
	(segment
		(start 95.48368 -21.04263)
		(end 95.187516 -21.338794)
		(width 0.1397)
		(layer "In2.Cu")
		(net "USB_P1_DN")
	)
	(segment
		(start 85.988398 -129.13741)
		(end 85.988398 -132.508244)
		(width 0.1397)
		(layer "In2.Cu")
		(net "USB_P1_DN")
	)
	(segment
		(start 86.35365 -128.772158)
		(end 85.988398 -129.13741)
		(width 0.1397)
		(layer "In2.Cu")
		(net "USB_P1_DN")
	)
	(segment
		(start 95.780098 -20.494752)
		(end 95.48368 -20.79117)
		(width 0.1397)
		(layer "In2.Cu")
		(net "USB_P1_DN")
	)
	(segment
		(start 87.91575 -157.550866)
		(end 87.02548 -158.441136)
		(width 0.1397)
		(layer "In2.Cu")
		(net "USB_P1_DN")
	)
	(segment
		(start 85.81517 -143.824198)
		(end 85.81517 -146.140424)
		(width 0.1397)
		(layer "In2.Cu")
		(net "USB_P1_DN")
	)
	(segment
		(start 90.98788 -27.501088)
		(end 90.98788 -37.40404)
		(width 0.1397)
		(layer "In2.Cu")
		(net "USB_P1_DN")
	)
	(segment
		(start 89.631012 -56.548274)
		(end 89.453212 -56.726074)
		(width 0.1397)
		(layer "In2.Cu")
		(net "USB_P1_DN")
	)
	(segment
		(start 89.453212 -54.338474)
		(end 89.453212 -54.757574)
		(width 0.1397)
		(layer "In2.Cu")
		(net "USB_P1_DN")
	)
	(segment
		(start 88.09355 -152.247854)
		(end 87.91575 -152.425654)
		(width 0.1397)
		(layer "In2.Cu")
		(net "USB_P1_DN")
	)
	(segment
		(start 89.453212 -50.856388)
		(end 89.453212 -53.563774)
		(width 0.1397)
		(layer "In2.Cu")
		(net "USB_P1_DN")
	)
	(segment
		(start 86.30666 -140.191998)
		(end 86.30666 -143.332708)
		(width 0.1397)
		(layer "In2.Cu")
		(net "USB_P1_DN")
	)
	(segment
		(start 87.38235 -123.512834)
		(end 86.35365 -124.541534)
		(width 0.1397)
		(layer "In2.Cu")
		(net "USB_P1_DN")
	)
	(segment
		(start 90.98788 -37.40404)
		(end 91.16568 -37.58184)
		(width 0.1397)
		(layer "In2.Cu")
		(net "USB_P1_DN")
	)
	(segment
		(start 90.98788 -38.17874)
		(end 90.98788 -38.59784)
		(width 0.1397)
		(layer "In2.Cu")
		(net "USB_P1_DN")
	)
	(segment
		(start 86.35365 -124.541534)
		(end 86.35365 -128.772158)
		(width 0.1397)
		(layer "In2.Cu")
		(net "USB_P1_DN")
	)
	(segment
		(start 91.16568 -39.96944)
		(end 91.16568 -40.38854)
		(width 0.1397)
		(layer "In2.Cu")
		(net "USB_P1_DN")
	)
	(segment
		(start 90.98788 -39.37254)
		(end 90.98788 -39.79164)
		(width 0.1397)
		(layer "In2.Cu")
		(net "USB_P1_DN")
	)
	(segment
		(start 89.453212 -61.245496)
		(end 91.092782 -62.885066)
		(width 0.1397)
		(layer "In2.Cu")
		(net "USB_P1_DN")
	)
	(segment
		(start 89.631012 -54.935374)
		(end 89.631012 -55.354474)
		(width 0.1397)
		(layer "In2.Cu")
		(net "USB_P1_DN")
	)
	(segment
		(start 87.02548 -158.441136)
		(end 87.02548 -160.08096)
		(width 0.1397)
		(layer "In2.Cu")
		(net "USB_P1_DN")
	)
	(segment
		(start 86.646004 -146.971258)
		(end 86.646004 -149.962108)
		(width 0.1397)
		(layer "In2.Cu")
		(net "USB_P1_DN")
	)
	(segment
		(start 90.98788 -38.59784)
		(end 91.16568 -38.77564)
		(width 0.1397)
		(layer "In2.Cu")
		(net "USB_P1_DN")
	)
	(segment
		(start 91.16568 -37.58184)
		(end 91.16568 -38.00094)
		(width 0.1397)
		(layer "In2.Cu")
		(net "USB_P1_DN")
	)
	(segment
		(start 89.631012 -53.741574)
		(end 89.631012 -54.160674)
		(width 0.1397)
		(layer "In2.Cu")
		(net "USB_P1_DN")
	)
	(segment
		(start 87.91575 -151.231854)
		(end 87.91575 -151.650954)
		(width 0.1397)
		(layer "In2.Cu")
		(net "USB_P1_DN")
	)
	(segment
		(start 87.653876 -138.844782)
		(end 86.30666 -140.191998)
		(width 0.1397)
		(layer "In2.Cu")
		(net "USB_P1_DN")
	)
	(segment
		(start 88.09355 -153.441654)
		(end 87.91575 -153.619454)
		(width 0.1397)
		(layer "In2.Cu")
		(net "USB_P1_DN")
	)
	(segment
		(start 96.3422 -20.198588)
		(end 96.045782 -20.494752)
		(width 0.1397)
		(layer "In2.Cu")
		(net "USB_P1_DN")
	)
	(segment
		(start 98.565208 -19.9136)
		(end 98.565208 -19.50466)
		(width 0.1397)
		(layer "In2.Cu")
		(net "USB_P1_DN")
	)
	(segment
		(start 89.631012 -55.354474)
		(end 89.453212 -55.532274)
		(width 0.1397)
		(layer "In2.Cu")
		(net "USB_P1_DN")
	)
	(segment
		(start 94.639638 -23.84933)
		(end 90.98788 -27.501088)
		(width 0.1397)
		(layer "In2.Cu")
		(net "USB_P1_DN")
	)
	(segment
		(start 87.91575 -153.619454)
		(end 87.91575 -154.038554)
		(width 0.1397)
		(layer "In2.Cu")
		(net "USB_P1_DN")
	)
	(segment
		(start 88.09355 -154.216354)
		(end 88.09355 -154.635454)
		(width 0.1397)
		(layer "In2.Cu")
		(net "USB_P1_DN")
	)
	(segment
		(start 86.646004 -149.962108)
		(end 87.91575 -151.231854)
		(width 0.1397)
		(layer "In2.Cu")
		(net "USB_P1_DN")
	)
	(segment
		(start 95.48368 -20.79117)
		(end 95.48368 -21.04263)
		(width 0.1397)
		(layer "In2.Cu")
		(net "USB_P1_DN")
	)
	(segment
		(start 98.236786 -20.242022)
		(end 98.565208 -19.9136)
		(width 0.1397)
		(layer "In2.Cu")
		(net "USB_P1_DN")
	)
	(segment
		(start 91.16568 -38.00094)
		(end 90.98788 -38.17874)
		(width 0.1397)
		(layer "In2.Cu")
		(net "USB_P1_DN")
	)
	(segment
		(start 90.98788 -41.76014)
		(end 90.98788 -43.84294)
		(width 0.1397)
		(layer "In2.Cu")
		(net "USB_P1_DN")
	)
	(segment
		(start 95.187516 -21.338794)
		(end 94.936056 -21.338794)
		(width 0.1397)
		(layer "In2.Cu")
		(net "USB_P1_DN")
	)
	(segment
		(start 90.98788 -40.56634)
		(end 90.98788 -40.98544)
		(width 0.1397)
		(layer "In2.Cu")
		(net "USB_P1_DN")
	)
	(segment
		(start 98.314764 -19.254216)
		(end 97.020634 -19.254216)
		(width 0.1397)
		(layer "In2.Cu")
		(net "USB_P1_DN")
	)
	(segment
		(start 87.02548 -160.08096)
		(end 87.324438 -160.379918)
		(width 0.1397)
		(layer "In2.Cu")
		(net "USB_P1_DN")
	)
	(segment
		(start 89.453212 -54.757574)
		(end 89.631012 -54.935374)
		(width 0.1397)
		(layer "In2.Cu")
		(net "USB_P1_DN")
	)
	(segment
		(start 96.045782 -20.494752)
		(end 95.780098 -20.494752)
		(width 0.1397)
		(layer "In2.Cu")
		(net "USB_P1_DN")
	)
	(segment
		(start 87.91575 -151.650954)
		(end 88.09355 -151.828754)
		(width 0.1397)
		(layer "In2.Cu")
		(net "USB_P1_DN")
	)
	(segment
		(start 91.16568 -41.58234)
		(end 90.98788 -41.76014)
		(width 0.1397)
		(layer "In2.Cu")
		(net "USB_P1_DN")
	)
	(segment
		(start 89.453212 -55.532274)
		(end 89.453212 -55.951374)
		(width 0.1397)
		(layer "In2.Cu")
		(net "USB_P1_DN")
	)
	(segment
		(start 88.09355 -151.828754)
		(end 88.09355 -152.247854)
		(width 0.1397)
		(layer "In2.Cu")
		(net "USB_P1_DN")
	)
	(segment
		(start 89.453212 -53.563774)
		(end 89.631012 -53.741574)
		(width 0.1397)
		(layer "In2.Cu")
		(net "USB_P1_DN")
	)
	(segment
		(start 87.653876 -135.141716)
		(end 87.653876 -138.844782)
		(width 0.1397)
		(layer "In2.Cu")
		(net "USB_P1_DN")
	)
	(segment
		(start 97.020634 -19.254216)
		(end 96.3422 -19.93265)
		(width 0.1397)
		(layer "In2.Cu")
		(net "USB_P1_DN")
	)
	(segment
		(start 91.16568 -39.19474)
		(end 90.98788 -39.37254)
		(width 0.1397)
		(layer "In2.Cu")
		(net "USB_P1_DN")
	)
	(segment
		(start 90.98788 -39.79164)
		(end 91.16568 -39.96944)
		(width 0.1397)
		(layer "In2.Cu")
		(net "USB_P1_DN")
	)
	(segment
		(start 91.092782 -110.840774)
		(end 87.38235 -114.551206)
		(width 0.1397)
		(layer "In2.Cu")
		(net "USB_P1_DN")
	)
	(segment
		(start 89.631012 -56.129174)
		(end 89.631012 -56.548274)
		(width 0.1397)
		(layer "In2.Cu")
		(net "USB_P1_DN")
	)
	(segment
		(start 98.565208 -19.50466)
		(end 98.314764 -19.254216)
		(width 0.1397)
		(layer "In2.Cu")
		(net "USB_P1_DN")
	)
	(segment
		(start 91.16568 -40.38854)
		(end 90.98788 -40.56634)
		(width 0.1397)
		(layer "In2.Cu")
		(net "USB_P1_DN")
	)
	(segment
		(start 90.98788 -43.84294)
		(end 90.105738 -44.725082)
		(width 0.1397)
		(layer "In2.Cu")
		(net "USB_P1_DN")
	)
	(segment
		(start 87.38235 -114.551206)
		(end 87.38235 -123.512834)
		(width 0.1397)
		(layer "In2.Cu")
		(net "USB_P1_DN")
	)
	(segment
		(start 89.453212 -55.951374)
		(end 89.631012 -56.129174)
		(width 0.1397)
		(layer "In2.Cu")
		(net "USB_P1_DN")
	)
	(segment
		(start 87.91575 -154.813254)
		(end 87.91575 -157.550866)
		(width 0.1397)
		(layer "In2.Cu")
		(net "USB_P1_DN")
	)
	(segment
		(start 91.092782 -62.885066)
		(end 91.092782 -110.840774)
		(width 0.1397)
		(layer "In2.Cu")
		(net "USB_P1_DN")
	)
	(segment
		(start 91.350592 -149.634956)
		(end 91.64828 -149.932644)
		(width 0.127)
		(layer "F.Cu")
		(net "USB_OCS_N1")
	)
	(segment
		(start 86.6394 -99.1235)
		(end 87.561928 -100.046028)
		(width 0.127)
		(layer "F.Cu")
		(net "USB_OCS_N1")
	)
	(segment
		(start 86.221824 -71.4121)
		(end 86.6394 -71.829676)
		(width 0.127)
		(layer "F.Cu")
		(net "USB_OCS_N1")
	)
	(segment
		(start 84.800186 -69.701156)
		(end 86.221824 -71.122794)
		(width 0.127)
		(layer "F.Cu")
		(net "USB_OCS_N1")
	)
	(segment
		(start 90.59672 -150.03272)
		(end 90.59672 -149.634956)
		(width 0.127)
		(layer "F.Cu")
		(net "USB_OCS_N1")
	)
	(segment
		(start 92.459556 -150.814024)
		(end 91.64828 -150.002748)
		(width 0.127)
		(layer "F.Cu")
		(net "USB_OCS_N1")
	)
	(segment
		(start 91.6432 -150.7236)
		(end 91.2876 -150.7236)
		(width 0.127)
		(layer "F.Cu")
		(net "USB_OCS_N1")
	)
	(segment
		(start 86.040722 -31.215076)
		(end 90.196924 -31.215076)
		(width 0.127)
		(layer "F.Cu")
		(net "USB_OCS_N1")
	)
	(segment
		(start 83.543902 -69.701156)
		(end 84.800186 -69.701156)
		(width 0.127)
		(layer "F.Cu")
		(net "USB_OCS_N1")
	)
	(segment
		(start 90.196924 -31.215076)
		(end 90.82024 -30.59176)
		(width 0.127)
		(layer "F.Cu")
		(net "USB_OCS_N1")
	)
	(segment
		(start 91.2876 -150.7236)
		(end 90.59672 -150.03272)
		(width 0.127)
		(layer "F.Cu")
		(net "USB_OCS_N1")
	)
	(segment
		(start 92.25153 -152.73528)
		(end 92.25153 -151.33193)
		(width 0.127)
		(layer "F.Cu")
		(net "USB_OCS_N1")
	)
	(segment
		(start 86.6394 -71.829676)
		(end 86.6394 -99.1235)
		(width 0.127)
		(layer "F.Cu")
		(net "USB_OCS_N1")
	)
	(segment
		(start 90.59672 -149.634956)
		(end 91.350592 -149.634956)
		(width 0.127)
		(layer "F.Cu")
		(net "USB_OCS_N1")
	)
	(segment
		(start 92.25153 -151.33193)
		(end 91.6432 -150.7236)
		(width 0.127)
		(layer "F.Cu")
		(net "USB_OCS_N1")
	)
	(segment
		(start 90.82024 -30.59176)
		(end 91.567 -30.59176)
		(width 0.127)
		(layer "F.Cu")
		(net "USB_OCS_N1")
	)
	(segment
		(start 86.221824 -71.122794)
		(end 86.221824 -71.4121)
		(width 0.127)
		(layer "F.Cu")
		(net "USB_OCS_N1")
	)
	(segment
		(start 53.699918 -142.999968)
		(end 54.099968 -142.599918)
		(width 0.127)
		(layer "F.Cu")
		(net "USB_OCS_N1")
	)
	(segment
		(start 91.64828 -150.002748)
		(end 91.64828 -149.932644)
		(width 0.127)
		(layer "F.Cu")
		(net "USB_OCS_N1")
	)
	(segment
		(start 92.459556 -150.874984)
		(end 92.459556 -150.814024)
		(width 0.127)
		(layer "F.Cu")
		(net "USB_OCS_N1")
	)
	(via
		(at 86.040722 -31.215076)
		(size 0.508)
		(drill 0.254)
		(layers "F.Cu" "B.Cu")
		(net "USB_OCS_N1")
	)
	(via
		(at 92.459556 -150.874984)
		(size 0.508)
		(drill 0.254)
		(layers "F.Cu" "B.Cu")
		(net "USB_OCS_N1")
	)
	(via
		(at 54.099968 -142.599918)
		(size 0.4572)
		(drill 0.2032)
		(layers "F.Cu" "B.Cu")
		(net "USB_OCS_N1")
	)
	(via
		(at 92.329 -118.0338)
		(size 0.508)
		(drill 0.254)
		(layers "F.Cu" "B.Cu")
		(net "USB_OCS_N1")
	)
	(via
		(at 61.803788 -151.767286)
		(size 0.508)
		(drill 0.254)
		(layers "F.Cu" "B.Cu")
		(net "USB_OCS_N1")
	)
	(via
		(at 87.561928 -100.046028)
		(size 0.508)
		(drill 0.254)
		(layers "F.Cu" "B.Cu")
		(net "USB_OCS_N1")
	)
	(via
		(at 83.543902 -69.701156)
		(size 0.508)
		(drill 0.254)
		(layers "F.Cu" "B.Cu")
		(net "USB_OCS_N1")
	)
	(via
		(at 91.5162 -149.95906)
		(size 0.6096)
		(drill 0.3048)
		(layers "F.Cu" "B.Cu")
		(net "USB_OCS_N1")
	)
	(via
		(at 87.0458 -110.5408)
		(size 0.508)
		(drill 0.254)
		(layers "F.Cu" "B.Cu")
		(net "USB_OCS_N1")
	)
	(segment
		(start 87.0458 -109.320584)
		(end 87.0458 -110.5408)
		(width 0.127)
		(layer "B.Cu")
		(net "USB_OCS_N1")
	)
	(segment
		(start 92.459556 -150.874984)
		(end 92.44965 -150.865078)
		(width 0.127)
		(layer "B.Cu")
		(net "USB_OCS_N1")
	)
	(segment
		(start 87.561928 -108.804456)
		(end 87.0458 -109.320584)
		(width 0.127)
		(layer "B.Cu")
		(net "USB_OCS_N1")
	)
	(segment
		(start 92.44965 -150.865078)
		(end 92.44965 -150.804118)
		(width 0.127)
		(layer "B.Cu")
		(net "USB_OCS_N1")
	)
	(segment
		(start 92.44965 -150.804118)
		(end 91.604592 -149.95906)
		(width 0.127)
		(layer "B.Cu")
		(net "USB_OCS_N1")
	)
	(segment
		(start 91.604592 -149.95906)
		(end 91.5162 -149.95906)
		(width 0.127)
		(layer "B.Cu")
		(net "USB_OCS_N1")
	)
	(segment
		(start 90.54592 -149.95906)
		(end 91.5162 -149.95906)
		(width 0.127)
		(layer "B.Cu")
		(net "USB_OCS_N1")
	)
	(segment
		(start 87.561928 -100.046028)
		(end 87.561928 -108.804456)
		(width 0.127)
		(layer "B.Cu")
		(net "USB_OCS_N1")
	)
	(segment
		(start 92.663518 -118.368318)
		(end 92.663518 -119.28983)
		(width 0.127)
		(layer "In2.Cu")
		(net "USB_OCS_N1")
	)
	(segment
		(start 93.111574 -135.721852)
		(end 92.708222 -136.125204)
		(width 0.127)
		(layer "In2.Cu")
		(net "USB_OCS_N1")
	)
	(segment
		(start 57.76341 -145.706084)
		(end 57.76341 -151.030432)
		(width 0.127)
		(layer "In2.Cu")
		(net "USB_OCS_N1")
	)
	(segment
		(start 92.95384 -119.580152)
		(end 92.95384 -119.75084)
		(width 0.127)
		(layer "In2.Cu")
		(net "USB_OCS_N1")
	)
	(segment
		(start 92.329 -118.0338)
		(end 92.663518 -118.368318)
		(width 0.127)
		(layer "In2.Cu")
		(net "USB_OCS_N1")
	)
	(segment
		(start 93.3831 -126.291086)
		(end 93.3831 -128.102106)
		(width 0.127)
		(layer "In2.Cu")
		(net "USB_OCS_N1")
	)
	(segment
		(start 92.150946 -150.874984)
		(end 92.459556 -150.874984)
		(width 0.127)
		(layer "In2.Cu")
		(net "USB_OCS_N1")
	)
	(segment
		(start 91.294966 -150.019004)
		(end 92.150946 -150.874984)
		(width 0.127)
		(layer "In2.Cu")
		(net "USB_OCS_N1")
	)
	(segment
		(start 54.099968 -142.599918)
		(end 54.506876 -143.006826)
		(width 0.127)
		(layer "In2.Cu")
		(net "USB_OCS_N1")
	)
	(segment
		(start 92.7481 -128.737106)
		(end 92.7481 -132.666232)
		(width 0.127)
		(layer "In2.Cu")
		(net "USB_OCS_N1")
	)
	(segment
		(start 92.955872 -119.752872)
		(end 92.955872 -122.240548)
		(width 0.127)
		(layer "In2.Cu")
		(net "USB_OCS_N1")
	)
	(segment
		(start 59.2328 -152.499822)
		(end 61.071252 -152.499822)
		(width 0.127)
		(layer "In2.Cu")
		(net "USB_OCS_N1")
	)
	(segment
		(start 61.071252 -152.499822)
		(end 61.803788 -151.767286)
		(width 0.127)
		(layer "In2.Cu")
		(net "USB_OCS_N1")
	)
	(segment
		(start 92.708222 -141.037564)
		(end 91.89466 -141.851126)
		(width 0.127)
		(layer "In2.Cu")
		(net "USB_OCS_N1")
	)
	(segment
		(start 92.663518 -119.28983)
		(end 92.95384 -119.580152)
		(width 0.127)
		(layer "In2.Cu")
		(net "USB_OCS_N1")
	)
	(segment
		(start 92.645992 -122.550428)
		(end 92.645992 -125.553978)
		(width 0.127)
		(layer "In2.Cu")
		(net "USB_OCS_N1")
	)
	(segment
		(start 92.708222 -136.125204)
		(end 92.708222 -141.037564)
		(width 0.127)
		(layer "In2.Cu")
		(net "USB_OCS_N1")
	)
	(segment
		(start 91.89466 -144.262856)
		(end 91.294966 -144.86255)
		(width 0.127)
		(layer "In2.Cu")
		(net "USB_OCS_N1")
	)
	(segment
		(start 91.294966 -144.86255)
		(end 91.294966 -150.019004)
		(width 0.127)
		(layer "In2.Cu")
		(net "USB_OCS_N1")
	)
	(segment
		(start 92.95384 -119.75084)
		(end 92.955872 -119.752872)
		(width 0.127)
		(layer "In2.Cu")
		(net "USB_OCS_N1")
	)
	(segment
		(start 91.89466 -141.851126)
		(end 91.89466 -144.262856)
		(width 0.127)
		(layer "In2.Cu")
		(net "USB_OCS_N1")
	)
	(segment
		(start 54.506876 -143.006826)
		(end 55.064152 -143.006826)
		(width 0.127)
		(layer "In2.Cu")
		(net "USB_OCS_N1")
	)
	(segment
		(start 55.064152 -143.006826)
		(end 57.76341 -145.706084)
		(width 0.127)
		(layer "In2.Cu")
		(net "USB_OCS_N1")
	)
	(segment
		(start 92.7481 -132.666232)
		(end 93.111574 -133.029706)
		(width 0.127)
		(layer "In2.Cu")
		(net "USB_OCS_N1")
	)
	(segment
		(start 92.645992 -125.553978)
		(end 93.3831 -126.291086)
		(width 0.127)
		(layer "In2.Cu")
		(net "USB_OCS_N1")
	)
	(segment
		(start 57.76341 -151.030432)
		(end 59.2328 -152.499822)
		(width 0.127)
		(layer "In2.Cu")
		(net "USB_OCS_N1")
	)
	(segment
		(start 93.3831 -128.102106)
		(end 92.7481 -128.737106)
		(width 0.127)
		(layer "In2.Cu")
		(net "USB_OCS_N1")
	)
	(segment
		(start 93.111574 -133.029706)
		(end 93.111574 -135.721852)
		(width 0.127)
		(layer "In2.Cu")
		(net "USB_OCS_N1")
	)
	(segment
		(start 92.955872 -122.240548)
		(end 92.645992 -122.550428)
		(width 0.127)
		(layer "In2.Cu")
		(net "USB_OCS_N1")
	)
	(segment
		(start 92.231972 -151.102568)
		(end 92.459556 -150.874984)
		(width 0.127)
		(layer "In5.Cu")
		(net "USB_OCS_N1")
	)
	(segment
		(start 84.165948 -151.481536)
		(end 84.326476 -151.321008)
		(width 0.127)
		(layer "In5.Cu")
		(net "USB_OCS_N1")
	)
	(segment
		(start 65.673224 -151.435054)
		(end 69.99224 -151.435054)
		(width 0.127)
		(layer "In5.Cu")
		(net "USB_OCS_N1")
	)
	(segment
		(start 85.20684 -41.0845)
		(end 83.492848 -42.798492)
		(width 0.127)
		(layer "In5.Cu")
		(net "USB_OCS_N1")
	)
	(segment
		(start 84.326476 -151.321008)
		(end 88.58758 -151.321008)
		(width 0.127)
		(layer "In5.Cu")
		(net "USB_OCS_N1")
	)
	(segment
		(start 88.58758 -151.321008)
		(end 88.80602 -151.102568)
		(width 0.127)
		(layer "In5.Cu")
		(net "USB_OCS_N1")
	)
	(segment
		(start 77.952346 -154.034236)
		(end 77.9526 -154.03449)
		(width 0.127)
		(layer "In5.Cu")
		(net "USB_OCS_N1")
	)
	(segment
		(start 83.492848 -60.300108)
		(end 84.184236 -60.991496)
		(width 0.127)
		(layer "In5.Cu")
		(net "USB_OCS_N1")
	)
	(segment
		(start 89.5096 -115.2144)
		(end 89.5096 -114.2746)
		(width 0.127)
		(layer "In5.Cu")
		(net "USB_OCS_N1")
	)
	(segment
		(start 78.268068 -154.03449)
		(end 80.821022 -151.481536)
		(width 0.127)
		(layer "In5.Cu")
		(net "USB_OCS_N1")
	)
	(segment
		(start 88.80602 -151.102568)
		(end 92.231972 -151.102568)
		(width 0.127)
		(layer "In5.Cu")
		(net "USB_OCS_N1")
	)
	(segment
		(start 76.400914 -154.034236)
		(end 77.952346 -154.034236)
		(width 0.127)
		(layer "In5.Cu")
		(net "USB_OCS_N1")
	)
	(segment
		(start 74.13879 -151.772112)
		(end 76.400914 -154.034236)
		(width 0.127)
		(layer "In5.Cu")
		(net "USB_OCS_N1")
	)
	(segment
		(start 87.0458 -111.8108)
		(end 87.0458 -110.5408)
		(width 0.127)
		(layer "In5.Cu")
		(net "USB_OCS_N1")
	)
	(segment
		(start 80.821022 -151.481536)
		(end 84.165948 -151.481536)
		(width 0.127)
		(layer "In5.Cu")
		(net "USB_OCS_N1")
	)
	(segment
		(start 86.040722 -31.215076)
		(end 85.20684 -32.048958)
		(width 0.127)
		(layer "In5.Cu")
		(net "USB_OCS_N1")
	)
	(segment
		(start 70.329298 -151.772112)
		(end 74.13879 -151.772112)
		(width 0.127)
		(layer "In5.Cu")
		(net "USB_OCS_N1")
	)
	(segment
		(start 84.184236 -60.991496)
		(end 84.184236 -69.060822)
		(width 0.127)
		(layer "In5.Cu")
		(net "USB_OCS_N1")
	)
	(segment
		(start 89.5096 -114.2746)
		(end 87.0458 -111.8108)
		(width 0.127)
		(layer "In5.Cu")
		(net "USB_OCS_N1")
	)
	(segment
		(start 69.99224 -151.435054)
		(end 70.329298 -151.772112)
		(width 0.127)
		(layer "In5.Cu")
		(net "USB_OCS_N1")
	)
	(segment
		(start 65.392554 -151.154384)
		(end 65.673224 -151.435054)
		(width 0.127)
		(layer "In5.Cu")
		(net "USB_OCS_N1")
	)
	(segment
		(start 77.9526 -154.03449)
		(end 78.268068 -154.03449)
		(width 0.127)
		(layer "In5.Cu")
		(net "USB_OCS_N1")
	)
	(segment
		(start 61.803788 -151.767286)
		(end 62.41669 -151.154384)
		(width 0.127)
		(layer "In5.Cu")
		(net "USB_OCS_N1")
	)
	(segment
		(start 85.20684 -32.048958)
		(end 85.20684 -41.0845)
		(width 0.127)
		(layer "In5.Cu")
		(net "USB_OCS_N1")
	)
	(segment
		(start 83.492848 -42.798492)
		(end 83.492848 -60.300108)
		(width 0.127)
		(layer "In5.Cu")
		(net "USB_OCS_N1")
	)
	(segment
		(start 62.41669 -151.154384)
		(end 65.392554 -151.154384)
		(width 0.127)
		(layer "In5.Cu")
		(net "USB_OCS_N1")
	)
	(segment
		(start 92.329 -118.0338)
		(end 89.5096 -115.2144)
		(width 0.127)
		(layer "In5.Cu")
		(net "USB_OCS_N1")
	)
	(segment
		(start 84.184236 -69.060822)
		(end 83.543902 -69.701156)
		(width 0.127)
		(layer "In5.Cu")
		(net "USB_OCS_N1")
	)
	(segment
		(start 176.6062 -77.9018)
		(end 176.5046 -77.8002)
		(width 0.127)
		(layer "F.Cu")
		(net "UART_SERCLK")
	)
	(segment
		(start 182.397146 -73.104756)
		(end 182.397146 -73.102724)
		(width 0.127)
		(layer "F.Cu")
		(net "UART_SERCLK")
	)
	(segment
		(start 174.4853 -77.8002)
		(end 175.5648 -77.8002)
		(width 0.127)
		(layer "F.Cu")
		(net "UART_SERCLK")
	)
	(segment
		(start 176.5046 -77.8002)
		(end 175.5648 -77.8002)
		(width 0.127)
		(layer "F.Cu")
		(net "UART_SERCLK")
	)
	(segment
		(start 182.397146 -73.102724)
		(end 182.79999 -72.69988)
		(width 0.127)
		(layer "F.Cu")
		(net "UART_SERCLK")
	)
	(segment
		(start 174.3075 -77.978)
		(end 174.4853 -77.8002)
		(width 0.127)
		(layer "F.Cu")
		(net "UART_SERCLK")
	)
	(via
		(at 176.6062 -77.9018)
		(size 0.508)
		(drill 0.254)
		(layers "F.Cu" "B.Cu")
		(net "UART_SERCLK")
	)
	(via
		(at 182.397146 -73.104756)
		(size 0.508)
		(drill 0.254)
		(layers "F.Cu" "B.Cu")
		(net "UART_SERCLK")
	)
	(via
		(at 176.5808 -76.6572)
		(size 0.6096)
		(drill 0.3048)
		(layers "F.Cu" "B.Cu")
		(net "UART_SERCLK")
	)
	(segment
		(start 176.708054 -76.52258)
		(end 179.645564 -73.58507)
		(width 0.127)
		(layer "B.Cu")
		(net "UART_SERCLK")
	)
	(segment
		(start 176.7078 -76.52258)
		(end 176.708054 -76.52258)
		(width 0.127)
		(layer "B.Cu")
		(net "UART_SERCLK")
	)
	(segment
		(start 176.5808 -76.64958)
		(end 176.7078 -76.52258)
		(width 0.127)
		(layer "B.Cu")
		(net "UART_SERCLK")
	)
	(segment
		(start 179.645564 -73.58507)
		(end 181.916832 -73.58507)
		(width 0.127)
		(layer "B.Cu")
		(net "UART_SERCLK")
	)
	(segment
		(start 176.5808 -77.8764)
		(end 176.6062 -77.9018)
		(width 0.127)
		(layer "B.Cu")
		(net "UART_SERCLK")
	)
	(segment
		(start 181.916832 -73.58507)
		(end 182.397146 -73.104756)
		(width 0.127)
		(layer "B.Cu")
		(net "UART_SERCLK")
	)
	(segment
		(start 176.5808 -76.6572)
		(end 176.5808 -76.64958)
		(width 0.127)
		(layer "B.Cu")
		(net "UART_SERCLK")
	)
	(segment
		(start 176.5808 -76.6572)
		(end 176.5808 -77.8764)
		(width 0.127)
		(layer "B.Cu")
		(net "UART_SERCLK")
	)
	(segment
		(start 42.100246 -138.599926)
		(end 42.500042 -138.999722)
		(width 0.127)
		(layer "F.Cu")
		(net "TP_BMC_GPIOR5")
	)
	(segment
		(start 42.500042 -138.999722)
		(end 42.500042 -138.999976)
		(width 0.127)
		(layer "F.Cu")
		(net "TP_BMC_GPIOR5")
	)
	(via
		(at 42.100246 -138.599926)
		(size 0.4572)
		(drill 0.2032)
		(layers "F.Cu" "B.Cu")
		(net "TP_BMC_GPIOR5")
	)
	(segment
		(start 42.100246 -138.599926)
		(end 42.493946 -138.206226)
		(width 0.127)
		(layer "B.Cu")
		(net "TP_BMC_GPIOR5")
	)
	(segment
		(start 42.493946 -137.525506)
		(end 41.91762 -136.94918)
		(width 0.127)
		(layer "B.Cu")
		(net "TP_BMC_GPIOR5")
	)
	(segment
		(start 42.493946 -138.206226)
		(end 42.493946 -137.525506)
		(width 0.127)
		(layer "B.Cu")
		(net "TP_BMC_GPIOR5")
	)
	(segment
		(start 41.699942 -138.999722)
		(end 41.699942 -138.999976)
		(width 0.127)
		(layer "F.Cu")
		(net "TP_BMC_GPIOR4")
	)
	(segment
		(start 41.300146 -138.599926)
		(end 41.699942 -138.999722)
		(width 0.127)
		(layer "F.Cu")
		(net "TP_BMC_GPIOR4")
	)
	(via
		(at 41.300146 -138.599926)
		(size 0.4572)
		(drill 0.2032)
		(layers "F.Cu" "B.Cu")
		(net "TP_BMC_GPIOR4")
	)
	(segment
		(start 40.906446 -137.452354)
		(end 40.9702 -137.3886)
		(width 0.127)
		(layer "B.Cu")
		(net "TP_BMC_GPIOR4")
	)
	(segment
		(start 40.9702 -137.3886)
		(end 40.9702 -136.0043)
		(width 0.127)
		(layer "B.Cu")
		(net "TP_BMC_GPIOR4")
	)
	(segment
		(start 40.906446 -138.206226)
		(end 40.906446 -137.452354)
		(width 0.127)
		(layer "B.Cu")
		(net "TP_BMC_GPIOR4")
	)
	(segment
		(start 41.300146 -138.599926)
		(end 40.906446 -138.206226)
		(width 0.127)
		(layer "B.Cu")
		(net "TP_BMC_GPIOR4")
	)
	(segment
		(start 40.9702 -136.0043)
		(end 41.0845 -135.89)
		(width 0.127)
		(layer "B.Cu")
		(net "TP_BMC_GPIOR4")
	)
	(segment
		(start 40.500046 -138.600434)
		(end 40.5003 -138.600434)
		(width 0.127)
		(layer "F.Cu")
		(net "TP_BMC_GPIOR3")
	)
	(segment
		(start 40.5003 -138.600434)
		(end 40.899842 -138.999976)
		(width 0.127)
		(layer "F.Cu")
		(net "TP_BMC_GPIOR3")
	)
	(via
		(at 40.500046 -138.600434)
		(size 0.4572)
		(drill 0.2032)
		(layers "F.Cu" "B.Cu")
		(net "TP_BMC_GPIOR3")
	)
	(segment
		(start 40.500046 -138.600434)
		(end 40.093646 -138.194034)
		(width 0.127)
		(layer "B.Cu")
		(net "TP_BMC_GPIOR3")
	)
	(segment
		(start 39.116254 -138.194034)
		(end 39.020496 -138.098276)
		(width 0.127)
		(layer "B.Cu")
		(net "TP_BMC_GPIOR3")
	)
	(segment
		(start 40.093646 -138.194034)
		(end 39.116254 -138.194034)
		(width 0.127)
		(layer "B.Cu")
		(net "TP_BMC_GPIOR3")
	)
	(segment
		(start 44.099988 -140.599922)
		(end 43.699938 -140.20038)
		(width 0.127)
		(layer "F.Cu")
		(net "TP_BMC_GPIOR2")
	)
	(via
		(at 43.699938 -140.20038)
		(size 0.4572)
		(drill 0.2032)
		(layers "F.Cu" "B.Cu")
		(net "TP_BMC_GPIOR2")
	)
	(segment
		(start 43.699938 -140.20038)
		(end 44.469558 -140.97)
		(width 0.0889)
		(layer "B.Cu")
		(net "TP_BMC_GPIOR2")
	)
	(segment
		(start 44.469558 -140.97)
		(end 44.5008 -140.97)
		(width 0.0889)
		(layer "B.Cu")
		(net "TP_BMC_GPIOR2")
	)
	(segment
		(start 44.099988 -138.999976)
		(end 43.699938 -138.599926)
		(width 0.127)
		(layer "F.Cu")
		(net "TP_BMC_GPIOR1")
	)
	(via
		(at 43.699938 -138.599926)
		(size 0.4572)
		(drill 0.2032)
		(layers "F.Cu" "B.Cu")
		(net "TP_BMC_GPIOR1")
	)
	(segment
		(start 43.31843 -137.624312)
		(end 43.31843 -137.103866)
		(width 0.127)
		(layer "B.Cu")
		(net "TP_BMC_GPIOR1")
	)
	(segment
		(start 43.306238 -137.636504)
		(end 43.31843 -137.624312)
		(width 0.127)
		(layer "B.Cu")
		(net "TP_BMC_GPIOR1")
	)
	(segment
		(start 43.699938 -138.594338)
		(end 43.306238 -138.200638)
		(width 0.127)
		(layer "B.Cu")
		(net "TP_BMC_GPIOR1")
	)
	(segment
		(start 43.306238 -138.200638)
		(end 43.306238 -137.636504)
		(width 0.127)
		(layer "B.Cu")
		(net "TP_BMC_GPIOR1")
	)
	(segment
		(start 43.699938 -138.599926)
		(end 43.699938 -138.594338)
		(width 0.0889)
		(layer "B.Cu")
		(net "TP_BMC_GPIOR1")
	)
	(segment
		(start 61.8236 -138.5062)
		(end 61.8236 -138.679174)
		(width 0.127)
		(layer "F.Cu")
		(net "TP_BMC_GPIOA7")
	)
	(segment
		(start 57.612534 -142.564866)
		(end 57.612534 -142.70736)
		(width 0.127)
		(layer "F.Cu")
		(net "TP_BMC_GPIOA7")
	)
	(segment
		(start 60.174632 -140.500862)
		(end 59.718194 -140.9573)
		(width 0.127)
		(layer "F.Cu")
		(net "TP_BMC_GPIOA7")
	)
	(segment
		(start 60.174632 -140.225526)
		(end 60.174632 -140.500862)
		(width 0.127)
		(layer "F.Cu")
		(net "TP_BMC_GPIOA7")
	)
	(segment
		(start 55.335932 -143.800068)
		(end 55.299864 -143.800068)
		(width 0.127)
		(layer "F.Cu")
		(net "TP_BMC_GPIOA7")
	)
	(segment
		(start 59.718194 -140.9573)
		(end 59.703716 -140.9573)
		(width 0.127)
		(layer "F.Cu")
		(net "TP_BMC_GPIOA7")
	)
	(segment
		(start 58.651394 -141.6685)
		(end 58.5089 -141.6685)
		(width 0.127)
		(layer "F.Cu")
		(net "TP_BMC_GPIOA7")
	)
	(segment
		(start 61.8236 -138.679174)
		(end 61.821822 -138.680952)
		(width 0.127)
		(layer "F.Cu")
		(net "TP_BMC_GPIOA7")
	)
	(segment
		(start 59.218576 -141.101318)
		(end 58.651394 -141.6685)
		(width 0.127)
		(layer "F.Cu")
		(net "TP_BMC_GPIOA7")
	)
	(segment
		(start 59.703716 -140.9573)
		(end 59.559698 -141.101318)
		(width 0.127)
		(layer "F.Cu")
		(net "TP_BMC_GPIOA7")
	)
	(segment
		(start 61.821822 -138.680952)
		(end 61.821822 -139.266168)
		(width 0.127)
		(layer "F.Cu")
		(net "TP_BMC_GPIOA7")
	)
	(segment
		(start 61.408818 -139.679172)
		(end 60.720986 -139.679172)
		(width 0.127)
		(layer "F.Cu")
		(net "TP_BMC_GPIOA7")
	)
	(segment
		(start 56.974994 -143.3449)
		(end 55.7911 -143.3449)
		(width 0.127)
		(layer "F.Cu")
		(net "TP_BMC_GPIOA7")
	)
	(segment
		(start 58.5089 -141.6685)
		(end 57.612534 -142.564866)
		(width 0.127)
		(layer "F.Cu")
		(net "TP_BMC_GPIOA7")
	)
	(segment
		(start 62.6872 -137.6426)
		(end 61.8236 -138.5062)
		(width 0.127)
		(layer "F.Cu")
		(net "TP_BMC_GPIOA7")
	)
	(segment
		(start 59.559698 -141.101318)
		(end 59.218576 -141.101318)
		(width 0.127)
		(layer "F.Cu")
		(net "TP_BMC_GPIOA7")
	)
	(segment
		(start 61.821822 -139.266168)
		(end 61.408818 -139.679172)
		(width 0.127)
		(layer "F.Cu")
		(net "TP_BMC_GPIOA7")
	)
	(segment
		(start 60.720986 -139.679172)
		(end 60.174632 -140.225526)
		(width 0.127)
		(layer "F.Cu")
		(net "TP_BMC_GPIOA7")
	)
	(segment
		(start 57.612534 -142.70736)
		(end 56.974994 -143.3449)
		(width 0.127)
		(layer "F.Cu")
		(net "TP_BMC_GPIOA7")
	)
	(segment
		(start 55.7911 -143.3449)
		(end 55.335932 -143.800068)
		(width 0.127)
		(layer "F.Cu")
		(net "TP_BMC_GPIOA7")
	)
	(segment
		(start 54.899814 -143.400526)
		(end 54.500272 -143.800068)
		(width 0.127)
		(layer "F.Cu")
		(net "TP_BMC_GPIOA6")
	)
	(segment
		(start 54.500272 -143.800068)
		(end 54.500018 -143.800068)
		(width 0.127)
		(layer "F.Cu")
		(net "TP_BMC_GPIOA6")
	)
	(via
		(at 54.899814 -143.400526)
		(size 0.4572)
		(drill 0.2032)
		(layers "F.Cu" "B.Cu")
		(net "TP_BMC_GPIOA6")
	)
	(segment
		(start 54.899814 -143.400526)
		(end 55.412132 -142.888208)
		(width 0.127)
		(layer "B.Cu")
		(net "TP_BMC_GPIOA6")
	)
	(segment
		(start 55.412132 -142.888208)
		(end 55.785258 -142.888208)
		(width 0.127)
		(layer "B.Cu")
		(net "TP_BMC_GPIOA6")
	)
	(segment
		(start 53.3527 -135.611362)
		(end 52.899818 -136.064244)
		(width 0.127)
		(layer "F.Cu")
		(net "TP_BMC0_LPC_LAD3")
	)
	(segment
		(start 52.899818 -136.064244)
		(end 52.899818 -136.59993)
		(width 0.127)
		(layer "F.Cu")
		(net "TP_BMC0_LPC_LAD3")
	)
	(segment
		(start 53.3019 -132.509514)
		(end 53.3019 -134.641336)
		(width 0.127)
		(layer "F.Cu")
		(net "TP_BMC0_LPC_LAD3")
	)
	(segment
		(start 53.3781 -131.3815)
		(end 53.3781 -132.433314)
		(width 0.127)
		(layer "F.Cu")
		(net "TP_BMC0_LPC_LAD3")
	)
	(segment
		(start 53.3019 -134.641336)
		(end 53.3527 -134.692136)
		(width 0.127)
		(layer "F.Cu")
		(net "TP_BMC0_LPC_LAD3")
	)
	(segment
		(start 52.8574 -130.8608)
		(end 53.3781 -131.3815)
		(width 0.127)
		(layer "F.Cu")
		(net "TP_BMC0_LPC_LAD3")
	)
	(segment
		(start 53.3781 -132.433314)
		(end 53.3019 -132.509514)
		(width 0.127)
		(layer "F.Cu")
		(net "TP_BMC0_LPC_LAD3")
	)
	(segment
		(start 53.3527 -134.692136)
		(end 53.3527 -135.611362)
		(width 0.127)
		(layer "F.Cu")
		(net "TP_BMC0_LPC_LAD3")
	)
	(segment
		(start 54.942994 -132.82803)
		(end 55.1434 -132.627624)
		(width 0.127)
		(layer "F.Cu")
		(net "TP_BMC0_LPC_LAD2")
	)
	(segment
		(start 55.0037 -133.797294)
		(end 54.942994 -133.736588)
		(width 0.127)
		(layer "F.Cu")
		(net "TP_BMC0_LPC_LAD2")
	)
	(segment
		(start 53.699918 -136.59993)
		(end 55.0037 -135.296148)
		(width 0.127)
		(layer "F.Cu")
		(net "TP_BMC0_LPC_LAD2")
	)
	(segment
		(start 55.0037 -135.296148)
		(end 55.0037 -133.797294)
		(width 0.127)
		(layer "F.Cu")
		(net "TP_BMC0_LPC_LAD2")
	)
	(segment
		(start 54.942994 -133.736588)
		(end 54.942994 -132.82803)
		(width 0.127)
		(layer "F.Cu")
		(net "TP_BMC0_LPC_LAD2")
	)
	(segment
		(start 55.1434 -132.627624)
		(end 55.1434 -132.1562)
		(width 0.127)
		(layer "F.Cu")
		(net "TP_BMC0_LPC_LAD2")
	)
	(segment
		(start 52.442872 -135.509)
		(end 52.3367 -135.402828)
		(width 0.127)
		(layer "F.Cu")
		(net "TP_BMC0_LPC_LAD1")
	)
	(segment
		(start 52.442872 -136.74217)
		(end 52.442872 -135.509)
		(width 0.127)
		(layer "F.Cu")
		(net "TP_BMC0_LPC_LAD1")
	)
	(segment
		(start 51.669696 -137.345166)
		(end 52.072032 -136.94283)
		(width 0.127)
		(layer "F.Cu")
		(net "TP_BMC0_LPC_LAD1")
	)
	(segment
		(start 51.669696 -137.830052)
		(end 51.669696 -137.345166)
		(width 0.127)
		(layer "F.Cu")
		(net "TP_BMC0_LPC_LAD1")
	)
	(segment
		(start 52.072032 -136.94283)
		(end 52.242212 -136.94283)
		(width 0.127)
		(layer "F.Cu")
		(net "TP_BMC0_LPC_LAD1")
	)
	(segment
		(start 52.3367 -135.402828)
		(end 52.3367 -134.268464)
		(width 0.127)
		(layer "F.Cu")
		(net "TP_BMC0_LPC_LAD1")
	)
	(segment
		(start 52.242212 -136.94283)
		(end 52.442872 -136.74217)
		(width 0.127)
		(layer "F.Cu")
		(net "TP_BMC0_LPC_LAD1")
	)
	(segment
		(start 51.299872 -138.199876)
		(end 51.669696 -137.830052)
		(width 0.127)
		(layer "F.Cu")
		(net "TP_BMC0_LPC_LAD1")
	)
	(segment
		(start 52.3367 -134.268464)
		(end 52.832 -133.773164)
		(width 0.127)
		(layer "F.Cu")
		(net "TP_BMC0_LPC_LAD1")
	)
	(segment
		(start 52.832 -133.773164)
		(end 52.832 -132.207)
		(width 0.127)
		(layer "F.Cu")
		(net "TP_BMC0_LPC_LAD1")
	)
	(segment
		(start 49.1871 -133.805168)
		(end 49.479962 -133.512306)
		(width 0.127)
		(layer "F.Cu")
		(net "TP_BMC0_LPC_LAD0")
	)
	(segment
		(start 49.479962 -131.545838)
		(end 51.5112 -129.5146)
		(width 0.127)
		(layer "F.Cu")
		(net "TP_BMC0_LPC_LAD0")
	)
	(segment
		(start 49.1871 -134.641336)
		(end 49.1871 -133.805168)
		(width 0.127)
		(layer "F.Cu")
		(net "TP_BMC0_LPC_LAD0")
	)
	(segment
		(start 50.923952 -137.02411)
		(end 50.923952 -136.378188)
		(width 0.127)
		(layer "F.Cu")
		(net "TP_BMC0_LPC_LAD0")
	)
	(segment
		(start 50.923952 -136.378188)
		(end 49.1871 -134.641336)
		(width 0.127)
		(layer "F.Cu")
		(net "TP_BMC0_LPC_LAD0")
	)
	(segment
		(start 49.479962 -133.512306)
		(end 49.479962 -131.545838)
		(width 0.127)
		(layer "F.Cu")
		(net "TP_BMC0_LPC_LAD0")
	)
	(segment
		(start 51.299872 -137.40003)
		(end 50.923952 -137.02411)
		(width 0.127)
		(layer "F.Cu")
		(net "TP_BMC0_LPC_LAD0")
	)
	(via
		(at 49.479962 -133.512306)
		(size 0.6604)
		(drill 0.3302)
		(layers "F.Cu" "B.Cu")
		(net "TP_BMC0_LPC_LAD0")
	)
	(segment
		(start 186.799982 -72.69988)
		(end 186.400186 -72.300084)
		(width 0.127)
		(layer "F.Cu")
		(net "SYS_RST_N_1")
	)
	(via
		(at 186.400186 -72.300084)
		(size 0.508)
		(drill 0.254)
		(layers "F.Cu" "B.Cu")
		(net "SYS_RST_N_1")
	)
	(segment
		(start 185.5343 -72.65924)
		(end 185.05932 -73.13422)
		(width 0.127)
		(layer "B.Cu")
		(net "SYS_RST_N_1")
	)
	(segment
		(start 186.400186 -72.300084)
		(end 186.400186 -72.40524)
		(width 0.127)
		(layer "B.Cu")
		(net "SYS_RST_N_1")
	)
	(segment
		(start 186.146186 -72.65924)
		(end 185.5343 -72.65924)
		(width 0.127)
		(layer "B.Cu")
		(net "SYS_RST_N_1")
	)
	(segment
		(start 186.400186 -72.40524)
		(end 186.146186 -72.65924)
		(width 0.127)
		(layer "B.Cu")
		(net "SYS_RST_N_1")
	)
	(segment
		(start 154.70632 -89.488264)
		(end 155.175204 -89.488264)
		(width 0.127)
		(layer "F.Cu")
		(net "SYS_RST_N_0")
	)
	(segment
		(start 153.383742 -96.383094)
		(end 153.383742 -96.716342)
		(width 0.127)
		(layer "F.Cu")
		(net "SYS_RST_N_0")
	)
	(segment
		(start 153.383742 -94.950788)
		(end 153.383742 -96.383094)
		(width 0.127)
		(layer "F.Cu")
		(net "SYS_RST_N_0")
	)
	(segment
		(start 155.175204 -89.488264)
		(end 155.492704 -89.805764)
		(width 0.127)
		(layer "F.Cu")
		(net "SYS_RST_N_0")
	)
	(segment
		(start 155.492704 -89.805764)
		(end 155.642564 -89.805764)
		(width 0.127)
		(layer "F.Cu")
		(net "SYS_RST_N_0")
	)
	(segment
		(start 154.422856 -89.2048)
		(end 154.70632 -89.488264)
		(width 0.127)
		(layer "F.Cu")
		(net "SYS_RST_N_0")
	)
	(segment
		(start 153.383742 -96.716342)
		(end 153.787348 -97.119948)
		(width 0.127)
		(layer "F.Cu")
		(net "SYS_RST_N_0")
	)
	(segment
		(start 156.724858 -90.354658)
		(end 156.724858 -91.190064)
		(width 0.127)
		(layer "F.Cu")
		(net "SYS_RST_N_0")
	)
	(segment
		(start 155.642564 -89.805764)
		(end 155.9306 -90.0938)
		(width 0.127)
		(layer "F.Cu")
		(net "SYS_RST_N_0")
	)
	(segment
		(start 154.2034 -89.2048)
		(end 154.422856 -89.2048)
		(width 0.127)
		(layer "F.Cu")
		(net "SYS_RST_N_0")
	)
	(segment
		(start 189.200028 -75.099926)
		(end 189.599824 -75.499722)
		(width 0.127)
		(layer "F.Cu")
		(net "SYS_RST_N_0")
	)
	(segment
		(start 153.787348 -97.119948)
		(end 154.3812 -97.119948)
		(width 0.127)
		(layer "F.Cu")
		(net "SYS_RST_N_0")
	)
	(segment
		(start 153.481532 -94.852998)
		(end 153.383742 -94.950788)
		(width 0.127)
		(layer "F.Cu")
		(net "SYS_RST_N_0")
	)
	(segment
		(start 156.464 -90.0938)
		(end 156.724858 -90.354658)
		(width 0.127)
		(layer "F.Cu")
		(net "SYS_RST_N_0")
	)
	(segment
		(start 155.9306 -90.0938)
		(end 156.464 -90.0938)
		(width 0.127)
		(layer "F.Cu")
		(net "SYS_RST_N_0")
	)
	(via
		(at 189.599824 -75.499722)
		(size 0.508)
		(drill 0.254)
		(layers "F.Cu" "B.Cu")
		(net "SYS_RST_N_0")
	)
	(via
		(at 154.3812 -97.119948)
		(size 0.508)
		(drill 0.254)
		(layers "F.Cu" "B.Cu")
		(net "SYS_RST_N_0")
	)
	(via
		(at 186.7662 -102.097078)
		(size 0.508)
		(drill 0.254)
		(layers "F.Cu" "B.Cu")
		(net "SYS_RST_N_0")
	)
	(via
		(at 154.2034 -89.2048)
		(size 0.508)
		(drill 0.254)
		(layers "F.Cu" "B.Cu")
		(net "SYS_RST_N_0")
	)
	(segment
		(start 188.0616 -82.959448)
		(end 188.0616 -80.960976)
		(width 0.127)
		(layer "In2.Cu")
		(net "SYS_RST_N_0")
	)
	(segment
		(start 154.3812 -97.119948)
		(end 153.9113 -96.650048)
		(width 0.127)
		(layer "In2.Cu")
		(net "SYS_RST_N_0")
	)
	(segment
		(start 153.565606 -89.842594)
		(end 154.2034 -89.2048)
		(width 0.127)
		(layer "In2.Cu")
		(net "SYS_RST_N_0")
	)
	(segment
		(start 186.8805 -101.982778)
		(end 186.8805 -84.140548)
		(width 0.127)
		(layer "In2.Cu")
		(net "SYS_RST_N_0")
	)
	(segment
		(start 186.8805 -84.140548)
		(end 188.0616 -82.959448)
		(width 0.127)
		(layer "In2.Cu")
		(net "SYS_RST_N_0")
	)
	(segment
		(start 153.911554 -92.412058)
		(end 153.911554 -91.886278)
		(width 0.127)
		(layer "In2.Cu")
		(net "SYS_RST_N_0")
	)
	(segment
		(start 189.618874 -75.518772)
		(end 189.599824 -75.499722)
		(width 0.127)
		(layer "In2.Cu")
		(net "SYS_RST_N_0")
	)
	(segment
		(start 188.0616 -80.960976)
		(end 189.618874 -79.403702)
		(width 0.127)
		(layer "In2.Cu")
		(net "SYS_RST_N_0")
	)
	(segment
		(start 186.7662 -102.097078)
		(end 186.8805 -101.982778)
		(width 0.127)
		(layer "In2.Cu")
		(net "SYS_RST_N_0")
	)
	(segment
		(start 189.618874 -79.403702)
		(end 189.618874 -75.518772)
		(width 0.127)
		(layer "In2.Cu")
		(net "SYS_RST_N_0")
	)
	(segment
		(start 153.9113 -96.650048)
		(end 153.911554 -92.412058)
		(width 0.127)
		(layer "In2.Cu")
		(net "SYS_RST_N_0")
	)
	(segment
		(start 153.565606 -91.54033)
		(end 153.565606 -89.842594)
		(width 0.127)
		(layer "In2.Cu")
		(net "SYS_RST_N_0")
	)
	(segment
		(start 153.911554 -91.886278)
		(end 153.565606 -91.54033)
		(width 0.127)
		(layer "In2.Cu")
		(net "SYS_RST_N_0")
	)
	(segment
		(start 157.24251 -96.926146)
		(end 157.053534 -97.115122)
		(width 0.127)
		(layer "In5.Cu")
		(net "SYS_RST_N_0")
	)
	(segment
		(start 157.76829 -96.926146)
		(end 157.24251 -96.926146)
		(width 0.127)
		(layer "In5.Cu")
		(net "SYS_RST_N_0")
	)
	(segment
		(start 154.446478 -97.115122)
		(end 154.441652 -97.119948)
		(width 0.127)
		(layer "In5.Cu")
		(net "SYS_RST_N_0")
	)
	(segment
		(start 157.053534 -97.115122)
		(end 154.446478 -97.115122)
		(width 0.127)
		(layer "In5.Cu")
		(net "SYS_RST_N_0")
	)
	(segment
		(start 184.977278 -102.097078)
		(end 183.500268 -100.620068)
		(width 0.127)
		(layer "In5.Cu")
		(net "SYS_RST_N_0")
	)
	(segment
		(start 154.441652 -97.119948)
		(end 154.3812 -97.119948)
		(width 0.127)
		(layer "In5.Cu")
		(net "SYS_RST_N_0")
	)
	(segment
		(start 183.500268 -100.620068)
		(end 164.574728 -100.620068)
		(width 0.127)
		(layer "In5.Cu")
		(net "SYS_RST_N_0")
	)
	(segment
		(start 161.269934 -97.315274)
		(end 158.157418 -97.315274)
		(width 0.127)
		(layer "In5.Cu")
		(net "SYS_RST_N_0")
	)
	(segment
		(start 158.157418 -97.315274)
		(end 157.76829 -96.926146)
		(width 0.127)
		(layer "In5.Cu")
		(net "SYS_RST_N_0")
	)
	(segment
		(start 164.574728 -100.620068)
		(end 161.269934 -97.315274)
		(width 0.127)
		(layer "In5.Cu")
		(net "SYS_RST_N_0")
	)
	(segment
		(start 186.7662 -102.097078)
		(end 184.977278 -102.097078)
		(width 0.127)
		(layer "In5.Cu")
		(net "SYS_RST_N_0")
	)
	(segment
		(start 197.999858 -65.499996)
		(end 197.600062 -65.1002)
		(width 0.3048)
		(layer "F.Cu")
		(net "SYS_PLL_VDD")
	)
	(via
		(at 202.240388 -53.077364)
		(size 0.6096)
		(drill 0.3048)
		(layers "F.Cu" "B.Cu")
		(net "SYS_PLL_VDD")
	)
	(via
		(at 197.600062 -65.1002)
		(size 0.508)
		(drill 0.254)
		(layers "F.Cu" "B.Cu")
		(net "SYS_PLL_VDD")
	)
	(via
		(at 202.080622 -52.340002)
		(size 0.508)
		(drill 0.254)
		(layers "F.Cu" "B.Cu")
		(net "SYS_PLL_VDD")
	)
	(segment
		(start 196.12864 -55.83682)
		(end 196.12864 -59.23534)
		(width 0.508)
		(layer "In2.Cu")
		(net "SYS_PLL_VDD")
	)
	(segment
		(start 196.7738 -60.7187)
		(end 197.600062 -61.544962)
		(width 0.508)
		(layer "In2.Cu")
		(net "SYS_PLL_VDD")
	)
	(segment
		(start 200.625456 -53.795168)
		(end 199.163432 -53.795168)
		(width 0.508)
		(layer "In2.Cu")
		(net "SYS_PLL_VDD")
	)
	(segment
		(start 199.163432 -53.795168)
		(end 198.2597 -54.6989)
		(width 0.508)
		(layer "In2.Cu")
		(net "SYS_PLL_VDD")
	)
	(segment
		(start 198.2597 -54.6989)
		(end 197.26656 -54.6989)
		(width 0.508)
		(layer "In2.Cu")
		(net "SYS_PLL_VDD")
	)
	(segment
		(start 197.600062 -61.544962)
		(end 197.600062 -65.1002)
		(width 0.508)
		(layer "In2.Cu")
		(net "SYS_PLL_VDD")
	)
	(segment
		(start 197.26656 -54.6989)
		(end 196.12864 -55.83682)
		(width 0.508)
		(layer "In2.Cu")
		(net "SYS_PLL_VDD")
	)
	(segment
		(start 196.12864 -59.23534)
		(end 196.7738 -59.8805)
		(width 0.508)
		(layer "In2.Cu")
		(net "SYS_PLL_VDD")
	)
	(segment
		(start 196.7738 -59.8805)
		(end 196.7738 -60.7187)
		(width 0.508)
		(layer "In2.Cu")
		(net "SYS_PLL_VDD")
	)
	(segment
		(start 202.080622 -52.340002)
		(end 200.625456 -53.795168)
		(width 0.508)
		(layer "In2.Cu")
		(net "SYS_PLL_VDD")
	)
	(segment
		(start 163.181284 -104.784398)
		(end 162.786314 -105.179368)
		(width 0.127)
		(layer "F.Cu")
		(net "SYS_HB_LED_R")
	)
	(segment
		(start 162.786314 -105.386632)
		(end 162.786314 -105.61066)
		(width 0.127)
		(layer "F.Cu")
		(net "SYS_HB_LED_R")
	)
	(segment
		(start 164.179758 -104.784398)
		(end 163.181284 -104.784398)
		(width 0.127)
		(layer "F.Cu")
		(net "SYS_HB_LED_R")
	)
	(segment
		(start 162.786314 -105.179368)
		(end 162.786314 -105.386632)
		(width 0.127)
		(layer "F.Cu")
		(net "SYS_HB_LED_R")
	)
	(segment
		(start 162.786314 -105.61066)
		(end 163.204398 -106.028744)
		(width 0.127)
		(layer "F.Cu")
		(net "SYS_HB_LED_R")
	)
	(segment
		(start 163.204398 -106.028744)
		(end 164.203126 -106.028744)
		(width 0.127)
		(layer "F.Cu")
		(net "SYS_HB_LED_R")
	)
	(via
		(at 162.786314 -105.386632)
		(size 0.6604)
		(drill 0.3302)
		(layers "F.Cu" "B.Cu")
		(net "SYS_HB_LED_R")
	)
	(segment
		(start 164.13988 -101.344476)
		(end 166.177976 -101.344476)
		(width 0.127)
		(layer "F.Cu")
		(net "SYS_HB_LED_D")
	)
	(segment
		(start 165.77818 -103.260398)
		(end 166.5732 -102.465378)
		(width 0.127)
		(layer "F.Cu")
		(net "SYS_HB_LED_D")
	)
	(segment
		(start 166.177976 -101.344476)
		(end 166.5732 -101.7397)
		(width 0.127)
		(layer "F.Cu")
		(net "SYS_HB_LED_D")
	)
	(segment
		(start 164.179758 -103.260398)
		(end 165.77818 -103.260398)
		(width 0.127)
		(layer "F.Cu")
		(net "SYS_HB_LED_D")
	)
	(segment
		(start 166.5732 -102.465378)
		(end 166.5732 -101.7397)
		(width 0.127)
		(layer "F.Cu")
		(net "SYS_HB_LED_D")
	)
	(via
		(at 166.5732 -101.7397)
		(size 0.6604)
		(drill 0.3302)
		(layers "F.Cu" "B.Cu")
		(net "SYS_HB_LED_D")
	)
	(segment
		(start 162.506914 -99.439476)
		(end 163.15563 -99.439476)
		(width 0.127)
		(layer "F.Cu")
		(net "SYS_HB_LED")
	)
	(segment
		(start 177.883566 -66.802)
		(end 178.645566 -66.04)
		(width 0.127)
		(layer "F.Cu")
		(net "SYS_HB_LED")
	)
	(segment
		(start 177.3428 -66.802)
		(end 177.883566 -66.802)
		(width 0.127)
		(layer "F.Cu")
		(net "SYS_HB_LED")
	)
	(segment
		(start 161.403538 -100.773738)
		(end 161.835338 -100.773738)
		(width 0.127)
		(layer "F.Cu")
		(net "SYS_HB_LED")
	)
	(segment
		(start 180.734462 -66.04)
		(end 180.902102 -65.87236)
		(width 0.127)
		(layer "F.Cu")
		(net "SYS_HB_LED")
	)
	(segment
		(start 181.627526 -65.87236)
		(end 181.99989 -65.499996)
		(width 0.127)
		(layer "F.Cu")
		(net "SYS_HB_LED")
	)
	(segment
		(start 160.58388 -98.982276)
		(end 160.58388 -99.95408)
		(width 0.127)
		(layer "F.Cu")
		(net "SYS_HB_LED")
	)
	(segment
		(start 180.902102 -65.87236)
		(end 181.627526 -65.87236)
		(width 0.127)
		(layer "F.Cu")
		(net "SYS_HB_LED")
	)
	(segment
		(start 160.58388 -99.95408)
		(end 161.403538 -100.773738)
		(width 0.127)
		(layer "F.Cu")
		(net "SYS_HB_LED")
	)
	(segment
		(start 161.835338 -100.773738)
		(end 161.835338 -100.111052)
		(width 0.127)
		(layer "F.Cu")
		(net "SYS_HB_LED")
	)
	(segment
		(start 178.645566 -66.04)
		(end 180.734462 -66.04)
		(width 0.127)
		(layer "F.Cu")
		(net "SYS_HB_LED")
	)
	(segment
		(start 177.0126 -67.1322)
		(end 177.3428 -66.802)
		(width 0.127)
		(layer "F.Cu")
		(net "SYS_HB_LED")
	)
	(segment
		(start 176.2252 -67.1322)
		(end 177.0126 -67.1322)
		(width 0.127)
		(layer "F.Cu")
		(net "SYS_HB_LED")
	)
	(segment
		(start 161.835338 -100.111052)
		(end 162.506914 -99.439476)
		(width 0.127)
		(layer "F.Cu")
		(net "SYS_HB_LED")
	)
	(via
		(at 160.58388 -98.982276)
		(size 0.508)
		(drill 0.254)
		(layers "F.Cu" "B.Cu")
		(net "SYS_HB_LED")
	)
	(via
		(at 175.735742 -102.5652)
		(size 0.508)
		(drill 0.254)
		(layers "F.Cu" "B.Cu")
		(net "SYS_HB_LED")
	)
	(via
		(at 160.58388 -99.95408)
		(size 0.6604)
		(drill 0.3302)
		(layers "F.Cu" "B.Cu")
		(net "SYS_HB_LED")
	)
	(via
		(at 176.2252 -67.1322)
		(size 0.508)
		(drill 0.254)
		(layers "F.Cu" "B.Cu")
		(net "SYS_HB_LED")
	)
	(segment
		(start 173.372018 -73.6092)
		(end 172.899324 -73.6092)
		(width 0.127)
		(layer "In2.Cu")
		(net "SYS_HB_LED")
	)
	(segment
		(start 172.5549 -99.384358)
		(end 175.735742 -102.5652)
		(width 0.127)
		(layer "In2.Cu")
		(net "SYS_HB_LED")
	)
	(segment
		(start 173.6471 -72.86117)
		(end 173.6471 -73.334118)
		(width 0.127)
		(layer "In2.Cu")
		(net "SYS_HB_LED")
	)
	(segment
		(start 176.2252 -67.1322)
		(end 176.2252 -70.283324)
		(width 0.127)
		(layer "In2.Cu")
		(net "SYS_HB_LED")
	)
	(segment
		(start 172.899324 -73.6092)
		(end 172.5549 -73.953624)
		(width 0.127)
		(layer "In2.Cu")
		(net "SYS_HB_LED")
	)
	(segment
		(start 176.2252 -70.283324)
		(end 173.6471 -72.86117)
		(width 0.127)
		(layer "In2.Cu")
		(net "SYS_HB_LED")
	)
	(segment
		(start 173.6471 -73.334118)
		(end 173.372018 -73.6092)
		(width 0.127)
		(layer "In2.Cu")
		(net "SYS_HB_LED")
	)
	(segment
		(start 172.5549 -73.953624)
		(end 172.5549 -99.384358)
		(width 0.127)
		(layer "In2.Cu")
		(net "SYS_HB_LED")
	)
	(segment
		(start 163.561014 -101.95941)
		(end 175.129952 -101.95941)
		(width 0.127)
		(layer "In5.Cu")
		(net "SYS_HB_LED")
	)
	(segment
		(start 175.129952 -101.95941)
		(end 175.735742 -102.5652)
		(width 0.127)
		(layer "In5.Cu")
		(net "SYS_HB_LED")
	)
	(segment
		(start 160.58388 -98.982276)
		(end 163.561014 -101.95941)
		(width 0.127)
		(layer "In5.Cu")
		(net "SYS_HB_LED")
	)
	(segment
		(start 179.4002 -81.2546)
		(end 179.324 -81.3308)
		(width 0.127)
		(layer "F.Cu")
		(net "SYS_HALT1#")
	)
	(segment
		(start 183.34482 -79.10068)
		(end 182.79872 -79.10068)
		(width 0.127)
		(layer "F.Cu")
		(net "SYS_HALT1#")
	)
	(segment
		(start 182.79872 -79.10068)
		(end 181.86654 -80.03286)
		(width 0.127)
		(layer "F.Cu")
		(net "SYS_HALT1#")
	)
	(segment
		(start 181.1909 -81.2546)
		(end 179.4002 -81.2546)
		(width 0.127)
		(layer "F.Cu")
		(net "SYS_HALT1#")
	)
	(segment
		(start 184.399936 -76.699872)
		(end 184.399936 -77.941932)
		(width 0.127)
		(layer "F.Cu")
		(net "SYS_HALT1#")
	)
	(segment
		(start 181.86654 -80.03286)
		(end 181.86654 -80.57896)
		(width 0.127)
		(layer "F.Cu")
		(net "SYS_HALT1#")
	)
	(segment
		(start 183.549544 -78.895956)
		(end 183.34482 -79.10068)
		(width 0.127)
		(layer "F.Cu")
		(net "SYS_HALT1#")
	)
	(segment
		(start 183.680608 -78.895956)
		(end 183.549544 -78.895956)
		(width 0.127)
		(layer "F.Cu")
		(net "SYS_HALT1#")
	)
	(segment
		(start 179.324 -81.3308)
		(end 179.324 -82.4865)
		(width 0.127)
		(layer "F.Cu")
		(net "SYS_HALT1#")
	)
	(segment
		(start 184.399936 -77.941932)
		(end 183.925972 -78.415896)
		(width 0.127)
		(layer "F.Cu")
		(net "SYS_HALT1#")
	)
	(segment
		(start 183.925972 -78.650592)
		(end 183.680608 -78.895956)
		(width 0.127)
		(layer "F.Cu")
		(net "SYS_HALT1#")
	)
	(segment
		(start 183.925972 -78.415896)
		(end 183.925972 -78.650592)
		(width 0.127)
		(layer "F.Cu")
		(net "SYS_HALT1#")
	)
	(segment
		(start 181.86654 -80.57896)
		(end 181.1909 -81.2546)
		(width 0.127)
		(layer "F.Cu")
		(net "SYS_HALT1#")
	)
	(segment
		(start 186.242452 -83.201256)
		(end 186.242452 -80.904588)
		(width 0.127)
		(layer "F.Cu")
		(net "SYS_HALT0#")
	)
	(segment
		(start 183.515 -85.928708)
		(end 186.242452 -83.201256)
		(width 0.127)
		(layer "F.Cu")
		(net "SYS_HALT0#")
	)
	(segment
		(start 183.515 -86.614)
		(end 183.515 -87.9475)
		(width 0.127)
		(layer "F.Cu")
		(net "SYS_HALT0#")
	)
	(segment
		(start 183.515 -86.614)
		(end 183.515 -85.928708)
		(width 0.127)
		(layer "F.Cu")
		(net "SYS_HALT0#")
	)
	(segment
		(start 186.799982 -80.347058)
		(end 186.799982 -76.699872)
		(width 0.127)
		(layer "F.Cu")
		(net "SYS_HALT0#")
	)
	(segment
		(start 186.242452 -80.904588)
		(end 186.799982 -80.347058)
		(width 0.127)
		(layer "F.Cu")
		(net "SYS_HALT0#")
	)
	(segment
		(start 189.225428 -79.960216)
		(end 190.059056 -79.126588)
		(width 0.127)
		(layer "F.Cu")
		(net "SYS_ERR_0")
	)
	(segment
		(start 189.225428 -81.843372)
		(end 189.225428 -79.960216)
		(width 0.127)
		(layer "F.Cu")
		(net "SYS_ERR_0")
	)
	(segment
		(start 189.606174 -76.836524)
		(end 189.606174 -76.306172)
		(width 0.127)
		(layer "F.Cu")
		(net "SYS_ERR_0")
	)
	(segment
		(start 189.869572 -77.302106)
		(end 189.869572 -77.099922)
		(width 0.127)
		(layer "F.Cu")
		(net "SYS_ERR_0")
	)
	(segment
		(start 190.059056 -77.49159)
		(end 189.869572 -77.302106)
		(width 0.127)
		(layer "F.Cu")
		(net "SYS_ERR_0")
	)
	(segment
		(start 190.059056 -79.126588)
		(end 190.059056 -77.49159)
		(width 0.127)
		(layer "F.Cu")
		(net "SYS_ERR_0")
	)
	(segment
		(start 225.713798 -76.019914)
		(end 226.941126 -76.019914)
		(width 0.127)
		(layer "F.Cu")
		(net "SYS_ERR_0")
	)
	(segment
		(start 189.606174 -76.306172)
		(end 189.200028 -75.900026)
		(width 0.127)
		(layer "F.Cu")
		(net "SYS_ERR_0")
	)
	(segment
		(start 225.476562 -76.25715)
		(end 225.713798 -76.019914)
		(width 0.127)
		(layer "F.Cu")
		(net "SYS_ERR_0")
	)
	(segment
		(start 224.786952 -76.25715)
		(end 225.476562 -76.25715)
		(width 0.127)
		(layer "F.Cu")
		(net "SYS_ERR_0")
	)
	(segment
		(start 189.869572 -77.099922)
		(end 189.606174 -76.836524)
		(width 0.127)
		(layer "F.Cu")
		(net "SYS_ERR_0")
	)
	(segment
		(start 189.0776 -81.9912)
		(end 189.225428 -81.843372)
		(width 0.127)
		(layer "F.Cu")
		(net "SYS_ERR_0")
	)
	(segment
		(start 224.34296 -76.701142)
		(end 224.786952 -76.25715)
		(width 0.127)
		(layer "F.Cu")
		(net "SYS_ERR_0")
	)
	(via
		(at 225.476562 -76.25715)
		(size 0.6604)
		(drill 0.3302)
		(layers "F.Cu" "B.Cu")
		(net "SYS_ERR_0")
	)
	(via
		(at 189.0776 -81.9912)
		(size 0.508)
		(drill 0.254)
		(layers "F.Cu" "B.Cu")
		(net "SYS_ERR_0")
	)
	(via
		(at 224.34296 -76.701142)
		(size 0.508)
		(drill 0.254)
		(layers "F.Cu" "B.Cu")
		(net "SYS_ERR_0")
	)
	(via
		(at 200.750678 -95.956374)
		(size 0.508)
		(drill 0.254)
		(layers "F.Cu" "B.Cu")
		(net "SYS_ERR_0")
	)
	(segment
		(start 188.878718 -82.190082)
		(end 188.878718 -82.681318)
		(width 0.127)
		(layer "In2.Cu")
		(net "SYS_ERR_0")
	)
	(segment
		(start 191.44742 -95.956374)
		(end 200.750678 -95.956374)
		(width 0.127)
		(layer "In2.Cu")
		(net "SYS_ERR_0")
	)
	(segment
		(start 188.4807 -87.95131)
		(end 188.4807 -92.989654)
		(width 0.127)
		(layer "In2.Cu")
		(net "SYS_ERR_0")
	)
	(segment
		(start 187.79236 -83.767676)
		(end 187.79236 -87.262716)
		(width 0.127)
		(layer "In2.Cu")
		(net "SYS_ERR_0")
	)
	(segment
		(start 187.79236 -87.262716)
		(end 188.4807 -87.95131)
		(width 0.127)
		(layer "In2.Cu")
		(net "SYS_ERR_0")
	)
	(segment
		(start 188.878718 -82.681318)
		(end 187.79236 -83.767676)
		(width 0.127)
		(layer "In2.Cu")
		(net "SYS_ERR_0")
	)
	(segment
		(start 188.4807 -92.989654)
		(end 191.44742 -95.956374)
		(width 0.127)
		(layer "In2.Cu")
		(net "SYS_ERR_0")
	)
	(segment
		(start 189.0776 -81.9912)
		(end 188.878718 -82.190082)
		(width 0.127)
		(layer "In2.Cu")
		(net "SYS_ERR_0")
	)
	(segment
		(start 213.204552 -93.669358)
		(end 205.83906 -93.669358)
		(width 0.127)
		(layer "In5.Cu")
		(net "SYS_ERR_0")
	)
	(segment
		(start 222.785178 -78.258924)
		(end 220.194124 -78.258924)
		(width 0.127)
		(layer "In5.Cu")
		(net "SYS_ERR_0")
	)
	(segment
		(start 205.83906 -93.669358)
		(end 203.552044 -95.956374)
		(width 0.127)
		(layer "In5.Cu")
		(net "SYS_ERR_0")
	)
	(segment
		(start 203.552044 -95.956374)
		(end 200.750678 -95.956374)
		(width 0.127)
		(layer "In5.Cu")
		(net "SYS_ERR_0")
	)
	(segment
		(start 216.6112 -90.26271)
		(end 213.204552 -93.669358)
		(width 0.127)
		(layer "In5.Cu")
		(net "SYS_ERR_0")
	)
	(segment
		(start 220.194124 -78.258924)
		(end 216.6112 -81.841848)
		(width 0.127)
		(layer "In5.Cu")
		(net "SYS_ERR_0")
	)
	(segment
		(start 216.6112 -81.841848)
		(end 216.6112 -90.26271)
		(width 0.127)
		(layer "In5.Cu")
		(net "SYS_ERR_0")
	)
	(segment
		(start 224.34296 -76.701142)
		(end 222.785178 -78.258924)
		(width 0.127)
		(layer "In5.Cu")
		(net "SYS_ERR_0")
	)
	(segment
		(start 223.8248 -80.425036)
		(end 224.321878 -80.922114)
		(width 0.127)
		(layer "F.Cu")
		(net "SYS_ERROR_LED_R")
	)
	(segment
		(start 224.321878 -80.922114)
		(end 224.934272 -80.922114)
		(width 0.127)
		(layer "F.Cu")
		(net "SYS_ERROR_LED_R")
	)
	(segment
		(start 223.8248 -80.264)
		(end 223.8248 -80.425036)
		(width 0.127)
		(layer "F.Cu")
		(net "SYS_ERROR_LED_R")
	)
	(segment
		(start 224.932748 -79.69377)
		(end 224.19183 -79.69377)
		(width 0.127)
		(layer "F.Cu")
		(net "SYS_ERROR_LED_R")
	)
	(segment
		(start 224.19183 -79.69377)
		(end 223.8248 -80.0608)
		(width 0.127)
		(layer "F.Cu")
		(net "SYS_ERROR_LED_R")
	)
	(segment
		(start 223.8248 -80.0608)
		(end 223.8248 -80.264)
		(width 0.127)
		(layer "F.Cu")
		(net "SYS_ERROR_LED_R")
	)
	(via
		(at 223.8248 -80.264)
		(size 0.6604)
		(drill 0.3302)
		(layers "F.Cu" "B.Cu")
		(net "SYS_ERROR_LED_R")
	)
	(segment
		(start 227.165154 -79.590646)
		(end 227.925376 -78.830424)
		(width 0.127)
		(layer "F.Cu")
		(net "SYS_ERROR_LED_D")
	)
	(segment
		(start 227.925376 -78.830424)
		(end 227.925376 -77.924914)
		(width 0.127)
		(layer "F.Cu")
		(net "SYS_ERROR_LED_D")
	)
	(segment
		(start 224.932748 -78.16977)
		(end 226.353624 -79.590646)
		(width 0.127)
		(layer "F.Cu")
		(net "SYS_ERROR_LED_D")
	)
	(segment
		(start 226.7839 -79.590646)
		(end 227.165154 -79.590646)
		(width 0.127)
		(layer "F.Cu")
		(net "SYS_ERROR_LED_D")
	)
	(segment
		(start 226.353624 -79.590646)
		(end 226.7839 -79.590646)
		(width 0.127)
		(layer "F.Cu")
		(net "SYS_ERROR_LED_D")
	)
	(via
		(at 226.7839 -79.590646)
		(size 0.6604)
		(drill 0.3302)
		(layers "F.Cu" "B.Cu")
		(net "SYS_ERROR_LED_D")
	)
	(segment
		(start 185.928 -84.593684)
		(end 187.004452 -83.517232)
		(width 0.127)
		(layer "F.Cu")
		(net "SYS_ERROR1")
	)
	(segment
		(start 187.004452 -83.517232)
		(end 187.004452 -81.220564)
		(width 0.127)
		(layer "F.Cu")
		(net "SYS_ERROR1")
	)
	(segment
		(start 187.6044 -80.620616)
		(end 187.6044 -79.442056)
		(width 0.127)
		(layer "F.Cu")
		(net "SYS_ERROR1")
	)
	(segment
		(start 185.928 -86.7156)
		(end 185.928 -84.593684)
		(width 0.127)
		(layer "F.Cu")
		(net "SYS_ERROR1")
	)
	(segment
		(start 187.6044 -79.442056)
		(end 187.600082 -79.437738)
		(width 0.127)
		(layer "F.Cu")
		(net "SYS_ERROR1")
	)
	(segment
		(start 187.600082 -79.437738)
		(end 187.600082 -76.699872)
		(width 0.127)
		(layer "F.Cu")
		(net "SYS_ERROR1")
	)
	(segment
		(start 187.004452 -81.220564)
		(end 187.6044 -80.620616)
		(width 0.127)
		(layer "F.Cu")
		(net "SYS_ERROR1")
	)
	(segment
		(start 185.7756 -89.68105)
		(end 186.191144 -89.265506)
		(width 0.127)
		(layer "F.Cu")
		(net "SYS_DBMODE4")
	)
	(segment
		(start 188.399928 -80.903064)
		(end 188.399928 -76.699872)
		(width 0.127)
		(layer "F.Cu")
		(net "SYS_DBMODE4")
	)
	(segment
		(start 186.862466 -88.594184)
		(end 186.862466 -84.737194)
		(width 0.127)
		(layer "F.Cu")
		(net "SYS_DBMODE4")
	)
	(segment
		(start 187.766452 -83.833208)
		(end 187.766452 -81.53654)
		(width 0.127)
		(layer "F.Cu")
		(net "SYS_DBMODE4")
	)
	(segment
		(start 185.7756 -90.4113)
		(end 185.7756 -89.68105)
		(width 0.127)
		(layer "F.Cu")
		(net "SYS_DBMODE4")
	)
	(segment
		(start 187.766452 -81.53654)
		(end 188.399928 -80.903064)
		(width 0.127)
		(layer "F.Cu")
		(net "SYS_DBMODE4")
	)
	(segment
		(start 186.862466 -84.737194)
		(end 187.766452 -83.833208)
		(width 0.127)
		(layer "F.Cu")
		(net "SYS_DBMODE4")
	)
	(segment
		(start 186.191144 -89.265506)
		(end 186.862466 -88.594184)
		(width 0.127)
		(layer "F.Cu")
		(net "SYS_DBMODE4")
	)
	(via
		(at 186.191144 -89.265506)
		(size 0.6604)
		(drill 0.3302)
		(layers "F.Cu" "B.Cu")
		(net "SYS_DBMODE4")
	)
	(segment
		(start 184.87136 -90.4367)
		(end 185.3565 -89.95156)
		(width 0.127)
		(layer "F.Cu")
		(net "SYS_DBMODE3")
	)
	(segment
		(start 186.623452 -83.359244)
		(end 186.623452 -81.062576)
		(width 0.127)
		(layer "F.Cu")
		(net "SYS_DBMODE3")
	)
	(segment
		(start 185.3184 -84.664296)
		(end 186.623452 -83.359244)
		(width 0.127)
		(layer "F.Cu")
		(net "SYS_DBMODE3")
	)
	(segment
		(start 187.2234 -80.462628)
		(end 187.2234 -76.323444)
		(width 0.127)
		(layer "F.Cu")
		(net "SYS_DBMODE3")
	)
	(segment
		(start 185.3184 -84.99348)
		(end 185.3184 -84.664296)
		(width 0.127)
		(layer "F.Cu")
		(net "SYS_DBMODE3")
	)
	(segment
		(start 187.2234 -76.323444)
		(end 186.799982 -75.900026)
		(width 0.127)
		(layer "F.Cu")
		(net "SYS_DBMODE3")
	)
	(segment
		(start 184.658 -87.9475)
		(end 184.658 -85.65388)
		(width 0.127)
		(layer "F.Cu")
		(net "SYS_DBMODE3")
	)
	(segment
		(start 185.3565 -88.226392)
		(end 185.077608 -87.9475)
		(width 0.127)
		(layer "F.Cu")
		(net "SYS_DBMODE3")
	)
	(segment
		(start 186.623452 -81.062576)
		(end 187.2234 -80.462628)
		(width 0.127)
		(layer "F.Cu")
		(net "SYS_DBMODE3")
	)
	(segment
		(start 185.077608 -87.9475)
		(end 184.658 -87.9475)
		(width 0.127)
		(layer "F.Cu")
		(net "SYS_DBMODE3")
	)
	(segment
		(start 185.3565 -89.95156)
		(end 185.3565 -88.226392)
		(width 0.127)
		(layer "F.Cu")
		(net "SYS_DBMODE3")
	)
	(segment
		(start 184.921652 -85.390228)
		(end 185.3184 -84.99348)
		(width 0.127)
		(layer "F.Cu")
		(net "SYS_DBMODE3")
	)
	(segment
		(start 184.658 -85.65388)
		(end 184.921652 -85.390228)
		(width 0.127)
		(layer "F.Cu")
		(net "SYS_DBMODE3")
	)
	(segment
		(start 184.7088 -90.4367)
		(end 184.87136 -90.4367)
		(width 0.127)
		(layer "F.Cu")
		(net "SYS_DBMODE3")
	)
	(via
		(at 184.921652 -85.390228)
		(size 0.6604)
		(drill 0.3302)
		(layers "F.Cu" "B.Cu")
		(net "SYS_DBMODE3")
	)
	(segment
		(start 180.7718 -87.6935)
		(end 181.229 -87.2363)
		(width 0.127)
		(layer "F.Cu")
		(net "SYS_DBMODE2")
	)
	(segment
		(start 179.750466 -89.605866)
		(end 179.750466 -88.72347)
		(width 0.127)
		(layer "F.Cu")
		(net "SYS_DBMODE2")
	)
	(segment
		(start 180.121306 -89.976706)
		(end 180.088032 -89.976706)
		(width 0.127)
		(layer "F.Cu")
		(net "SYS_DBMODE2")
	)
	(segment
		(start 180.6067 -90.4621)
		(end 180.121306 -89.976706)
		(width 0.127)
		(layer "F.Cu")
		(net "SYS_DBMODE2")
	)
	(segment
		(start 180.088032 -89.976706)
		(end 180.088032 -89.943432)
		(width 0.127)
		(layer "F.Cu")
		(net "SYS_DBMODE2")
	)
	(segment
		(start 180.484018 -87.989918)
		(end 180.484018 -87.981282)
		(width 0.127)
		(layer "F.Cu")
		(net "SYS_DBMODE2")
	)
	(segment
		(start 185.79719 -78.95717)
		(end 185.79719 -78.03515)
		(width 0.127)
		(layer "F.Cu")
		(net "SYS_DBMODE2")
	)
	(segment
		(start 184.972452 -82.674968)
		(end 184.972452 -79.781908)
		(width 0.127)
		(layer "F.Cu")
		(net "SYS_DBMODE2")
	)
	(segment
		(start 185.999882 -77.832458)
		(end 185.999882 -76.699872)
		(width 0.127)
		(layer "F.Cu")
		(net "SYS_DBMODE2")
	)
	(segment
		(start 181.229 -86.41842)
		(end 184.972452 -82.674968)
		(width 0.127)
		(layer "F.Cu")
		(net "SYS_DBMODE2")
	)
	(segment
		(start 180.484018 -87.981282)
		(end 180.7718 -87.6935)
		(width 0.127)
		(layer "F.Cu")
		(net "SYS_DBMODE2")
	)
	(segment
		(start 185.79719 -78.03515)
		(end 185.999882 -77.832458)
		(width 0.127)
		(layer "F.Cu")
		(net "SYS_DBMODE2")
	)
	(segment
		(start 181.229 -90.4621)
		(end 180.6067 -90.4621)
		(width 0.127)
		(layer "F.Cu")
		(net "SYS_DBMODE2")
	)
	(segment
		(start 184.972452 -79.781908)
		(end 185.79719 -78.95717)
		(width 0.127)
		(layer "F.Cu")
		(net "SYS_DBMODE2")
	)
	(segment
		(start 180.088032 -89.943432)
		(end 179.750466 -89.605866)
		(width 0.127)
		(layer "F.Cu")
		(net "SYS_DBMODE2")
	)
	(segment
		(start 179.750466 -88.72347)
		(end 180.484018 -87.989918)
		(width 0.127)
		(layer "F.Cu")
		(net "SYS_DBMODE2")
	)
	(segment
		(start 181.229 -87.2363)
		(end 181.229 -86.41842)
		(width 0.127)
		(layer "F.Cu")
		(net "SYS_DBMODE2")
	)
	(via
		(at 180.088032 -89.976706)
		(size 0.6604)
		(drill 0.3302)
		(layers "F.Cu" "B.Cu")
		(net "SYS_DBMODE2")
	)
	(segment
		(start 189.686184 -77.722476)
		(end 189.686184 -78.770226)
		(width 0.127)
		(layer "F.Cu")
		(net "SYS_DBMODE1")
	)
	(segment
		(start 188.272166 -88.633046)
		(end 187.57011 -87.93099)
		(width 0.127)
		(layer "F.Cu")
		(net "SYS_DBMODE1")
	)
	(segment
		(start 187.57011 -86.576154)
		(end 187.600844 -86.54542)
		(width 0.127)
		(layer "F.Cu")
		(net "SYS_DBMODE1")
	)
	(segment
		(start 187.524644 -86.46922)
		(end 187.600844 -86.54542)
		(width 0.127)
		(layer "F.Cu")
		(net "SYS_DBMODE1")
	)
	(segment
		(start 189.200028 -76.699872)
		(end 189.200028 -77.23632)
		(width 0.127)
		(layer "F.Cu")
		(net "SYS_DBMODE1")
	)
	(segment
		(start 188.272166 -89.692734)
		(end 188.272166 -88.633046)
		(width 0.127)
		(layer "F.Cu")
		(net "SYS_DBMODE1")
	)
	(segment
		(start 188.147452 -81.694528)
		(end 188.147452 -83.991196)
		(width 0.127)
		(layer "F.Cu")
		(net "SYS_DBMODE1")
	)
	(segment
		(start 187.54471 -90.42019)
		(end 188.272166 -89.692734)
		(width 0.127)
		(layer "F.Cu")
		(net "SYS_DBMODE1")
	)
	(segment
		(start 189.200028 -77.23632)
		(end 189.686184 -77.722476)
		(width 0.127)
		(layer "F.Cu")
		(net "SYS_DBMODE1")
	)
	(segment
		(start 187.57011 -87.93099)
		(end 187.57011 -86.576154)
		(width 0.127)
		(layer "F.Cu")
		(net "SYS_DBMODE1")
	)
	(segment
		(start 188.780928 -79.675482)
		(end 188.780928 -81.061052)
		(width 0.127)
		(layer "F.Cu")
		(net "SYS_DBMODE1")
	)
	(segment
		(start 188.780928 -81.061052)
		(end 188.147452 -81.694528)
		(width 0.127)
		(layer "F.Cu")
		(net "SYS_DBMODE1")
	)
	(segment
		(start 188.147452 -83.991196)
		(end 187.524644 -84.614004)
		(width 0.127)
		(layer "F.Cu")
		(net "SYS_DBMODE1")
	)
	(segment
		(start 187.524644 -84.614004)
		(end 187.524644 -86.46922)
		(width 0.127)
		(layer "F.Cu")
		(net "SYS_DBMODE1")
	)
	(segment
		(start 189.686184 -78.770226)
		(end 188.780928 -79.675482)
		(width 0.127)
		(layer "F.Cu")
		(net "SYS_DBMODE1")
	)
	(segment
		(start 181.49316 -82.49666)
		(end 182.03926 -83.04276)
		(width 0.127)
		(layer "F.Cu")
		(net "SYS_DBMODE0")
	)
	(segment
		(start 182.03926 -83.058)
		(end 182.07736 -83.0961)
		(width 0.127)
		(layer "F.Cu")
		(net "SYS_DBMODE0")
	)
	(segment
		(start 181.37886 -82.49666)
		(end 180.37048 -82.4865)
		(width 0.127)
		(layer "F.Cu")
		(net "SYS_DBMODE0")
	)
	(segment
		(start 182.03926 -83.04276)
		(end 182.03926 -83.058)
		(width 0.127)
		(layer "F.Cu")
		(net "SYS_DBMODE0")
	)
	(segment
		(start 182.07736 -84.01812)
		(end 182.03926 -84.05622)
		(width 0.127)
		(layer "F.Cu")
		(net "SYS_DBMODE0")
	)
	(segment
		(start 180.37048 -82.4865)
		(end 180.35524 -82.50174)
		(width 0.127)
		(layer "F.Cu")
		(net "SYS_DBMODE0")
	)
	(segment
		(start 182.03926 -84.05622)
		(end 182.03926 -84.0613)
		(width 0.127)
		(layer "F.Cu")
		(net "SYS_DBMODE0")
	)
	(segment
		(start 182.03926 -84.0613)
		(end 181.9402 -84.16036)
		(width 0.127)
		(layer "F.Cu")
		(net "SYS_DBMODE0")
	)
	(segment
		(start 182.07736 -83.0961)
		(end 182.07736 -84.01812)
		(width 0.127)
		(layer "F.Cu")
		(net "SYS_DBMODE0")
	)
	(segment
		(start 181.37886 -82.49666)
		(end 181.49316 -82.49666)
		(width 0.127)
		(layer "F.Cu")
		(net "SYS_DBMODE0")
	)
	(segment
		(start 187.600082 -72.69988)
		(end 187.200286 -72.300084)
		(width 0.127)
		(layer "F.Cu")
		(net "SYS_DBMODE0")
	)
	(via
		(at 187.200286 -72.300084)
		(size 0.508)
		(drill 0.254)
		(layers "F.Cu" "B.Cu")
		(net "SYS_DBMODE0")
	)
	(via
		(at 181.9402 -84.16036)
		(size 0.508)
		(drill 0.254)
		(layers "F.Cu" "B.Cu")
		(net "SYS_DBMODE0")
	)
	(segment
		(start 186.800236 -71.900034)
		(end 187.200286 -72.300084)
		(width 0.0889)
		(layer "B.Cu")
		(net "SYS_DBMODE0")
	)
	(segment
		(start 186.800236 -71.035164)
		(end 186.800236 -71.900034)
		(width 0.0889)
		(layer "B.Cu")
		(net "SYS_DBMODE0")
	)
	(segment
		(start 187.1472 -70.6882)
		(end 186.800236 -71.035164)
		(width 0.0889)
		(layer "B.Cu")
		(net "SYS_DBMODE0")
	)
	(segment
		(start 183.580786 -73.72604)
		(end 183.580786 -74.147934)
		(width 0.127)
		(layer "In2.Cu")
		(net "SYS_DBMODE0")
	)
	(segment
		(start 183.580786 -74.147934)
		(end 181.9402 -75.78852)
		(width 0.127)
		(layer "In2.Cu")
		(net "SYS_DBMODE0")
	)
	(segment
		(start 183.925972 -73.380854)
		(end 183.580786 -73.72604)
		(width 0.127)
		(layer "In2.Cu")
		(net "SYS_DBMODE0")
	)
	(segment
		(start 187.200286 -72.300084)
		(end 186.119516 -73.380854)
		(width 0.127)
		(layer "In2.Cu")
		(net "SYS_DBMODE0")
	)
	(segment
		(start 181.9402 -75.78852)
		(end 181.9402 -84.16036)
		(width 0.127)
		(layer "In2.Cu")
		(net "SYS_DBMODE0")
	)
	(segment
		(start 186.119516 -73.380854)
		(end 183.925972 -73.380854)
		(width 0.127)
		(layer "In2.Cu")
		(net "SYS_DBMODE0")
	)
	(segment
		(start 177.546 -64.516)
		(end 177.414682 -64.647318)
		(width 0.127)
		(layer "F.Cu")
		(net "SYS_CORE_TRI#")
	)
	(segment
		(start 174.1043 -63.6397)
		(end 174.4472 -63.9826)
		(width 0.127)
		(layer "F.Cu")
		(net "SYS_CORE_TRI#")
	)
	(segment
		(start 180.191918 -64.647318)
		(end 179.8828 -64.3382)
		(width 0.127)
		(layer "F.Cu")
		(net "SYS_CORE_TRI#")
	)
	(segment
		(start 181.200044 -64.699896)
		(end 181.147466 -64.647318)
		(width 0.127)
		(layer "F.Cu")
		(net "SYS_CORE_TRI#")
	)
	(segment
		(start 178.383946 -64.516)
		(end 177.546 -64.516)
		(width 0.127)
		(layer "F.Cu")
		(net "SYS_CORE_TRI#")
	)
	(segment
		(start 175.738282 -63.9826)
		(end 176.403 -64.647318)
		(width 0.127)
		(layer "F.Cu")
		(net "SYS_CORE_TRI#")
	)
	(segment
		(start 178.561746 -64.3382)
		(end 178.383946 -64.516)
		(width 0.127)
		(layer "F.Cu")
		(net "SYS_CORE_TRI#")
	)
	(segment
		(start 179.8828 -64.3382)
		(end 178.561746 -64.3382)
		(width 0.127)
		(layer "F.Cu")
		(net "SYS_CORE_TRI#")
	)
	(segment
		(start 174.1043 -63.2714)
		(end 174.1043 -63.6397)
		(width 0.127)
		(layer "F.Cu")
		(net "SYS_CORE_TRI#")
	)
	(segment
		(start 174.4472 -63.9826)
		(end 175.738282 -63.9826)
		(width 0.127)
		(layer "F.Cu")
		(net "SYS_CORE_TRI#")
	)
	(segment
		(start 177.414682 -64.647318)
		(end 176.403 -64.647318)
		(width 0.127)
		(layer "F.Cu")
		(net "SYS_CORE_TRI#")
	)
	(segment
		(start 181.147466 -64.647318)
		(end 180.191918 -64.647318)
		(width 0.127)
		(layer "F.Cu")
		(net "SYS_CORE_TRI#")
	)
	(via
		(at 176.403 -64.647318)
		(size 0.6604)
		(drill 0.3302)
		(layers "F.Cu" "B.Cu")
		(net "SYS_CORE_TRI#")
	)
	(segment
		(start 189.999874 -72.69988)
		(end 189.600078 -72.300084)
		(width 0.127)
		(layer "F.Cu")
		(net "SPARE5")
	)
	(via
		(at 189.600078 -72.300084)
		(size 0.508)
		(drill 0.254)
		(layers "F.Cu" "B.Cu")
		(net "SPARE5")
	)
	(segment
		(start 189.600078 -72.760078)
		(end 189.992 -73.152)
		(width 0.127)
		(layer "B.Cu")
		(net "SPARE5")
	)
	(segment
		(start 189.600078 -72.300084)
		(end 189.600078 -72.760078)
		(width 0.127)
		(layer "B.Cu")
		(net "SPARE5")
	)
	(segment
		(start 178.681888 -70.669912)
		(end 178.681888 -70.182486)
		(width 0.127)
		(layer "F.Cu")
		(net "SPARE4")
	)
	(segment
		(start 181.565804 -69.133974)
		(end 181.99989 -68.699888)
		(width 0.127)
		(layer "F.Cu")
		(net "SPARE4")
	)
	(segment
		(start 177.882042 -71.901812)
		(end 177.882042 -71.469758)
		(width 0.127)
		(layer "F.Cu")
		(net "SPARE4")
	)
	(segment
		(start 179.7304 -69.133974)
		(end 181.565804 -69.133974)
		(width 0.127)
		(layer "F.Cu")
		(net "SPARE4")
	)
	(segment
		(start 177.882042 -71.469758)
		(end 178.681888 -70.669912)
		(width 0.127)
		(layer "F.Cu")
		(net "SPARE4")
	)
	(segment
		(start 178.681888 -70.182486)
		(end 179.7304 -69.133974)
		(width 0.127)
		(layer "F.Cu")
		(net "SPARE4")
	)
	(via
		(at 177.882042 -71.901812)
		(size 0.508)
		(drill 0.254)
		(layers "F.Cu" "B.Cu")
		(net "SPARE4")
	)
	(segment
		(start 177.882042 -71.901812)
		(end 177.882042 -71.157338)
		(width 0.127)
		(layer "B.Cu")
		(net "SPARE4")
	)
	(segment
		(start 177.882042 -71.157338)
		(end 177.488342 -70.763638)
		(width 0.127)
		(layer "B.Cu")
		(net "SPARE4")
	)
	(segment
		(start 189.200028 -72.69988)
		(end 188.800232 -72.300084)
		(width 0.127)
		(layer "F.Cu")
		(net "SPARE3")
	)
	(via
		(at 188.800232 -72.300084)
		(size 0.508)
		(drill 0.254)
		(layers "F.Cu" "B.Cu")
		(net "SPARE3")
	)
	(segment
		(start 189.274958 -71.825358)
		(end 188.800232 -72.300084)
		(width 0.127)
		(layer "B.Cu")
		(net "SPARE3")
	)
	(segment
		(start 190.0174 -71.4502)
		(end 189.642242 -71.825358)
		(width 0.127)
		(layer "B.Cu")
		(net "SPARE3")
	)
	(segment
		(start 189.642242 -71.825358)
		(end 189.274958 -71.825358)
		(width 0.127)
		(layer "B.Cu")
		(net "SPARE3")
	)
	(segment
		(start 187.385452 -81.378552)
		(end 187.9854 -80.778604)
		(width 0.127)
		(layer "F.Cu")
		(net "SPARE2")
	)
	(segment
		(start 186.0804 -88.1126)
		(end 186.481466 -87.711534)
		(width 0.127)
		(layer "F.Cu")
		(net "SPARE2")
	)
	(segment
		(start 186.481466 -87.711534)
		(end 186.481466 -84.579206)
		(width 0.127)
		(layer "F.Cu")
		(net "SPARE2")
	)
	(segment
		(start 187.9854 -80.778604)
		(end 187.9854 -76.285344)
		(width 0.127)
		(layer "F.Cu")
		(net "SPARE2")
	)
	(segment
		(start 187.385452 -83.67522)
		(end 187.385452 -81.378552)
		(width 0.127)
		(layer "F.Cu")
		(net "SPARE2")
	)
	(segment
		(start 187.9854 -76.285344)
		(end 187.600082 -75.900026)
		(width 0.127)
		(layer "F.Cu")
		(net "SPARE2")
	)
	(segment
		(start 186.481466 -84.579206)
		(end 187.385452 -83.67522)
		(width 0.127)
		(layer "F.Cu")
		(net "SPARE2")
	)
	(segment
		(start 184.033922 -80.672686)
		(end 184.033922 -79.705962)
		(width 0.127)
		(layer "F.Cu")
		(net "SPARE1")
	)
	(segment
		(start 185.0898 -78.650084)
		(end 185.0898 -76.810108)
		(width 0.127)
		(layer "F.Cu")
		(net "SPARE1")
	)
	(segment
		(start 185.0898 -76.810108)
		(end 185.200036 -76.699872)
		(width 0.127)
		(layer "F.Cu")
		(net "SPARE1")
	)
	(segment
		(start 183.035702 -81.670906)
		(end 184.033922 -80.672686)
		(width 0.127)
		(layer "F.Cu")
		(net "SPARE1")
	)
	(segment
		(start 184.033922 -79.705962)
		(end 185.0898 -78.650084)
		(width 0.127)
		(layer "F.Cu")
		(net "SPARE1")
	)
	(segment
		(start 183.60009 -75.099926)
		(end 183.999886 -75.499722)
		(width 0.127)
		(layer "F.Cu")
		(net "SPARE0")
	)
	(via
		(at 183.999886 -75.499722)
		(size 0.508)
		(drill 0.254)
		(layers "F.Cu" "B.Cu")
		(net "SPARE0")
	)
	(segment
		(start 183.999886 -75.499722)
		(end 183.632094 -75.867514)
		(width 0.127)
		(layer "B.Cu")
		(net "SPARE0")
	)
	(segment
		(start 183.632094 -75.867514)
		(end 183.632094 -76.449428)
		(width 0.127)
		(layer "B.Cu")
		(net "SPARE0")
	)
	(segment
		(start 204.957172 -60.402216)
		(end 204.659484 -60.699904)
		(width 0.127)
		(layer "F.Cu")
		(net "SIO_LOAD_1")
	)
	(segment
		(start 204.659484 -60.699904)
		(end 204.399896 -60.699904)
		(width 0.127)
		(layer "F.Cu")
		(net "SIO_LOAD_1")
	)
	(via
		(at 204.957172 -60.402216)
		(size 0.508)
		(drill 0.254)
		(layers "F.Cu" "B.Cu")
		(net "SIO_LOAD_1")
	)
	(segment
		(start 204.64018 -58.88482)
		(end 204.64018 -60.085224)
		(width 0.127)
		(layer "B.Cu")
		(net "SIO_LOAD_1")
	)
	(segment
		(start 204.978 -58.547)
		(end 205.7654 -57.7596)
		(width 0.127)
		(layer "B.Cu")
		(net "SIO_LOAD_1")
	)
	(segment
		(start 204.64018 -60.085224)
		(end 204.957172 -60.402216)
		(width 0.127)
		(layer "B.Cu")
		(net "SIO_LOAD_1")
	)
	(segment
		(start 204.978 -58.547)
		(end 204.64018 -58.88482)
		(width 0.127)
		(layer "B.Cu")
		(net "SIO_LOAD_1")
	)
	(segment
		(start 205.7654 -57.7596)
		(end 205.7654 -57.3913)
		(width 0.127)
		(layer "B.Cu")
		(net "SIO_LOAD_1")
	)
	(segment
		(start 203.205334 -61.904118)
		(end 203.195682 -61.904118)
		(width 0.127)
		(layer "F.Cu")
		(net "SIO_LOAD_0")
	)
	(segment
		(start 203.195682 -61.904118)
		(end 202.79995 -62.29985)
		(width 0.127)
		(layer "F.Cu")
		(net "SIO_LOAD_0")
	)
	(via
		(at 203.205334 -61.904118)
		(size 0.508)
		(drill 0.254)
		(layers "F.Cu" "B.Cu")
		(net "SIO_LOAD_0")
	)
	(segment
		(start 202.864466 -57.830466)
		(end 202.864466 -60.155582)
		(width 0.127)
		(layer "B.Cu")
		(net "SIO_LOAD_0")
	)
	(segment
		(start 203.205334 -60.49645)
		(end 203.205334 -61.904118)
		(width 0.127)
		(layer "B.Cu")
		(net "SIO_LOAD_0")
	)
	(segment
		(start 202.565 -57.531)
		(end 202.864466 -57.830466)
		(width 0.127)
		(layer "B.Cu")
		(net "SIO_LOAD_0")
	)
	(segment
		(start 203.7334 -57.3913)
		(end 202.5777 -57.3913)
		(width 0.127)
		(layer "B.Cu")
		(net "SIO_LOAD_0")
	)
	(segment
		(start 202.864466 -60.155582)
		(end 203.205334 -60.49645)
		(width 0.127)
		(layer "B.Cu")
		(net "SIO_LOAD_0")
	)
	(segment
		(start 202.5777 -57.3913)
		(end 202.565 -57.404)
		(width 0.127)
		(layer "B.Cu")
		(net "SIO_LOAD_0")
	)
	(segment
		(start 202.565 -57.404)
		(end 202.565 -57.531)
		(width 0.127)
		(layer "B.Cu")
		(net "SIO_LOAD_0")
	)
	(segment
		(start 203.999338 -61.900562)
		(end 203.60005 -62.29985)
		(width 0.127)
		(layer "F.Cu")
		(net "SIO_DOUT_1")
	)
	(segment
		(start 204.841094 -61.900562)
		(end 203.999338 -61.900562)
		(width 0.127)
		(layer "F.Cu")
		(net "SIO_DOUT_1")
	)
	(segment
		(start 204.942948 -61.798708)
		(end 204.841094 -61.900562)
		(width 0.127)
		(layer "F.Cu")
		(net "SIO_DOUT_1")
	)
	(via
		(at 204.942948 -61.798708)
		(size 0.508)
		(drill 0.254)
		(layers "F.Cu" "B.Cu")
		(net "SIO_DOUT_1")
	)
	(segment
		(start 206.018384 -61.265816)
		(end 205.47584 -61.265816)
		(width 0.127)
		(layer "B.Cu")
		(net "SIO_DOUT_1")
	)
	(segment
		(start 207.381856 -59.934856)
		(end 208.589372 -59.934856)
		(width 0.127)
		(layer "B.Cu")
		(net "SIO_DOUT_1")
	)
	(segment
		(start 207.3656 -59.9186)
		(end 206.018384 -61.265816)
		(width 0.127)
		(layer "B.Cu")
		(net "SIO_DOUT_1")
	)
	(segment
		(start 207.3656 -59.9186)
		(end 207.381856 -59.934856)
		(width 0.127)
		(layer "B.Cu")
		(net "SIO_DOUT_1")
	)
	(segment
		(start 205.47584 -61.265816)
		(end 204.942948 -61.798708)
		(width 0.127)
		(layer "B.Cu")
		(net "SIO_DOUT_1")
	)
	(segment
		(start 203.605384 -60.699904)
		(end 203.60005 -60.699904)
		(width 0.127)
		(layer "F.Cu")
		(net "SIO_DOUT_0")
	)
	(segment
		(start 204.002132 -60.303156)
		(end 203.605384 -60.699904)
		(width 0.127)
		(layer "F.Cu")
		(net "SIO_DOUT_0")
	)
	(via
		(at 204.002132 -60.303156)
		(size 0.508)
		(drill 0.254)
		(layers "F.Cu" "B.Cu")
		(net "SIO_DOUT_0")
	)
	(segment
		(start 203.708 -58.547)
		(end 204.7494 -57.5056)
		(width 0.127)
		(layer "B.Cu")
		(net "SIO_DOUT_0")
	)
	(segment
		(start 204.7494 -57.5056)
		(end 204.7494 -57.3913)
		(width 0.127)
		(layer "B.Cu")
		(net "SIO_DOUT_0")
	)
	(segment
		(start 203.708 -59.055)
		(end 203.708 -58.547)
		(width 0.127)
		(layer "B.Cu")
		(net "SIO_DOUT_0")
	)
	(segment
		(start 203.708 -59.055)
		(end 203.708 -60.009024)
		(width 0.127)
		(layer "B.Cu")
		(net "SIO_DOUT_0")
	)
	(segment
		(start 203.708 -60.009024)
		(end 204.002132 -60.303156)
		(width 0.127)
		(layer "B.Cu")
		(net "SIO_DOUT_0")
	)
	(segment
		(start 203.994766 -61.105288)
		(end 203.60005 -61.500004)
		(width 0.127)
		(layer "F.Cu")
		(net "SIO_DIN_1")
	)
	(segment
		(start 203.994766 -61.09589)
		(end 203.994766 -61.105288)
		(width 0.127)
		(layer "F.Cu")
		(net "SIO_DIN_1")
	)
	(via
		(at 203.994766 -61.09589)
		(size 0.508)
		(drill 0.254)
		(layers "F.Cu" "B.Cu")
		(net "SIO_DIN_1")
	)
	(segment
		(start 205.994 -58.801)
		(end 205.994 -59.5122)
		(width 0.127)
		(layer "B.Cu")
		(net "SIO_DIN_1")
	)
	(segment
		(start 206.7814 -57.3913)
		(end 206.7814 -58.0136)
		(width 0.127)
		(layer "B.Cu")
		(net "SIO_DIN_1")
	)
	(segment
		(start 206.7814 -58.0136)
		(end 205.994 -58.801)
		(width 0.127)
		(layer "B.Cu")
		(net "SIO_DIN_1")
	)
	(segment
		(start 205.481174 -60.559442)
		(end 205.481174 -60.025026)
		(width 0.127)
		(layer "B.Cu")
		(net "SIO_DIN_1")
	)
	(segment
		(start 204.944726 -61.09589)
		(end 205.481174 -60.559442)
		(width 0.127)
		(layer "B.Cu")
		(net "SIO_DIN_1")
	)
	(segment
		(start 205.481174 -60.025026)
		(end 205.994 -59.5122)
		(width 0.127)
		(layer "B.Cu")
		(net "SIO_DIN_1")
	)
	(segment
		(start 203.994766 -61.09589)
		(end 204.944726 -61.09589)
		(width 0.127)
		(layer "B.Cu")
		(net "SIO_DIN_1")
	)
	(segment
		(start 200.792842 -65.107058)
		(end 200.399904 -65.499996)
		(width 0.127)
		(layer "F.Cu")
		(net "SIO_DIN_0")
	)
	(segment
		(start 200.792842 -65.097406)
		(end 200.792842 -65.107058)
		(width 0.127)
		(layer "F.Cu")
		(net "SIO_DIN_0")
	)
	(via
		(at 200.792842 -65.097406)
		(size 0.508)
		(drill 0.254)
		(layers "F.Cu" "B.Cu")
		(net "SIO_DIN_0")
	)
	(segment
		(start 203.337414 -64.31788)
		(end 201.572368 -64.31788)
		(width 0.127)
		(layer "B.Cu")
		(net "SIO_DIN_0")
	)
	(segment
		(start 208.007966 -62.758066)
		(end 206.181706 -62.758066)
		(width 0.127)
		(layer "B.Cu")
		(net "SIO_DIN_0")
	)
	(segment
		(start 206.181706 -62.758066)
		(end 205.328012 -63.61176)
		(width 0.127)
		(layer "B.Cu")
		(net "SIO_DIN_0")
	)
	(segment
		(start 208.3054 -63.0555)
		(end 208.3054 -64.1604)
		(width 0.127)
		(layer "B.Cu")
		(net "SIO_DIN_0")
	)
	(segment
		(start 201.572368 -64.31788)
		(end 200.792842 -65.097406)
		(width 0.127)
		(layer "B.Cu")
		(net "SIO_DIN_0")
	)
	(segment
		(start 205.328012 -63.61176)
		(end 204.043534 -63.61176)
		(width 0.127)
		(layer "B.Cu")
		(net "SIO_DIN_0")
	)
	(segment
		(start 208.2927 -63.0428)
		(end 208.007966 -62.758066)
		(width 0.127)
		(layer "B.Cu")
		(net "SIO_DIN_0")
	)
	(segment
		(start 204.043534 -63.61176)
		(end 203.337414 -64.31788)
		(width 0.127)
		(layer "B.Cu")
		(net "SIO_DIN_0")
	)
	(segment
		(start 208.2927 -63.0428)
		(end 208.3054 -63.0555)
		(width 0.127)
		(layer "B.Cu")
		(net "SIO_DIN_0")
	)
	(segment
		(start 205.914752 -60.691776)
		(end 205.298294 -61.308234)
		(width 0.127)
		(layer "F.Cu")
		(net "SIO_CLK_1")
	)
	(segment
		(start 205.298294 -61.308234)
		(end 204.591666 -61.308234)
		(width 0.127)
		(layer "F.Cu")
		(net "SIO_CLK_1")
	)
	(segment
		(start 204.591666 -61.308234)
		(end 204.399896 -61.500004)
		(width 0.127)
		(layer "F.Cu")
		(net "SIO_CLK_1")
	)
	(via
		(at 205.914752 -60.691776)
		(size 0.508)
		(drill 0.254)
		(layers "F.Cu" "B.Cu")
		(net "SIO_CLK_1")
	)
	(segment
		(start 206.7814 -58.6486)
		(end 206.7814 -59.825128)
		(width 0.127)
		(layer "B.Cu")
		(net "SIO_CLK_1")
	)
	(segment
		(start 208.2673 -57.3913)
		(end 208.5086 -57.15)
		(width 0.127)
		(layer "B.Cu")
		(net "SIO_CLK_1")
	)
	(segment
		(start 209.0674 -57.912)
		(end 208.661 -58.3184)
		(width 0.127)
		(layer "B.Cu")
		(net "SIO_CLK_1")
	)
	(segment
		(start 207.1116 -58.3184)
		(end 206.7814 -58.6486)
		(width 0.127)
		(layer "B.Cu")
		(net "SIO_CLK_1")
	)
	(segment
		(start 208.5086 -57.15)
		(end 208.9658 -57.15)
		(width 0.127)
		(layer "B.Cu")
		(net "SIO_CLK_1")
	)
	(segment
		(start 208.661 -58.3184)
		(end 207.1116 -58.3184)
		(width 0.127)
		(layer "B.Cu")
		(net "SIO_CLK_1")
	)
	(segment
		(start 207.7974 -57.3913)
		(end 208.2673 -57.3913)
		(width 0.127)
		(layer "B.Cu")
		(net "SIO_CLK_1")
	)
	(segment
		(start 206.7814 -59.825128)
		(end 205.914752 -60.691776)
		(width 0.127)
		(layer "B.Cu")
		(net "SIO_CLK_1")
	)
	(segment
		(start 208.9658 -57.15)
		(end 209.0674 -57.2516)
		(width 0.127)
		(layer "B.Cu")
		(net "SIO_CLK_1")
	)
	(segment
		(start 209.0674 -57.2516)
		(end 209.0674 -57.912)
		(width 0.127)
		(layer "B.Cu")
		(net "SIO_CLK_1")
	)
	(segment
		(start 205.287118 -62.0522)
		(end 205.039468 -62.29985)
		(width 0.127)
		(layer "F.Cu")
		(net "SIO_CLK_0")
	)
	(segment
		(start 205.810358 -61.77026)
		(end 205.528418 -62.0522)
		(width 0.127)
		(layer "F.Cu")
		(net "SIO_CLK_0")
	)
	(segment
		(start 205.039468 -62.29985)
		(end 204.399896 -62.29985)
		(width 0.127)
		(layer "F.Cu")
		(net "SIO_CLK_0")
	)
	(segment
		(start 205.528418 -62.0522)
		(end 205.287118 -62.0522)
		(width 0.127)
		(layer "F.Cu")
		(net "SIO_CLK_0")
	)
	(via
		(at 205.810358 -61.77026)
		(size 0.508)
		(drill 0.254)
		(layers "F.Cu" "B.Cu")
		(net "SIO_CLK_0")
	)
	(segment
		(start 207.10398 -61.77026)
		(end 207.18018 -61.69406)
		(width 0.127)
		(layer "B.Cu")
		(net "SIO_CLK_0")
	)
	(segment
		(start 205.810358 -61.77026)
		(end 207.10398 -61.77026)
		(width 0.127)
		(layer "B.Cu")
		(net "SIO_CLK_0")
	)
	(segment
		(start 207.18018 -61.69406)
		(end 207.91424 -61.69406)
		(width 0.127)
		(layer "B.Cu")
		(net "SIO_CLK_0")
	)
	(segment
		(start 207.91424 -61.69406)
		(end 208.5975 -61.0108)
		(width 0.127)
		(layer "B.Cu")
		(net "SIO_CLK_0")
	)
	(segment
		(start 197.594474 -66.694304)
		(end 197.200012 -66.299842)
		(width 0.3048)
		(layer "F.Cu")
		(net "SHELL_PLL_VDD")
	)
	(segment
		(start 197.603618 -66.694304)
		(end 197.594474 -66.694304)
		(width 0.3048)
		(layer "F.Cu")
		(net "SHELL_PLL_VDD")
	)
	(via
		(at 197.603618 -66.694304)
		(size 0.508)
		(drill 0.254)
		(layers "F.Cu" "B.Cu")
		(net "SHELL_PLL_VDD")
	)
	(via
		(at 206.822548 -55.6133)
		(size 0.508)
		(drill 0.254)
		(layers "F.Cu" "B.Cu")
		(net "SHELL_PLL_VDD")
	)
	(via
		(at 206.626714 -52.566062)
		(size 0.6096)
		(drill 0.3048)
		(layers "F.Cu" "B.Cu")
		(net "SHELL_PLL_VDD")
	)
	(segment
		(start 206.626714 -52.566062)
		(end 206.822548 -52.761896)
		(width 0.508)
		(layer "B.Cu")
		(net "SHELL_PLL_VDD")
	)
	(segment
		(start 206.822548 -52.761896)
		(end 206.822548 -55.6133)
		(width 0.508)
		(layer "B.Cu")
		(net "SHELL_PLL_VDD")
	)
	(segment
		(start 200.7616 -60.99937)
		(end 200.2028 -60.44057)
		(width 0.508)
		(layer "In2.Cu")
		(net "SHELL_PLL_VDD")
	)
	(segment
		(start 205.438248 -56.9976)
		(end 206.822548 -55.6133)
		(width 0.508)
		(layer "In2.Cu")
		(net "SHELL_PLL_VDD")
	)
	(segment
		(start 200.2028 -58.0898)
		(end 201.295 -56.9976)
		(width 0.508)
		(layer "In2.Cu")
		(net "SHELL_PLL_VDD")
	)
	(segment
		(start 199.5424 -63.5)
		(end 200.7616 -62.2808)
		(width 0.508)
		(layer "In2.Cu")
		(net "SHELL_PLL_VDD")
	)
	(segment
		(start 198.9836 -63.5)
		(end 199.5424 -63.5)
		(width 0.508)
		(layer "In2.Cu")
		(net "SHELL_PLL_VDD")
	)
	(segment
		(start 201.295 -56.9976)
		(end 205.438248 -56.9976)
		(width 0.508)
		(layer "In2.Cu")
		(net "SHELL_PLL_VDD")
	)
	(segment
		(start 200.7616 -62.2808)
		(end 200.7616 -60.99937)
		(width 0.508)
		(layer "In2.Cu")
		(net "SHELL_PLL_VDD")
	)
	(segment
		(start 197.699376 -66.694304)
		(end 198.5264 -65.86728)
		(width 0.508)
		(layer "In2.Cu")
		(net "SHELL_PLL_VDD")
	)
	(segment
		(start 198.5264 -65.86728)
		(end 198.5264 -63.9572)
		(width 0.508)
		(layer "In2.Cu")
		(net "SHELL_PLL_VDD")
	)
	(segment
		(start 200.2028 -60.44057)
		(end 200.2028 -58.0898)
		(width 0.508)
		(layer "In2.Cu")
		(net "SHELL_PLL_VDD")
	)
	(segment
		(start 198.5264 -63.9572)
		(end 198.9836 -63.5)
		(width 0.508)
		(layer "In2.Cu")
		(net "SHELL_PLL_VDD")
	)
	(segment
		(start 197.603618 -66.694304)
		(end 197.699376 -66.694304)
		(width 0.508)
		(layer "In2.Cu")
		(net "SHELL_PLL_VDD")
	)
	(segment
		(start 171.571666 -75.870308)
		(end 171.571666 -61.683392)
		(width 0.127)
		(layer "F.Cu")
		(net "SBL_SDA")
	)
	(segment
		(start 206.749396 -102.853236)
		(end 205.7654 -102.853236)
		(width 0.127)
		(layer "F.Cu")
		(net "SBL_SDA")
	)
	(segment
		(start 168.960546 -79.481172)
		(end 168.960546 -78.481428)
		(width 0.127)
		(layer "F.Cu")
		(net "SBL_SDA")
	)
	(segment
		(start 171.571666 -61.683392)
		(end 172.834808 -60.42025)
		(width 0.127)
		(layer "F.Cu")
		(net "SBL_SDA")
	)
	(segment
		(start 170.294554 -80.188054)
		(end 169.667428 -80.188054)
		(width 0.127)
		(layer "F.Cu")
		(net "SBL_SDA")
	)
	(segment
		(start 175.5902 -60.642246)
		(end 176.632108 -60.642246)
		(width 0.127)
		(layer "F.Cu")
		(net "SBL_SDA")
	)
	(segment
		(start 168.960546 -78.481428)
		(end 171.571666 -75.870308)
		(width 0.127)
		(layer "F.Cu")
		(net "SBL_SDA")
	)
	(segment
		(start 181.200044 -63.09995)
		(end 180.682392 -63.09995)
		(width 0.127)
		(layer "F.Cu")
		(net "SBL_SDA")
	)
	(segment
		(start 176.759108 -60.515246)
		(end 176.759108 -60.514992)
		(width 0.127)
		(layer "F.Cu")
		(net "SBL_SDA")
	)
	(segment
		(start 207.946752 -102.41407)
		(end 207.188562 -102.41407)
		(width 0.127)
		(layer "F.Cu")
		(net "SBL_SDA")
	)
	(segment
		(start 175.368204 -60.42025)
		(end 175.5902 -60.642246)
		(width 0.127)
		(layer "F.Cu")
		(net "SBL_SDA")
	)
	(segment
		(start 170.7769 -80.6704)
		(end 170.294554 -80.188054)
		(width 0.127)
		(layer "F.Cu")
		(net "SBL_SDA")
	)
	(segment
		(start 180.682392 -63.09995)
		(end 178.543458 -60.961016)
		(width 0.127)
		(layer "F.Cu")
		(net "SBL_SDA")
	)
	(segment
		(start 178.543458 -60.961016)
		(end 177.928016 -60.961016)
		(width 0.127)
		(layer "F.Cu")
		(net "SBL_SDA")
	)
	(segment
		(start 177.1142 -60.1599)
		(end 177.1269 -60.1599)
		(width 0.127)
		(layer "F.Cu")
		(net "SBL_SDA")
	)
	(segment
		(start 207.188562 -102.41407)
		(end 206.749396 -102.853236)
		(width 0.127)
		(layer "F.Cu")
		(net "SBL_SDA")
	)
	(segment
		(start 176.632108 -60.642246)
		(end 176.759108 -60.515246)
		(width 0.127)
		(layer "F.Cu")
		(net "SBL_SDA")
	)
	(segment
		(start 177.928016 -60.961016)
		(end 177.1269 -60.1599)
		(width 0.127)
		(layer "F.Cu")
		(net "SBL_SDA")
	)
	(segment
		(start 169.667428 -80.188054)
		(end 168.960546 -79.481172)
		(width 0.127)
		(layer "F.Cu")
		(net "SBL_SDA")
	)
	(segment
		(start 172.834808 -60.42025)
		(end 175.368204 -60.42025)
		(width 0.127)
		(layer "F.Cu")
		(net "SBL_SDA")
	)
	(segment
		(start 176.759108 -60.514992)
		(end 177.1142 -60.1599)
		(width 0.127)
		(layer "F.Cu")
		(net "SBL_SDA")
	)
	(via
		(at 170.7769 -80.6704)
		(size 0.508)
		(drill 0.254)
		(layers "F.Cu" "B.Cu")
		(net "SBL_SDA")
	)
	(via
		(at 205.7654 -102.853236)
		(size 0.508)
		(drill 0.254)
		(layers "F.Cu" "B.Cu")
		(net "SBL_SDA")
	)
	(via
		(at 206.749396 -102.853236)
		(size 0.6604)
		(drill 0.3302)
		(layers "F.Cu" "B.Cu")
		(net "SBL_SDA")
	)
	(via
		(at 175.735996 -104.328214)
		(size 0.508)
		(drill 0.254)
		(layers "F.Cu" "B.Cu")
		(net "SBL_SDA")
	)
	(segment
		(start 175.33747 -104.328214)
		(end 175.735996 -104.328214)
		(width 0.127)
		(layer "In2.Cu")
		(net "SBL_SDA")
	)
	(segment
		(start 170.878246 -80.771746)
		(end 170.878246 -81.096612)
		(width 0.127)
		(layer "In2.Cu")
		(net "SBL_SDA")
	)
	(segment
		(start 170.7769 -80.6704)
		(end 170.878246 -80.771746)
		(width 0.127)
		(layer "In2.Cu")
		(net "SBL_SDA")
	)
	(segment
		(start 170.878246 -81.096612)
		(end 171.0563 -81.274666)
		(width 0.127)
		(layer "In2.Cu")
		(net "SBL_SDA")
	)
	(segment
		(start 171.0563 -81.274666)
		(end 171.0563 -100.047044)
		(width 0.127)
		(layer "In2.Cu")
		(net "SBL_SDA")
	)
	(segment
		(start 171.0563 -100.047044)
		(end 175.33747 -104.328214)
		(width 0.127)
		(layer "In2.Cu")
		(net "SBL_SDA")
	)
	(segment
		(start 204.766164 -101.854)
		(end 188.44641 -101.854)
		(width 0.127)
		(layer "In5.Cu")
		(net "SBL_SDA")
	)
	(segment
		(start 186.743086 -103.557324)
		(end 176.697132 -103.557324)
		(width 0.127)
		(layer "In5.Cu")
		(net "SBL_SDA")
	)
	(segment
		(start 176.697132 -103.557324)
		(end 175.926242 -104.328214)
		(width 0.127)
		(layer "In5.Cu")
		(net "SBL_SDA")
	)
	(segment
		(start 188.44641 -101.854)
		(end 186.743086 -103.557324)
		(width 0.127)
		(layer "In5.Cu")
		(net "SBL_SDA")
	)
	(segment
		(start 175.926242 -104.328214)
		(end 175.735996 -104.328214)
		(width 0.127)
		(layer "In5.Cu")
		(net "SBL_SDA")
	)
	(segment
		(start 205.7654 -102.853236)
		(end 204.766164 -101.854)
		(width 0.127)
		(layer "In5.Cu")
		(net "SBL_SDA")
	)
	(segment
		(start 205.763876 -101.2698)
		(end 205.826614 -101.332538)
		(width 0.127)
		(layer "F.Cu")
		(net "SBL_SCL")
	)
	(segment
		(start 176.826418 -66.480182)
		(end 177.0126 -66.294)
		(width 0.127)
		(layer "F.Cu")
		(net "SBL_SCL")
	)
	(segment
		(start 174.9171 -66.0527)
		(end 175.344582 -66.480182)
		(width 0.127)
		(layer "F.Cu")
		(net "SBL_SCL")
	)
	(segment
		(start 173.84014 -66.6369)
		(end 172.1231 -68.35394)
		(width 0.127)
		(layer "F.Cu")
		(net "SBL_SCL")
	)
	(segment
		(start 171.3865 -80.754474)
		(end 171.59097 -80.958944)
		(width 0.127)
		(layer "F.Cu")
		(net "SBL_SCL")
	)
	(segment
		(start 169.877994 -79.680054)
		(end 170.50512 -79.680054)
		(width 0.127)
		(layer "F.Cu")
		(net "SBL_SCL")
	)
	(segment
		(start 174.9171 -65.913)
		(end 174.9171 -66.0527)
		(width 0.127)
		(layer "F.Cu")
		(net "SBL_SCL")
	)
	(segment
		(start 169.468546 -78.691994)
		(end 169.468546 -79.270606)
		(width 0.127)
		(layer "F.Cu")
		(net "SBL_SCL")
	)
	(segment
		(start 179.324508 -65.129156)
		(end 179.695348 -65.499996)
		(width 0.127)
		(layer "F.Cu")
		(net "SBL_SCL")
	)
	(segment
		(start 179.695348 -65.499996)
		(end 181.200044 -65.499996)
		(width 0.127)
		(layer "F.Cu")
		(net "SBL_SCL")
	)
	(segment
		(start 174.9171 -65.913)
		(end 174.1932 -66.6369)
		(width 0.127)
		(layer "F.Cu")
		(net "SBL_SCL")
	)
	(segment
		(start 175.344582 -66.480182)
		(end 176.826418 -66.480182)
		(width 0.127)
		(layer "F.Cu")
		(net "SBL_SCL")
	)
	(segment
		(start 178.474116 -65.433956)
		(end 178.778916 -65.129156)
		(width 0.127)
		(layer "F.Cu")
		(net "SBL_SCL")
	)
	(segment
		(start 171.3865 -80.561434)
		(end 171.3865 -80.754474)
		(width 0.127)
		(layer "F.Cu")
		(net "SBL_SCL")
	)
	(segment
		(start 178.778916 -65.129156)
		(end 179.324508 -65.129156)
		(width 0.127)
		(layer "F.Cu")
		(net "SBL_SCL")
	)
	(segment
		(start 169.468546 -79.270606)
		(end 169.877994 -79.680054)
		(width 0.127)
		(layer "F.Cu")
		(net "SBL_SCL")
	)
	(segment
		(start 178.474116 -65.4685)
		(end 178.474116 -65.433956)
		(width 0.127)
		(layer "F.Cu")
		(net "SBL_SCL")
	)
	(segment
		(start 206.963518 -101.337872)
		(end 205.831948 -101.337872)
		(width 0.127)
		(layer "F.Cu")
		(net "SBL_SCL")
	)
	(segment
		(start 174.1932 -66.6369)
		(end 173.84014 -66.6369)
		(width 0.127)
		(layer "F.Cu")
		(net "SBL_SCL")
	)
	(segment
		(start 205.831948 -101.337872)
		(end 205.826614 -101.332538)
		(width 0.127)
		(layer "F.Cu")
		(net "SBL_SCL")
	)
	(segment
		(start 170.50512 -79.680054)
		(end 171.3865 -80.561434)
		(width 0.127)
		(layer "F.Cu")
		(net "SBL_SCL")
	)
	(segment
		(start 204.8256 -101.2698)
		(end 205.763876 -101.2698)
		(width 0.127)
		(layer "F.Cu")
		(net "SBL_SCL")
	)
	(segment
		(start 172.1231 -76.03744)
		(end 169.468546 -78.691994)
		(width 0.127)
		(layer "F.Cu")
		(net "SBL_SCL")
	)
	(segment
		(start 177.648616 -66.294)
		(end 178.474116 -65.4685)
		(width 0.127)
		(layer "F.Cu")
		(net "SBL_SCL")
	)
	(segment
		(start 172.1231 -68.35394)
		(end 172.1231 -76.03744)
		(width 0.127)
		(layer "F.Cu")
		(net "SBL_SCL")
	)
	(segment
		(start 177.0126 -66.294)
		(end 177.648616 -66.294)
		(width 0.127)
		(layer "F.Cu")
		(net "SBL_SCL")
	)
	(via
		(at 175.720502 -103.43134)
		(size 0.508)
		(drill 0.254)
		(layers "F.Cu" "B.Cu")
		(net "SBL_SCL")
	)
	(via
		(at 171.59097 -80.958944)
		(size 0.508)
		(drill 0.254)
		(layers "F.Cu" "B.Cu")
		(net "SBL_SCL")
	)
	(via
		(at 205.826614 -101.332538)
		(size 0.6604)
		(drill 0.3302)
		(layers "F.Cu" "B.Cu")
		(net "SBL_SCL")
	)
	(via
		(at 204.8256 -101.2698)
		(size 0.508)
		(drill 0.254)
		(layers "F.Cu" "B.Cu")
		(net "SBL_SCL")
	)
	(segment
		(start 171.5643 -99.734878)
		(end 175.152558 -103.323136)
		(width 0.127)
		(layer "In2.Cu")
		(net "SBL_SCL")
	)
	(segment
		(start 171.59097 -80.958944)
		(end 171.5643 -80.985614)
		(width 0.127)
		(layer "In2.Cu")
		(net "SBL_SCL")
	)
	(segment
		(start 175.152558 -103.323136)
		(end 175.612298 -103.323136)
		(width 0.127)
		(layer "In2.Cu")
		(net "SBL_SCL")
	)
	(segment
		(start 175.612298 -103.323136)
		(end 175.720502 -103.43134)
		(width 0.127)
		(layer "In2.Cu")
		(net "SBL_SCL")
	)
	(segment
		(start 171.5643 -80.985614)
		(end 171.5643 -99.734878)
		(width 0.127)
		(layer "In2.Cu")
		(net "SBL_SCL")
	)
	(segment
		(start 186.53252 -103.049324)
		(end 188.235844 -101.346)
		(width 0.127)
		(layer "In5.Cu")
		(net "SBL_SCL")
	)
	(segment
		(start 176.10455 -103.43134)
		(end 176.486566 -103.049324)
		(width 0.127)
		(layer "In5.Cu")
		(net "SBL_SCL")
	)
	(segment
		(start 176.486566 -103.049324)
		(end 186.53252 -103.049324)
		(width 0.127)
		(layer "In5.Cu")
		(net "SBL_SCL")
	)
	(segment
		(start 175.720502 -103.43134)
		(end 176.10455 -103.43134)
		(width 0.127)
		(layer "In5.Cu")
		(net "SBL_SCL")
	)
	(segment
		(start 204.7494 -101.346)
		(end 204.8256 -101.2698)
		(width 0.127)
		(layer "In5.Cu")
		(net "SBL_SCL")
	)
	(segment
		(start 188.235844 -101.346)
		(end 204.7494 -101.346)
		(width 0.127)
		(layer "In5.Cu")
		(net "SBL_SCL")
	)
	(segment
		(start 205.3336 -76.4286)
		(end 205.2066 -76.4286)
		(width 0.3048)
		(layer "F.Cu")
		(net "SAS0_VDDH")
	)
	(segment
		(start 204.399896 -66.299842)
		(end 205.022958 -66.299842)
		(width 0.3048)
		(layer "F.Cu")
		(net "SAS0_VDDH")
	)
	(segment
		(start 206.289656 -71.037196)
		(end 206.190596 -71.136256)
		(width 0.254)
		(layer "F.Cu")
		(net "SAS0_VDDH")
	)
	(segment
		(start 206.190596 -71.136256)
		(end 204.436218 -71.136256)
		(width 0.254)
		(layer "F.Cu")
		(net "SAS0_VDDH")
	)
	(segment
		(start 205.558898 -68.699888)
		(end 204.399896 -68.699888)
		(width 0.3048)
		(layer "F.Cu")
		(net "SAS0_VDDH")
	)
	(segment
		(start 204.436218 -71.136256)
		(end 204.399896 -71.099934)
		(width 0.254)
		(layer "F.Cu")
		(net "SAS0_VDDH")
	)
	(segment
		(start 205.430882 -73.476866)
		(end 204.42301 -73.476866)
		(width 0.3556)
		(layer "F.Cu")
		(net "SAS0_VDDH")
	)
	(segment
		(start 205.731872 -73.777856)
		(end 205.430882 -73.476866)
		(width 0.3556)
		(layer "F.Cu")
		(net "SAS0_VDDH")
	)
	(segment
		(start 200.409556 -71.099934)
		(end 200.399904 -71.099934)
		(width 0.3556)
		(layer "F.Cu")
		(net "SAS0_VDDH")
	)
	(segment
		(start 204.678026 -75.900026)
		(end 204.399896 -75.900026)
		(width 0.3048)
		(layer "F.Cu")
		(net "SAS0_VDDH")
	)
	(segment
		(start 205.760066 -68.901056)
		(end 205.558898 -68.699888)
		(width 0.3048)
		(layer "F.Cu")
		(net "SAS0_VDDH")
	)
	(segment
		(start 200.006204 -69.10324)
		(end 200.399904 -68.70954)
		(width 0.3556)
		(layer "F.Cu")
		(net "SAS0_VDDH")
	)
	(segment
		(start 205.2066 -76.4286)
		(end 204.678026 -75.900026)
		(width 0.3048)
		(layer "F.Cu")
		(net "SAS0_VDDH")
	)
	(segment
		(start 204.42301 -73.476866)
		(end 204.399896 -73.49998)
		(width 0.3556)
		(layer "F.Cu")
		(net "SAS0_VDDH")
	)
	(segment
		(start 200.399904 -68.70954)
		(end 200.399904 -68.699888)
		(width 0.3556)
		(layer "F.Cu")
		(net "SAS0_VDDH")
	)
	(segment
		(start 200.799954 -70.709536)
		(end 200.409556 -71.099934)
		(width 0.3556)
		(layer "F.Cu")
		(net "SAS0_VDDH")
	)
	(via
		(at 209.5754 -88.2142)
		(size 0.7112)
		(drill 0.4064)
		(layers "F.Cu" "B.Cu")
		(net "SAS0_VDDH")
	)
	(via
		(at 205.022958 -66.299842)
		(size 0.508)
		(drill 0.254)
		(layers "F.Cu" "B.Cu")
		(net "SAS0_VDDH")
	)
	(via
		(at 210.3374 -89.6366)
		(size 0.7112)
		(drill 0.4064)
		(layers "F.Cu" "B.Cu")
		(net "SAS0_VDDH")
	)
	(via
		(at 205.731872 -73.777856)
		(size 0.508)
		(drill 0.254)
		(layers "F.Cu" "B.Cu")
		(net "SAS0_VDDH")
	)
	(via
		(at 210.0326 -84.455)
		(size 0.7112)
		(drill 0.4064)
		(layers "F.Cu" "B.Cu")
		(net "SAS0_VDDH")
	)
	(via
		(at 205.760066 -68.901056)
		(size 0.508)
		(drill 0.254)
		(layers "F.Cu" "B.Cu")
		(net "SAS0_VDDH")
	)
	(via
		(at 209.6262 -86.3346)
		(size 0.7112)
		(drill 0.4064)
		(layers "F.Cu" "B.Cu")
		(net "SAS0_VDDH")
	)
	(via
		(at 200.006204 -69.10324)
		(size 0.508)
		(drill 0.254)
		(layers "F.Cu" "B.Cu")
		(net "SAS0_VDDH")
	)
	(via
		(at 200.799954 -70.709536)
		(size 0.508)
		(drill 0.254)
		(layers "F.Cu" "B.Cu")
		(net "SAS0_VDDH")
	)
	(via
		(at 205.3336 -76.4286)
		(size 0.508)
		(drill 0.254)
		(layers "F.Cu" "B.Cu")
		(net "SAS0_VDDH")
	)
	(via
		(at 208.43875 -87.845392)
		(size 0.6096)
		(drill 0.3048)
		(layers "F.Cu" "B.Cu")
		(net "SAS0_VDDH")
	)
	(via
		(at 206.289656 -71.037196)
		(size 0.508)
		(drill 0.254)
		(layers "F.Cu" "B.Cu")
		(net "SAS0_VDDH")
	)
	(segment
		(start 205.607666 -68.748656)
		(end 205.760066 -68.901056)
		(width 0.254)
		(layer "B.Cu")
		(net "SAS0_VDDH")
	)
	(segment
		(start 206.194406 -71.037196)
		(end 206.289656 -71.037196)
		(width 0.3048)
		(layer "B.Cu")
		(net "SAS0_VDDH")
	)
	(segment
		(start 204.690472 -68.748656)
		(end 205.607666 -68.748656)
		(width 0.254)
		(layer "B.Cu")
		(net "SAS0_VDDH")
	)
	(segment
		(start 205.887066 -70.729856)
		(end 206.194406 -71.037196)
		(width 0.3048)
		(layer "B.Cu")
		(net "SAS0_VDDH")
	)
	(segment
		(start 200.5584 -70.95109)
		(end 200.799954 -70.709536)
		(width 0.254)
		(layer "B.Cu")
		(net "SAS0_VDDH")
	)
	(segment
		(start 204.741272 -70.729856)
		(end 205.887066 -70.729856)
		(width 0.3048)
		(layer "B.Cu")
		(net "SAS0_VDDH")
	)
	(segment
		(start 200.152 -68.957444)
		(end 200.006204 -69.10324)
		(width 0.254)
		(layer "B.Cu")
		(net "SAS0_VDDH")
	)
	(segment
		(start 200.152 -68.326)
		(end 200.152 -68.957444)
		(width 0.254)
		(layer "B.Cu")
		(net "SAS0_VDDH")
	)
	(segment
		(start 200.5584 -71.247)
		(end 200.5584 -70.95109)
		(width 0.254)
		(layer "B.Cu")
		(net "SAS0_VDDH")
	)
	(segment
		(start 197.999858 -67.10934)
		(end 197.999858 -67.099942)
		(width 0.3048)
		(layer "F.Cu")
		(net "SAS0_AVDD")
	)
	(segment
		(start 199.199246 -71.491856)
		(end 199.600058 -71.892668)
		(width 0.3556)
		(layer "F.Cu")
		(net "SAS0_AVDD")
	)
	(segment
		(start 199.600058 -68.69684)
		(end 199.600058 -68.699888)
		(width 0.254)
		(layer "F.Cu")
		(net "SAS0_AVDD")
	)
	(segment
		(start 199.596502 -67.099942)
		(end 199.600058 -67.099942)
		(width 0.3048)
		(layer "F.Cu")
		(net "SAS0_AVDD")
	)
	(segment
		(start 201.99985 -73.49998)
		(end 202.397106 -73.897236)
		(width 0.254)
		(layer "F.Cu")
		(net "SAS0_AVDD")
	)
	(segment
		(start 201.99985 -68.708778)
		(end 201.99985 -68.699888)
		(width 0.3556)
		(layer "F.Cu")
		(net "SAS0_AVDD")
	)
	(segment
		(start 202.402948 -71.500492)
		(end 202.00239 -71.099934)
		(width 0.3556)
		(layer "F.Cu")
		(net "SAS0_AVDD")
	)
	(segment
		(start 202.00239 -71.099934)
		(end 201.99985 -71.099934)
		(width 0.3556)
		(layer "F.Cu")
		(net "SAS0_AVDD")
	)
	(segment
		(start 202.40625 -77.300074)
		(end 202.40625 -76.293726)
		(width 0.1778)
		(layer "F.Cu")
		(net "SAS0_AVDD")
	)
	(segment
		(start 200.009252 -69.900038)
		(end 199.609456 -70.299834)
		(width 0.3556)
		(layer "F.Cu")
		(net "SAS0_AVDD")
	)
	(segment
		(start 202.395328 -69.104256)
		(end 201.99985 -68.708778)
		(width 0.3556)
		(layer "F.Cu")
		(net "SAS0_AVDD")
	)
	(segment
		(start 199.201532 -66.704972)
		(end 199.596502 -67.099942)
		(width 0.3048)
		(layer "F.Cu")
		(net "SAS0_AVDD")
	)
	(segment
		(start 202.40625 -76.293726)
		(end 202.79995 -75.900026)
		(width 0.1778)
		(layer "F.Cu")
		(net "SAS0_AVDD")
	)
	(segment
		(start 199.609456 -70.299834)
		(end 199.600058 -70.299834)
		(width 0.3556)
		(layer "F.Cu")
		(net "SAS0_AVDD")
	)
	(segment
		(start 199.200008 -68.29679)
		(end 199.600058 -68.69684)
		(width 0.254)
		(layer "F.Cu")
		(net "SAS0_AVDD")
	)
	(segment
		(start 199.600058 -71.892668)
		(end 199.600058 -71.900034)
		(width 0.3556)
		(layer "F.Cu")
		(net "SAS0_AVDD")
	)
	(segment
		(start 198.39432 -67.503802)
		(end 197.999858 -67.10934)
		(width 0.3048)
		(layer "F.Cu")
		(net "SAS0_AVDD")
	)
	(segment
		(start 202.402948 -71.506588)
		(end 202.402948 -71.500492)
		(width 0.3556)
		(layer "F.Cu")
		(net "SAS0_AVDD")
	)
	(via
		(at 198.39432 -67.503802)
		(size 0.508)
		(drill 0.254)
		(layers "F.Cu" "B.Cu")
		(net "SAS0_AVDD")
	)
	(via
		(at 199.201532 -66.704972)
		(size 0.508)
		(drill 0.254)
		(layers "F.Cu" "B.Cu")
		(net "SAS0_AVDD")
	)
	(via
		(at 200.009252 -69.900038)
		(size 0.508)
		(drill 0.254)
		(layers "F.Cu" "B.Cu")
		(net "SAS0_AVDD")
	)
	(via
		(at 202.395328 -69.104256)
		(size 0.508)
		(drill 0.254)
		(layers "F.Cu" "B.Cu")
		(net "SAS0_AVDD")
	)
	(via
		(at 199.200008 -68.29679)
		(size 0.508)
		(drill 0.254)
		(layers "F.Cu" "B.Cu")
		(net "SAS0_AVDD")
	)
	(via
		(at 210.09483 -92.364052)
		(size 0.7112)
		(drill 0.4064)
		(layers "F.Cu" "B.Cu")
		(net "SAS0_AVDD")
	)
	(via
		(at 210.056222 -91.14536)
		(size 0.7112)
		(drill 0.4064)
		(layers "F.Cu" "B.Cu")
		(net "SAS0_AVDD")
	)
	(via
		(at 208.661508 -91.022424)
		(size 0.7112)
		(drill 0.4064)
		(layers "F.Cu" "B.Cu")
		(net "SAS0_AVDD")
	)
	(via
		(at 199.199246 -71.491856)
		(size 0.508)
		(drill 0.254)
		(layers "F.Cu" "B.Cu")
		(net "SAS0_AVDD")
	)
	(via
		(at 214.279226 -96.094804)
		(size 0.6604)
		(drill 0.3302)
		(layers "F.Cu" "B.Cu")
		(net "SAS0_AVDD")
	)
	(via
		(at 202.402948 -71.506588)
		(size 0.508)
		(drill 0.254)
		(layers "F.Cu" "B.Cu")
		(net "SAS0_AVDD")
	)
	(via
		(at 220.370908 -93.484192)
		(size 0.6604)
		(drill 0.3302)
		(layers "F.Cu" "B.Cu")
		(net "SAS0_AVDD")
	)
	(via
		(at 202.397106 -73.897236)
		(size 0.508)
		(drill 0.254)
		(layers "F.Cu" "B.Cu")
		(net "SAS0_AVDD")
	)
	(via
		(at 202.40625 -77.300074)
		(size 0.508)
		(drill 0.254)
		(layers "F.Cu" "B.Cu")
		(net "SAS0_AVDD")
	)
	(via
		(at 208.699862 -92.325952)
		(size 0.7112)
		(drill 0.4064)
		(layers "F.Cu" "B.Cu")
		(net "SAS0_AVDD")
	)
	(segment
		(start 199.445118 -71.685658)
		(end 199.393048 -71.685658)
		(width 0.254)
		(layer "B.Cu")
		(net "SAS0_AVDD")
	)
	(segment
		(start 203.38288 -69.596)
		(end 202.887072 -69.596)
		(width 0.254)
		(layer "B.Cu")
		(net "SAS0_AVDD")
	)
	(segment
		(start 203.0476 -77.941424)
		(end 202.40625 -77.300074)
		(width 0.254)
		(layer "B.Cu")
		(net "SAS0_AVDD")
	)
	(segment
		(start 204.1652 -69.5452)
		(end 203.43368 -69.5452)
		(width 0.254)
		(layer "B.Cu")
		(net "SAS0_AVDD")
	)
	(segment
		(start 199.48906 -67.56654)
		(end 198.457058 -67.56654)
		(width 0.3048)
		(layer "B.Cu")
		(net "SAS0_AVDD")
	)
	(segment
		(start 202.887072 -69.596)
		(end 202.395328 -69.104256)
		(width 0.254)
		(layer "B.Cu")
		(net "SAS0_AVDD")
	)
	(segment
		(start 203.0349 -74.551032)
		(end 202.397106 -73.913238)
		(width 0.254)
		(layer "B.Cu")
		(net "SAS0_AVDD")
	)
	(segment
		(start 199.64908 -71.88962)
		(end 199.445118 -71.685658)
		(width 0.254)
		(layer "B.Cu")
		(net "SAS0_AVDD")
	)
	(segment
		(start 203.0476 -77.978)
		(end 203.0476 -77.941424)
		(width 0.254)
		(layer "B.Cu")
		(net "SAS0_AVDD")
	)
	(segment
		(start 198.457058 -67.56654)
		(end 198.39432 -67.503802)
		(width 0.3048)
		(layer "B.Cu")
		(net "SAS0_AVDD")
	)
	(segment
		(start 198.693532 -66.704972)
		(end 199.201532 -66.704972)
		(width 0.254)
		(layer "B.Cu")
		(net "SAS0_AVDD")
	)
	(segment
		(start 199.733408 -66.704972)
		(end 199.86752 -66.57086)
		(width 0.254)
		(layer "B.Cu")
		(net "SAS0_AVDD")
	)
	(segment
		(start 203.0476 -78.613)
		(end 203.0476 -77.978)
		(width 0.254)
		(layer "B.Cu")
		(net "SAS0_AVDD")
	)
	(segment
		(start 199.201532 -66.704972)
		(end 199.733408 -66.704972)
		(width 0.254)
		(layer "B.Cu")
		(net "SAS0_AVDD")
	)
	(segment
		(start 198.56196 -68.33362)
		(end 199.163178 -68.33362)
		(width 0.3048)
		(layer "B.Cu")
		(net "SAS0_AVDD")
	)
	(segment
		(start 203.807568 -74.551032)
		(end 203.0349 -74.551032)
		(width 0.254)
		(layer "B.Cu")
		(net "SAS0_AVDD")
	)
	(segment
		(start 199.163178 -68.33362)
		(end 199.200008 -68.29679)
		(width 0.3048)
		(layer "B.Cu")
		(net "SAS0_AVDD")
	)
	(segment
		(start 198.52132 -66.53276)
		(end 198.693532 -66.704972)
		(width 0.254)
		(layer "B.Cu")
		(net "SAS0_AVDD")
	)
	(segment
		(start 203.43368 -69.5452)
		(end 203.38288 -69.596)
		(width 0.254)
		(layer "B.Cu")
		(net "SAS0_AVDD")
	)
	(segment
		(start 202.397106 -73.913238)
		(end 202.397106 -73.897236)
		(width 0.254)
		(layer "B.Cu")
		(net "SAS0_AVDD")
	)
	(segment
		(start 199.393048 -71.685658)
		(end 199.199246 -71.491856)
		(width 0.254)
		(layer "B.Cu")
		(net "SAS0_AVDD")
	)
	(segment
		(start 203.9874 -74.3712)
		(end 203.807568 -74.551032)
		(width 0.254)
		(layer "B.Cu")
		(net "SAS0_AVDD")
	)
	(segment
		(start 203.192888 -65.102486)
		(end 203.590398 -65.499996)
		(width 0.127)
		(layer "F.Cu")
		(net "RTRIM#")
	)
	(segment
		(start 203.590398 -65.499996)
		(end 203.60005 -65.499996)
		(width 0.127)
		(layer "F.Cu")
		(net "RTRIM#")
	)
	(via
		(at 203.192888 -65.102486)
		(size 0.508)
		(drill 0.254)
		(layers "F.Cu" "B.Cu")
		(net "RTRIM#")
	)
	(via
		(at 202.88758 -65.913)
		(size 0.6096)
		(drill 0.3048)
		(layers "F.Cu" "B.Cu")
		(net "RTRIM#")
	)
	(segment
		(start 202.88758 -65.407794)
		(end 203.192888 -65.102486)
		(width 0.127)
		(layer "B.Cu")
		(net "RTRIM#")
	)
	(segment
		(start 202.88758 -65.913)
		(end 202.88758 -65.407794)
		(width 0.127)
		(layer "B.Cu")
		(net "RTRIM#")
	)
	(segment
		(start 204.498956 -64.798956)
		(end 204.390244 -64.690244)
		(width 0.127)
		(layer "B.Cu")
		(net "RTRIM#")
	)
	(segment
		(start 205.9813 -65.4812)
		(end 205.299056 -64.798956)
		(width 0.127)
		(layer "B.Cu")
		(net "RTRIM#")
	)
	(segment
		(start 205.299056 -64.798956)
		(end 204.498956 -64.798956)
		(width 0.127)
		(layer "B.Cu")
		(net "RTRIM#")
	)
	(segment
		(start 204.390244 -64.690244)
		(end 203.705714 -64.690244)
		(width 0.127)
		(layer "B.Cu")
		(net "RTRIM#")
	)
	(segment
		(start 203.293472 -65.102486)
		(end 203.192888 -65.102486)
		(width 0.127)
		(layer "B.Cu")
		(net "RTRIM#")
	)
	(segment
		(start 203.705714 -64.690244)
		(end 203.293472 -65.102486)
		(width 0.127)
		(layer "B.Cu")
		(net "RTRIM#")
	)
	(segment
		(start 204.0001 -65.109344)
		(end 204.009244 -65.109344)
		(width 0.127)
		(layer "F.Cu")
		(net "RTRIM")
	)
	(segment
		(start 204.009244 -65.109344)
		(end 204.399896 -65.499996)
		(width 0.127)
		(layer "F.Cu")
		(net "RTRIM")
	)
	(via
		(at 204.0001 -65.109344)
		(size 0.508)
		(drill 0.254)
		(layers "F.Cu" "B.Cu")
		(net "RTRIM")
	)
	(via
		(at 205.867 -66.6496)
		(size 0.6096)
		(drill 0.3048)
		(layers "F.Cu" "B.Cu")
		(net "RTRIM")
	)
	(segment
		(start 203.58354 -65.525904)
		(end 203.58354 -66.075052)
		(width 0.127)
		(layer "B.Cu")
		(net "RTRIM")
	)
	(segment
		(start 206.8703 -65.6463)
		(end 206.8703 -65.4812)
		(width 0.127)
		(layer "B.Cu")
		(net "RTRIM")
	)
	(segment
		(start 204.22743 -66.718942)
		(end 205.797658 -66.718942)
		(width 0.127)
		(layer "B.Cu")
		(net "RTRIM")
	)
	(segment
		(start 204.0001 -65.109344)
		(end 203.58354 -65.525904)
		(width 0.127)
		(layer "B.Cu")
		(net "RTRIM")
	)
	(segment
		(start 205.797658 -66.718942)
		(end 205.867 -66.6496)
		(width 0.127)
		(layer "B.Cu")
		(net "RTRIM")
	)
	(segment
		(start 203.58354 -66.075052)
		(end 204.22743 -66.718942)
		(width 0.127)
		(layer "B.Cu")
		(net "RTRIM")
	)
	(segment
		(start 205.867 -66.6496)
		(end 206.8703 -65.6463)
		(width 0.127)
		(layer "B.Cu")
		(net "RTRIM")
	)
	(segment
		(start 224.3074 -57.0611)
		(end 225.9965 -57.0611)
		(width 0.127)
		(layer "F.Cu")
		(net "REF_CLK")
	)
	(segment
		(start 226.682046 -57.746646)
		(end 226.682046 -58.666888)
		(width 0.127)
		(layer "F.Cu")
		(net "REF_CLK")
	)
	(segment
		(start 224.259902 -58.101992)
		(end 224.259902 -57.108598)
		(width 0.127)
		(layer "F.Cu")
		(net "REF_CLK")
	)
	(segment
		(start 225.9965 -57.0611)
		(end 226.682046 -57.746646)
		(width 0.127)
		(layer "F.Cu")
		(net "REF_CLK")
	)
	(segment
		(start 224.259902 -57.108598)
		(end 224.3074 -57.0611)
		(width 0.127)
		(layer "F.Cu")
		(net "REF_CLK")
	)
	(segment
		(start 72.846438 -131.196588)
		(end 70.212712 -131.196588)
		(width 0.127)
		(layer "F.Cu")
		(net "PWRBTN_OUT_N")
	)
	(segment
		(start 70.212712 -131.196588)
		(end 68.4784 -132.9309)
		(width 0.127)
		(layer "F.Cu")
		(net "PWRBTN_OUT_N")
	)
	(segment
		(start 68.4784 -132.9309)
		(end 68.4784 -134.1247)
		(width 0.127)
		(layer "F.Cu")
		(net "PWRBTN_OUT_N")
	)
	(via
		(at 51.71694 -134.466838)
		(size 0.508)
		(drill 0.254)
		(layers "F.Cu" "B.Cu")
		(net "PWRBTN_OUT_N")
	)
	(via
		(at 72.846438 -131.196588)
		(size 0.508)
		(drill 0.254)
		(layers "F.Cu" "B.Cu")
		(net "PWRBTN_OUT_N")
	)
	(via
		(at 68.4784 -132.9309)
		(size 0.6604)
		(drill 0.3302)
		(layers "F.Cu" "B.Cu")
		(net "PWRBTN_OUT_N")
	)
	(segment
		(start 51.4858 -135.2931)
		(end 51.4858 -134.697978)
		(width 0.127)
		(layer "B.Cu")
		(net "PWRBTN_OUT_N")
	)
	(segment
		(start 51.4858 -134.697978)
		(end 51.71694 -134.466838)
		(width 0.127)
		(layer "B.Cu")
		(net "PWRBTN_OUT_N")
	)
	(segment
		(start 65.821052 -131.566666)
		(end 65.752218 -131.6355)
		(width 0.127)
		(layer "In5.Cu")
		(net "PWRBTN_OUT_N")
	)
	(segment
		(start 64.3636 -132.461)
		(end 59.622436 -132.461)
		(width 0.127)
		(layer "In5.Cu")
		(net "PWRBTN_OUT_N")
	)
	(segment
		(start 65.1891 -131.6355)
		(end 64.3636 -132.461)
		(width 0.127)
		(layer "In5.Cu")
		(net "PWRBTN_OUT_N")
	)
	(segment
		(start 58.123836 -133.9596)
		(end 52.224178 -133.9596)
		(width 0.127)
		(layer "In5.Cu")
		(net "PWRBTN_OUT_N")
	)
	(segment
		(start 67.636136 -131.567174)
		(end 67.635628 -131.566666)
		(width 0.127)
		(layer "In5.Cu")
		(net "PWRBTN_OUT_N")
	)
	(segment
		(start 67.635628 -131.566666)
		(end 65.821052 -131.566666)
		(width 0.127)
		(layer "In5.Cu")
		(net "PWRBTN_OUT_N")
	)
	(segment
		(start 72.475852 -131.567174)
		(end 67.636136 -131.567174)
		(width 0.127)
		(layer "In5.Cu")
		(net "PWRBTN_OUT_N")
	)
	(segment
		(start 72.846438 -131.196588)
		(end 72.475852 -131.567174)
		(width 0.127)
		(layer "In5.Cu")
		(net "PWRBTN_OUT_N")
	)
	(segment
		(start 52.224178 -133.9596)
		(end 51.71694 -134.466838)
		(width 0.127)
		(layer "In5.Cu")
		(net "PWRBTN_OUT_N")
	)
	(segment
		(start 59.622436 -132.461)
		(end 58.123836 -133.9596)
		(width 0.127)
		(layer "In5.Cu")
		(net "PWRBTN_OUT_N")
	)
	(segment
		(start 65.752218 -131.6355)
		(end 65.1891 -131.6355)
		(width 0.127)
		(layer "In5.Cu")
		(net "PWRBTN_OUT_N")
	)
	(segment
		(start 67.480434 -116.3828)
		(end 66.947034 -116.9162)
		(width 0.127)
		(layer "F.Cu")
		(net "PU_IBMC_BT_HOLD_N")
	)
	(segment
		(start 66.947034 -116.9162)
		(end 65.806066 -116.9162)
		(width 0.127)
		(layer "F.Cu")
		(net "PU_IBMC_BT_HOLD_N")
	)
	(segment
		(start 68.0593 -116.3828)
		(end 67.480434 -116.3828)
		(width 0.127)
		(layer "F.Cu")
		(net "PU_IBMC_BT_HOLD_N")
	)
	(segment
		(start 200.399904 -64.699896)
		(end 200.7997 -64.3001)
		(width 0.127)
		(layer "F.Cu")
		(net "POWERLOSS#")
	)
	(via
		(at 200.7997 -64.3001)
		(size 0.508)
		(drill 0.254)
		(layers "F.Cu" "B.Cu")
		(net "POWERLOSS#")
	)
	(via
		(at 200.09358 -64.68364)
		(size 0.6096)
		(drill 0.3048)
		(layers "F.Cu" "B.Cu")
		(net "POWERLOSS#")
	)
	(segment
		(start 200.43648 -64.66332)
		(end 200.7997 -64.3001)
		(width 0.127)
		(layer "B.Cu")
		(net "POWERLOSS#")
	)
	(segment
		(start 200.09358 -63.82766)
		(end 200.09358 -64.68364)
		(width 0.127)
		(layer "B.Cu")
		(net "POWERLOSS#")
	)
	(segment
		(start 199.75576 -63.46952)
		(end 200.0758 -63.80988)
		(width 0.127)
		(layer "B.Cu")
		(net "POWERLOSS#")
	)
	(segment
		(start 200.1139 -64.66332)
		(end 200.43648 -64.66332)
		(width 0.127)
		(layer "B.Cu")
		(net "POWERLOSS#")
	)
	(segment
		(start 200.09358 -64.68364)
		(end 200.1139 -64.66332)
		(width 0.127)
		(layer "B.Cu")
		(net "POWERLOSS#")
	)
	(segment
		(start 200.0758 -63.80988)
		(end 200.09358 -63.82766)
		(width 0.127)
		(layer "B.Cu")
		(net "POWERLOSS#")
	)
	(segment
		(start 186.799982 -69.499988)
		(end 186.400186 -69.100192)
		(width 0.3048)
		(layer "F.Cu")
		(net "PLL_VDD")
	)
	(via
		(at 175.407066 -76.190856)
		(size 0.508)
		(drill 0.254)
		(layers "F.Cu" "B.Cu")
		(net "PLL_VDD")
	)
	(via
		(at 186.400186 -69.100192)
		(size 0.508)
		(drill 0.254)
		(layers "F.Cu" "B.Cu")
		(net "PLL_VDD")
	)
	(via
		(at 174.425356 -75.805792)
		(size 0.6096)
		(drill 0.3048)
		(layers "F.Cu" "B.Cu")
		(net "PLL_VDD")
	)
	(segment
		(start 175.407066 -76.190856)
		(end 177.947066 -73.650856)
		(width 0.508)
		(layer "In2.Cu")
		(net "PLL_VDD")
	)
	(segment
		(start 184.047384 -73.025)
		(end 184.8612 -72.211184)
		(width 0.381)
		(layer "In2.Cu")
		(net "PLL_VDD")
	)
	(segment
		(start 185.346086 -70.181978)
		(end 186.400186 -69.127878)
		(width 0.381)
		(layer "In2.Cu")
		(net "PLL_VDD")
	)
	(segment
		(start 186.400186 -69.127878)
		(end 186.400186 -69.100192)
		(width 0.381)
		(layer "In2.Cu")
		(net "PLL_VDD")
	)
	(segment
		(start 184.8612 -71.411084)
		(end 185.346086 -70.926198)
		(width 0.381)
		(layer "In2.Cu")
		(net "PLL_VDD")
	)
	(segment
		(start 183.225186 -73.84923)
		(end 183.225186 -73.57872)
		(width 0.381)
		(layer "In2.Cu")
		(net "PLL_VDD")
	)
	(segment
		(start 185.346086 -70.926198)
		(end 185.346086 -70.181978)
		(width 0.381)
		(layer "In2.Cu")
		(net "PLL_VDD")
	)
	(segment
		(start 179.865782 -73.650856)
		(end 180.459126 -74.2442)
		(width 0.508)
		(layer "In2.Cu")
		(net "PLL_VDD")
	)
	(segment
		(start 184.8612 -72.211184)
		(end 184.8612 -71.411084)
		(width 0.381)
		(layer "In2.Cu")
		(net "PLL_VDD")
	)
	(segment
		(start 180.665882 -74.450956)
		(end 182.62346 -74.450956)
		(width 0.381)
		(layer "In2.Cu")
		(net "PLL_VDD")
	)
	(segment
		(start 183.778906 -73.025)
		(end 184.047384 -73.025)
		(width 0.381)
		(layer "In2.Cu")
		(net "PLL_VDD")
	)
	(segment
		(start 182.62346 -74.450956)
		(end 183.225186 -73.84923)
		(width 0.381)
		(layer "In2.Cu")
		(net "PLL_VDD")
	)
	(segment
		(start 183.225186 -73.57872)
		(end 183.778906 -73.025)
		(width 0.381)
		(layer "In2.Cu")
		(net "PLL_VDD")
	)
	(segment
		(start 177.947066 -73.650856)
		(end 179.865782 -73.650856)
		(width 0.508)
		(layer "In2.Cu")
		(net "PLL_VDD")
	)
	(segment
		(start 180.459126 -74.2442)
		(end 180.665882 -74.450956)
		(width 0.381)
		(layer "In2.Cu")
		(net "PLL_VDD")
	)
	(segment
		(start 26.3652 -144.907)
		(end 26.335482 -144.877282)
		(width 0.127)
		(layer "F.Cu")
		(net "PD_ZQ")
	)
	(segment
		(start 24.6253 -144.56156)
		(end 23.234396 -144.56156)
		(width 0.127)
		(layer "F.Cu")
		(net "PD_ZQ")
	)
	(segment
		(start 27.5844 -144.907)
		(end 26.3652 -144.907)
		(width 0.127)
		(layer "F.Cu")
		(net "PD_ZQ")
	)
	(segment
		(start 24.941022 -144.877282)
		(end 24.6253 -144.56156)
		(width 0.127)
		(layer "F.Cu")
		(net "PD_ZQ")
	)
	(segment
		(start 26.335482 -144.877282)
		(end 24.941022 -144.877282)
		(width 0.127)
		(layer "F.Cu")
		(net "PD_ZQ")
	)
	(via
		(at 26.3652 -144.907)
		(size 0.6604)
		(drill 0.3302)
		(layers "F.Cu" "B.Cu")
		(net "PD_ZQ")
	)
	(segment
		(start 48.50003 -137.799826)
		(end 48.09998 -138.199876)
		(width 0.127)
		(layer "F.Cu")
		(net "PD_PERST_N")
	)
	(via
		(at 48.5394 -137.0838)
		(size 0.6096)
		(drill 0.3048)
		(layers "F.Cu" "B.Cu")
		(net "PD_PERST_N")
	)
	(via
		(at 48.50003 -137.799826)
		(size 0.4572)
		(drill 0.2032)
		(layers "F.Cu" "B.Cu")
		(net "PD_PERST_N")
	)
	(segment
		(start 48.50003 -137.799826)
		(end 48.6156 -137.684256)
		(width 0.127)
		(layer "B.Cu")
		(net "PD_PERST_N")
	)
	(segment
		(start 48.6156 -137.684256)
		(end 48.6156 -137.16)
		(width 0.127)
		(layer "B.Cu")
		(net "PD_PERST_N")
	)
	(segment
		(start 47.4726 -136.1821)
		(end 47.6377 -136.1821)
		(width 0.127)
		(layer "B.Cu")
		(net "PD_PERST_N")
	)
	(segment
		(start 47.6377 -136.1821)
		(end 48.5394 -137.0838)
		(width 0.127)
		(layer "B.Cu")
		(net "PD_PERST_N")
	)
	(segment
		(start 48.6156 -137.16)
		(end 48.5394 -137.0838)
		(width 0.127)
		(layer "B.Cu")
		(net "PD_PERST_N")
	)
	(segment
		(start 196.398388 -71.099934)
		(end 196.399912 -71.099934)
		(width 0.3048)
		(layer "F.Cu")
		(net "PCE_AVDD")
	)
	(segment
		(start 197.999858 -71.900288)
		(end 197.999858 -71.900034)
		(width 0.3556)
		(layer "F.Cu")
		(net "PCE_AVDD")
	)
	(segment
		(start 195.521072 -77.333856)
		(end 195.600066 -77.254862)
		(width 0.3048)
		(layer "F.Cu")
		(net "PCE_AVDD")
	)
	(segment
		(start 197.999858 -76.972414)
		(end 197.999858 -76.699872)
		(width 0.3048)
		(layer "F.Cu")
		(net "PCE_AVDD")
	)
	(segment
		(start 196.399912 -71.890382)
		(end 196.003926 -71.494396)
		(width 0.3048)
		(layer "F.Cu")
		(net "PCE_AVDD")
	)
	(segment
		(start 196.003926 -71.494396)
		(end 196.398388 -71.099934)
		(width 0.3048)
		(layer "F.Cu")
		(net "PCE_AVDD")
	)
	(segment
		(start 194.403726 -71.494396)
		(end 194.799966 -71.890636)
		(width 0.3048)
		(layer "F.Cu")
		(net "PCE_AVDD")
	)
	(segment
		(start 193.199258 -71.900034)
		(end 193.20002 -71.900034)
		(width 0.3048)
		(layer "F.Cu")
		(net "PCE_AVDD")
	)
	(segment
		(start 190.453264 -77.046582)
		(end 190.799974 -76.699872)
		(width 0.3048)
		(layer "F.Cu")
		(net "PCE_AVDD")
	)
	(segment
		(start 197.55866 -77.413612)
		(end 197.999858 -76.972414)
		(width 0.3048)
		(layer "F.Cu")
		(net "PCE_AVDD")
	)
	(segment
		(start 198.40448 -72.30491)
		(end 197.999858 -71.900288)
		(width 0.3556)
		(layer "F.Cu")
		(net "PCE_AVDD")
	)
	(segment
		(start 196.399912 -71.900034)
		(end 196.399912 -71.890382)
		(width 0.3048)
		(layer "F.Cu")
		(net "PCE_AVDD")
	)
	(segment
		(start 193.20002 -76.926948)
		(end 193.20002 -76.699872)
		(width 0.3048)
		(layer "F.Cu")
		(net "PCE_AVDD")
	)
	(segment
		(start 190.453264 -77.143864)
		(end 190.453264 -77.046582)
		(width 0.3048)
		(layer "F.Cu")
		(net "PCE_AVDD")
	)
	(segment
		(start 192.838832 -77.288136)
		(end 193.20002 -76.926948)
		(width 0.3048)
		(layer "F.Cu")
		(net "PCE_AVDD")
	)
	(segment
		(start 200.399904 -76.696824)
		(end 200.399904 -76.699872)
		(width 0.3048)
		(layer "F.Cu")
		(net "PCE_AVDD")
	)
	(segment
		(start 195.600066 -77.254862)
		(end 195.600066 -76.699872)
		(width 0.3048)
		(layer "F.Cu")
		(net "PCE_AVDD")
	)
	(segment
		(start 192.80378 -71.504556)
		(end 193.199258 -71.900034)
		(width 0.3048)
		(layer "F.Cu")
		(net "PCE_AVDD")
	)
	(segment
		(start 200.793604 -76.303124)
		(end 200.399904 -76.696824)
		(width 0.3048)
		(layer "F.Cu")
		(net "PCE_AVDD")
	)
	(segment
		(start 194.799966 -71.890636)
		(end 194.799966 -71.900034)
		(width 0.3048)
		(layer "F.Cu")
		(net "PCE_AVDD")
	)
	(via
		(at 192.838832 -77.288136)
		(size 0.508)
		(drill 0.254)
		(layers "F.Cu" "B.Cu")
		(net "PCE_AVDD")
	)
	(via
		(at 190.453264 -77.143864)
		(size 0.508)
		(drill 0.254)
		(layers "F.Cu" "B.Cu")
		(net "PCE_AVDD")
	)
	(via
		(at 198.40448 -72.30491)
		(size 0.508)
		(drill 0.254)
		(layers "F.Cu" "B.Cu")
		(net "PCE_AVDD")
	)
	(via
		(at 176.092358 -79.589376)
		(size 0.6096)
		(drill 0.3048)
		(layers "F.Cu" "B.Cu")
		(net "PCE_AVDD")
	)
	(via
		(at 181.173882 -79.244952)
		(size 0.7112)
		(drill 0.4064)
		(layers "F.Cu" "B.Cu")
		(net "PCE_AVDD")
	)
	(via
		(at 179.954682 -79.244952)
		(size 0.7112)
		(drill 0.4064)
		(layers "F.Cu" "B.Cu")
		(net "PCE_AVDD")
	)
	(via
		(at 200.793604 -76.303124)
		(size 0.508)
		(drill 0.254)
		(layers "F.Cu" "B.Cu")
		(net "PCE_AVDD")
	)
	(via
		(at 192.80378 -71.504556)
		(size 0.508)
		(drill 0.254)
		(layers "F.Cu" "B.Cu")
		(net "PCE_AVDD")
	)
	(via
		(at 197.55866 -77.413612)
		(size 0.508)
		(drill 0.254)
		(layers "F.Cu" "B.Cu")
		(net "PCE_AVDD")
	)
	(via
		(at 194.403726 -71.494396)
		(size 0.508)
		(drill 0.254)
		(layers "F.Cu" "B.Cu")
		(net "PCE_AVDD")
	)
	(via
		(at 195.521072 -77.333856)
		(size 0.508)
		(drill 0.254)
		(layers "F.Cu" "B.Cu")
		(net "PCE_AVDD")
	)
	(via
		(at 196.003926 -71.494396)
		(size 0.508)
		(drill 0.254)
		(layers "F.Cu" "B.Cu")
		(net "PCE_AVDD")
	)
	(segment
		(start 196.729604 -71.494396)
		(end 196.003926 -71.494396)
		(width 0.3048)
		(layer "B.Cu")
		(net "PCE_AVDD")
	)
	(segment
		(start 198.1454 -71.11492)
		(end 198.1454 -72.04583)
		(width 0.3048)
		(layer "B.Cu")
		(net "PCE_AVDD")
	)
	(segment
		(start 195.7832 -77.071728)
		(end 195.521072 -77.333856)
		(width 0.254)
		(layer "B.Cu")
		(net "PCE_AVDD")
	)
	(segment
		(start 193.194432 -71.895208)
		(end 192.80378 -71.504556)
		(width 0.254)
		(layer "B.Cu")
		(net "PCE_AVDD")
	)
	(segment
		(start 198.1454 -72.04583)
		(end 198.40448 -72.30491)
		(width 0.3048)
		(layer "B.Cu")
		(net "PCE_AVDD")
	)
	(segment
		(start 195.7832 -76.7334)
		(end 195.7832 -77.071728)
		(width 0.254)
		(layer "B.Cu")
		(net "PCE_AVDD")
	)
	(segment
		(start 197.5358 -77.436472)
		(end 197.55866 -77.413612)
		(width 0.254)
		(layer "B.Cu")
		(net "PCE_AVDD")
	)
	(segment
		(start 196.9008 -71.3232)
		(end 196.729604 -71.494396)
		(width 0.3048)
		(layer "B.Cu")
		(net "PCE_AVDD")
	)
	(segment
		(start 198.1454 -70.18782)
		(end 198.1454 -71.11492)
		(width 0.3048)
		(layer "B.Cu")
		(net "PCE_AVDD")
	)
	(segment
		(start 200.8632 -75.6158)
		(end 200.8632 -76.233528)
		(width 0.254)
		(layer "B.Cu")
		(net "PCE_AVDD")
	)
	(segment
		(start 197.5358 -78.0542)
		(end 197.5358 -77.436472)
		(width 0.254)
		(layer "B.Cu")
		(net "PCE_AVDD")
	)
	(segment
		(start 198.22414 -70.10908)
		(end 198.1454 -70.18782)
		(width 0.3048)
		(layer "B.Cu")
		(net "PCE_AVDD")
	)
	(segment
		(start 193.194432 -72.380856)
		(end 193.194432 -71.895208)
		(width 0.254)
		(layer "B.Cu")
		(net "PCE_AVDD")
	)
	(segment
		(start 200.8632 -76.233528)
		(end 200.793604 -76.303124)
		(width 0.254)
		(layer "B.Cu")
		(net "PCE_AVDD")
	)
	(segment
		(start 89.281 -28.69184)
		(end 88.248236 -28.69184)
		(width 0.508)
		(layer "F.Cu")
		(net "P5V_STBY")
	)
	(segment
		(start 90.3732 -117.8306)
		(end 87.8713 -120.3325)
		(width 0.508)
		(layer "F.Cu")
		(net "P5V_STBY")
	)
	(segment
		(start 213.6902 -14.68882)
		(end 213.6902 -13.7668)
		(width 0.508)
		(layer "F.Cu")
		(net "P5V_STBY")
	)
	(segment
		(start 85.471 -169.225214)
		(end 85.471 -170.1927)
		(width 0.508)
		(layer "F.Cu")
		(net "P5V_STBY")
	)
	(segment
		(start 207.029304 -12.875768)
		(end 207.97139 -12.875768)
		(width 0.4064)
		(layer "F.Cu")
		(net "P5V_STBY")
	)
	(segment
		(start 169.799 -180.2257)
		(end 169.799 -179.7558)
		(width 0.254)
		(layer "F.Cu")
		(net "P5V_STBY")
	)
	(segment
		(start 85.2805 -169.034714)
		(end 85.471 -169.225214)
		(width 0.508)
		(layer "F.Cu")
		(net "P5V_STBY")
	)
	(segment
		(start 73.6092 -168.6433)
		(end 73.6092 -169.3672)
		(width 0.508)
		(layer "F.Cu")
		(net "P5V_STBY")
	)
	(segment
		(start 179.832 -157.226)
		(end 179.578 -156.972)
		(width 0.254)
		(layer "F.Cu")
		(net "P5V_STBY")
	)
	(segment
		(start 73.6092 -169.3672)
		(end 73.3298 -169.6466)
		(width 0.508)
		(layer "F.Cu")
		(net "P5V_STBY")
	)
	(segment
		(start 19.3294 -177.0634)
		(end 19.3294 -176.2125)
		(width 0.508)
		(layer "F.Cu")
		(net "P5V_STBY")
	)
	(segment
		(start 198.4375 -25.8445)
		(end 198.46417 -25.8445)
		(width 0.508)
		(layer "F.Cu")
		(net "P5V_STBY")
	)
	(segment
		(start 85.2805 -168.8338)
		(end 85.2805 -169.034714)
		(width 0.508)
		(layer "F.Cu")
		(net "P5V_STBY")
	)
	(segment
		(start 172.6692 -157.3784)
		(end 172.6692 -161.203894)
		(width 0.254)
		(layer "F.Cu")
		(net "P5V_STBY")
	)
	(segment
		(start 66.802 -172.5295)
		(end 66.926714 -172.654214)
		(width 0.4064)
		(layer "F.Cu")
		(net "P5V_STBY")
	)
	(segment
		(start 90.3732 -116.2812)
		(end 90.3732 -117.8306)
		(width 0.508)
		(layer "F.Cu")
		(net "P5V_STBY")
	)
	(segment
		(start 145.04416 -13.36548)
		(end 144.38122 -12.70254)
		(width 0.4064)
		(layer "F.Cu")
		(net "P5V_STBY")
	)
	(segment
		(start 173.0756 -156.972)
		(end 172.6692 -157.3784)
		(width 0.254)
		(layer "F.Cu")
		(net "P5V_STBY")
	)
	(segment
		(start 66.802 -172.5295)
		(end 67.5767 -172.5295)
		(width 0.508)
		(layer "F.Cu")
		(net "P5V_STBY")
	)
	(segment
		(start 145.04416 -13.91031)
		(end 145.04416 -13.36548)
		(width 0.4064)
		(layer "F.Cu")
		(net "P5V_STBY")
	)
	(segment
		(start 87.994236 -28.94584)
		(end 87.67445 -28.94584)
		(width 0.508)
		(layer "F.Cu")
		(net "P5V_STBY")
	)
	(segment
		(start 198.71817 -26.0985)
		(end 199.2376 -26.0985)
		(width 0.508)
		(layer "F.Cu")
		(net "P5V_STBY")
	)
	(segment
		(start 73.05548 -186.35218)
		(end 73.05548 -187.2742)
		(width 0.508)
		(layer "F.Cu")
		(net "P5V_STBY")
	)
	(segment
		(start 87.8713 -126.7079)
		(end 87.503 -127.0762)
		(width 0.508)
		(layer "F.Cu")
		(net "P5V_STBY")
	)
	(segment
		(start 193.07556 -12.70254)
		(end 192.133474 -13.71854)
		(width 0.4064)
		(layer "F.Cu")
		(net "P5V_STBY")
	)
	(segment
		(start 202.164188 -133.694932)
		(end 202.164188 -135.001)
		(width 0.508)
		(layer "F.Cu")
		(net "P5V_STBY")
	)
	(segment
		(start 179.578 -156.972)
		(end 173.0756 -156.972)
		(width 0.254)
		(layer "F.Cu")
		(net "P5V_STBY")
	)
	(segment
		(start 87.67445 -28.94584)
		(end 86.164928 -28.94584)
		(width 0.508)
		(layer "F.Cu")
		(net "P5V_STBY")
	)
	(segment
		(start 198.46417 -25.8445)
		(end 198.71817 -26.0985)
		(width 0.508)
		(layer "F.Cu")
		(net "P5V_STBY")
	)
	(segment
		(start 91.4654 -115.189)
		(end 90.3732 -116.2812)
		(width 0.508)
		(layer "F.Cu")
		(net "P5V_STBY")
	)
	(segment
		(start 88.248236 -28.69184)
		(end 87.994236 -28.94584)
		(width 0.508)
		(layer "F.Cu")
		(net "P5V_STBY")
	)
	(segment
		(start 199.176894 -32.22371)
		(end 198.016876 -32.22371)
		(width 0.508)
		(layer "F.Cu")
		(net "P5V_STBY")
	)
	(segment
		(start 87.8713 -120.3325)
		(end 87.8713 -126.7079)
		(width 0.508)
		(layer "F.Cu")
		(net "P5V_STBY")
	)
	(segment
		(start 66.926714 -172.654214)
		(end 66.926714 -174.262796)
		(width 0.4064)
		(layer "F.Cu")
		(net "P5V_STBY")
	)
	(segment
		(start 67.5767 -172.5295)
		(end 67.6148 -172.5676)
		(width 0.508)
		(layer "F.Cu")
		(net "P5V_STBY")
	)
	(via
		(at 85.2805 -168.8338)
		(size 0.508)
		(drill 0.254)
		(layers "F.Cu" "B.Cu")
		(net "P5V_STBY")
	)
	(via
		(at 187.147962 -13.230098)
		(size 0.508)
		(drill 0.254)
		(layers "F.Cu" "B.Cu")
		(net "P5V_STBY")
	)
	(via
		(at 68.169536 -168.378886)
		(size 0.508)
		(drill 0.254)
		(layers "F.Cu" "B.Cu")
		(net "P5V_STBY")
	)
	(via
		(at 171.1833 -176.810416)
		(size 0.7112)
		(drill 0.4064)
		(layers "F.Cu" "B.Cu")
		(net "P5V_STBY")
	)
	(via
		(at 198.016876 -32.22371)
		(size 0.508)
		(drill 0.254)
		(layers "F.Cu" "B.Cu")
		(net "P5V_STBY")
	)
	(via
		(at 176.12487 -171.843954)
		(size 0.6604)
		(drill 0.3302)
		(layers "F.Cu" "B.Cu")
		(net "P5V_STBY")
	)
	(via
		(at 77.6478 -50.1904)
		(size 0.508)
		(drill 0.254)
		(layers "F.Cu" "B.Cu")
		(net "P5V_STBY")
	)
	(via
		(at 202.164188 -135.001)
		(size 0.508)
		(drill 0.254)
		(layers "F.Cu" "B.Cu")
		(net "P5V_STBY")
	)
	(via
		(at 60.327286 -171.42841)
		(size 0.508)
		(drill 0.254)
		(layers "F.Cu" "B.Cu")
		(net "P5V_STBY")
	)
	(via
		(at 87.503 -127.0762)
		(size 0.508)
		(drill 0.254)
		(layers "F.Cu" "B.Cu")
		(net "P5V_STBY")
	)
	(via
		(at 174.50181 -169.5958)
		(size 0.7112)
		(drill 0.4064)
		(layers "F.Cu" "B.Cu")
		(net "P5V_STBY")
	)
	(via
		(at 146.434048 -92.66555)
		(size 0.7112)
		(drill 0.4064)
		(layers "F.Cu" "B.Cu")
		(net "P5V_STBY")
	)
	(via
		(at 146.434048 -93.88475)
		(size 0.7112)
		(drill 0.4064)
		(layers "F.Cu" "B.Cu")
		(net "P5V_STBY")
	)
	(via
		(at 174.50181 -164.719)
		(size 0.7112)
		(drill 0.4064)
		(layers "F.Cu" "B.Cu")
		(net "P5V_STBY")
	)
	(via
		(at 174.50181 -167.1574)
		(size 0.7112)
		(drill 0.4064)
		(layers "F.Cu" "B.Cu")
		(net "P5V_STBY")
	)
	(via
		(at 147.653248 -92.66555)
		(size 0.7112)
		(drill 0.4064)
		(layers "F.Cu" "B.Cu")
		(net "P5V_STBY")
	)
	(via
		(at 81.631028 -50.183796)
		(size 0.7112)
		(drill 0.4064)
		(layers "F.Cu" "B.Cu")
		(net "P5V_STBY")
	)
	(via
		(at 147.653248 -93.88475)
		(size 0.7112)
		(drill 0.4064)
		(layers "F.Cu" "B.Cu")
		(net "P5V_STBY")
	)
	(via
		(at 57.523634 -164.878766)
		(size 0.508)
		(drill 0.254)
		(layers "F.Cu" "B.Cu")
		(net "P5V_STBY")
	)
	(via
		(at 174.50181 -170.815)
		(size 0.7112)
		(drill 0.4064)
		(layers "F.Cu" "B.Cu")
		(net "P5V_STBY")
	)
	(via
		(at 171.1833 -179.350416)
		(size 0.7112)
		(drill 0.4064)
		(layers "F.Cu" "B.Cu")
		(net "P5V_STBY")
	)
	(via
		(at 174.50181 -165.9382)
		(size 0.7112)
		(drill 0.4064)
		(layers "F.Cu" "B.Cu")
		(net "P5V_STBY")
	)
	(via
		(at 173.16196 -179.086256)
		(size 0.6604)
		(drill 0.3302)
		(layers "F.Cu" "B.Cu")
		(net "P5V_STBY")
	)
	(via
		(at 89.478866 -147.394676)
		(size 0.508)
		(drill 0.254)
		(layers "F.Cu" "B.Cu")
		(net "P5V_STBY")
	)
	(via
		(at 198.4375 -25.8445)
		(size 0.508)
		(drill 0.254)
		(layers "F.Cu" "B.Cu")
		(net "P5V_STBY")
	)
	(via
		(at 171.1833 -175.540416)
		(size 0.7112)
		(drill 0.4064)
		(layers "F.Cu" "B.Cu")
		(net "P5V_STBY")
	)
	(via
		(at 213.6902 -13.7668)
		(size 0.508)
		(drill 0.254)
		(layers "F.Cu" "B.Cu")
		(net "P5V_STBY")
	)
	(via
		(at 151.257 -9.0424)
		(size 0.7112)
		(drill 0.4064)
		(layers "F.Cu" "B.Cu")
		(net "P5V_STBY")
	)
	(via
		(at 144.38122 -12.70254)
		(size 0.508)
		(drill 0.254)
		(layers "F.Cu" "B.Cu")
		(net "P5V_STBY")
	)
	(via
		(at 19.3294 -177.0634)
		(size 0.508)
		(drill 0.254)
		(layers "F.Cu" "B.Cu")
		(net "P5V_STBY")
	)
	(via
		(at 174.50181 -168.3766)
		(size 0.7112)
		(drill 0.4064)
		(layers "F.Cu" "B.Cu")
		(net "P5V_STBY")
	)
	(via
		(at 86.164928 -28.94584)
		(size 0.508)
		(drill 0.254)
		(layers "F.Cu" "B.Cu")
		(net "P5V_STBY")
	)
	(via
		(at 174.50181 -173.2534)
		(size 0.7112)
		(drill 0.4064)
		(layers "F.Cu" "B.Cu")
		(net "P5V_STBY")
	)
	(via
		(at 171.1833 -178.080416)
		(size 0.7112)
		(drill 0.4064)
		(layers "F.Cu" "B.Cu")
		(net "P5V_STBY")
	)
	(via
		(at 152.5778 -9.0678)
		(size 0.7112)
		(drill 0.4064)
		(layers "F.Cu" "B.Cu")
		(net "P5V_STBY")
	)
	(via
		(at 176.144936 -166.199312)
		(size 0.6604)
		(drill 0.3302)
		(layers "F.Cu" "B.Cu")
		(net "P5V_STBY")
	)
	(via
		(at 73.3298 -169.6466)
		(size 0.508)
		(drill 0.254)
		(layers "F.Cu" "B.Cu")
		(net "P5V_STBY")
	)
	(via
		(at 174.50181 -172.0342)
		(size 0.7112)
		(drill 0.4064)
		(layers "F.Cu" "B.Cu")
		(net "P5V_STBY")
	)
	(via
		(at 152.6286 -7.5438)
		(size 0.7112)
		(drill 0.4064)
		(layers "F.Cu" "B.Cu")
		(net "P5V_STBY")
	)
	(via
		(at 207.97139 -12.875768)
		(size 0.508)
		(drill 0.254)
		(layers "F.Cu" "B.Cu")
		(net "P5V_STBY")
	)
	(via
		(at 67.6148 -172.5676)
		(size 0.508)
		(drill 0.254)
		(layers "F.Cu" "B.Cu")
		(net "P5V_STBY")
	)
	(via
		(at 192.133474 -13.71854)
		(size 0.508)
		(drill 0.254)
		(layers "F.Cu" "B.Cu")
		(net "P5V_STBY")
	)
	(via
		(at 151.3078 -7.5692)
		(size 0.7112)
		(drill 0.4064)
		(layers "F.Cu" "B.Cu")
		(net "P5V_STBY")
	)
	(via
		(at 91.4654 -115.189)
		(size 0.508)
		(drill 0.254)
		(layers "F.Cu" "B.Cu")
		(net "P5V_STBY")
	)
	(via
		(at 171.1833 -174.270416)
		(size 0.7112)
		(drill 0.4064)
		(layers "F.Cu" "B.Cu")
		(net "P5V_STBY")
	)
	(via
		(at 152.253188 -13.122148)
		(size 0.508)
		(drill 0.254)
		(layers "F.Cu" "B.Cu")
		(net "P5V_STBY")
	)
	(via
		(at 81.631028 -51.402996)
		(size 0.7112)
		(drill 0.4064)
		(layers "F.Cu" "B.Cu")
		(net "P5V_STBY")
	)
	(via
		(at 73.05548 -187.2742)
		(size 0.508)
		(drill 0.254)
		(layers "F.Cu" "B.Cu")
		(net "P5V_STBY")
	)
	(via
		(at 174.50181 -163.4998)
		(size 0.7112)
		(drill 0.4064)
		(layers "F.Cu" "B.Cu")
		(net "P5V_STBY")
	)
	(segment
		(start 87.425784 -132.47751)
		(end 87.425784 -131.449826)
		(width 0.508)
		(layer "B.Cu")
		(net "P5V_STBY")
	)
	(segment
		(start 87.503 -127.1524)
		(end 87.503 -127.0762)
		(width 0.508)
		(layer "B.Cu")
		(net "P5V_STBY")
	)
	(segment
		(start 89.750138 -141.506702)
		(end 87.46236 -139.218924)
		(width 0.508)
		(layer "B.Cu")
		(net "P5V_STBY")
	)
	(segment
		(start 91.650058 -94.455996)
		(end 93.048074 -93.05798)
		(width 0.508)
		(layer "B.Cu")
		(net "P5V_STBY")
	)
	(segment
		(start 94.2086 -112.4458)
		(end 91.4654 -115.189)
		(width 0.508)
		(layer "B.Cu")
		(net "P5V_STBY")
	)
	(segment
		(start 20.4343 -175.9585)
		(end 26.035 -175.9585)
		(width 0.508)
		(layer "B.Cu")
		(net "P5V_STBY")
	)
	(segment
		(start 19.3294 -177.0634)
		(end 20.4343 -175.9585)
		(width 0.508)
		(layer "B.Cu")
		(net "P5V_STBY")
	)
	(segment
		(start 85.2424 -95.4786)
		(end 86.200996 -95.4786)
		(width 0.508)
		(layer "B.Cu")
		(net "P5V_STBY")
	)
	(segment
		(start 58.7502 -172.7073)
		(end 60.02909 -171.42841)
		(width 0.508)
		(layer "B.Cu")
		(net "P5V_STBY")
	)
	(segment
		(start 86.446868 -134.803896)
		(end 86.446868 -133.456426)
		(width 0.508)
		(layer "B.Cu")
		(net "P5V_STBY")
	)
	(segment
		(start 50.5841 -172.7073)
		(end 58.7502 -172.7073)
		(width 0.508)
		(layer "B.Cu")
		(net "P5V_STBY")
	)
	(segment
		(start 75.18908 -52.34432)
		(end 75.18908 -93.619574)
		(width 0.508)
		(layer "B.Cu")
		(net "P5V_STBY")
	)
	(segment
		(start 87.2236 -94.455996)
		(end 91.650058 -94.455996)
		(width 0.508)
		(layer "B.Cu")
		(net "P5V_STBY")
	)
	(segment
		(start 87.425784 -131.449826)
		(end 88.808052 -130.067558)
		(width 0.508)
		(layer "B.Cu")
		(net "P5V_STBY")
	)
	(segment
		(start 77.6478 -50.1904)
		(end 77.343 -50.1904)
		(width 0.508)
		(layer "B.Cu")
		(net "P5V_STBY")
	)
	(segment
		(start 44.490386 -174.480474)
		(end 45.50664 -173.46422)
		(width 0.508)
		(layer "B.Cu")
		(net "P5V_STBY")
	)
	(segment
		(start 80.137 -95.504)
		(end 80.7212 -94.9198)
		(width 0.508)
		(layer "B.Cu")
		(net "P5V_STBY")
	)
	(segment
		(start 57.287668 -163.708842)
		(end 57.287668 -163.069524)
		(width 0.508)
		(layer "B.Cu")
		(net "P5V_STBY")
	)
	(segment
		(start 94.34449 -93.05798)
		(end 97.028 -95.74149)
		(width 0.508)
		(layer "B.Cu")
		(net "P5V_STBY")
	)
	(segment
		(start 27.513026 -174.480474)
		(end 44.490386 -174.480474)
		(width 0.508)
		(layer "B.Cu")
		(net "P5V_STBY")
	)
	(segment
		(start 89.478866 -147.394676)
		(end 89.750138 -147.123404)
		(width 0.508)
		(layer "B.Cu")
		(net "P5V_STBY")
	)
	(segment
		(start 77.343 -50.1904)
		(end 75.18908 -52.34432)
		(width 0.508)
		(layer "B.Cu")
		(net "P5V_STBY")
	)
	(segment
		(start 80.7212 -94.9198)
		(end 82.1182 -94.9198)
		(width 0.508)
		(layer "B.Cu")
		(net "P5V_STBY")
	)
	(segment
		(start 57.305702 -164.660834)
		(end 57.305702 -163.726876)
		(width 0.508)
		(layer "B.Cu")
		(net "P5V_STBY")
	)
	(segment
		(start 86.200996 -95.4786)
		(end 87.2236 -94.455996)
		(width 0.508)
		(layer "B.Cu")
		(net "P5V_STBY")
	)
	(segment
		(start 192.976246 -12.875768)
		(end 192.133474 -13.71854)
		(width 0.508)
		(layer "B.Cu")
		(net "P5V_STBY")
	)
	(segment
		(start 88.808052 -128.457452)
		(end 87.503 -127.1524)
		(width 0.508)
		(layer "B.Cu")
		(net "P5V_STBY")
	)
	(segment
		(start 87.46236 -135.819388)
		(end 86.446868 -134.803896)
		(width 0.508)
		(layer "B.Cu")
		(net "P5V_STBY")
	)
	(segment
		(start 75.18908 -93.619574)
		(end 77.073506 -95.504)
		(width 0.508)
		(layer "B.Cu")
		(net "P5V_STBY")
	)
	(segment
		(start 89.750138 -147.123404)
		(end 89.750138 -141.506702)
		(width 0.508)
		(layer "B.Cu")
		(net "P5V_STBY")
	)
	(segment
		(start 207.97139 -12.875768)
		(end 192.976246 -12.875768)
		(width 0.508)
		(layer "B.Cu")
		(net "P5V_STBY")
	)
	(segment
		(start 82.3468 -95.1484)
		(end 82.3468 -96.6724)
		(width 0.508)
		(layer "B.Cu")
		(net "P5V_STBY")
	)
	(segment
		(start 26.035 -175.9585)
		(end 27.513026 -174.480474)
		(width 0.508)
		(layer "B.Cu")
		(net "P5V_STBY")
	)
	(segment
		(start 94.2086 -112.0394)
		(end 94.2086 -112.4458)
		(width 0.508)
		(layer "B.Cu")
		(net "P5V_STBY")
	)
	(segment
		(start 86.446868 -133.456426)
		(end 87.425784 -132.47751)
		(width 0.508)
		(layer "B.Cu")
		(net "P5V_STBY")
	)
	(segment
		(start 57.523634 -164.878766)
		(end 57.305702 -164.660834)
		(width 0.508)
		(layer "B.Cu")
		(net "P5V_STBY")
	)
	(segment
		(start 212.799168 -12.875768)
		(end 213.6902 -13.7668)
		(width 0.508)
		(layer "B.Cu")
		(net "P5V_STBY")
	)
	(segment
		(start 82.3468 -96.6724)
		(end 82.7532 -97.0788)
		(width 0.508)
		(layer "B.Cu")
		(net "P5V_STBY")
	)
	(segment
		(start 88.808052 -130.067558)
		(end 88.808052 -128.457452)
		(width 0.508)
		(layer "B.Cu")
		(net "P5V_STBY")
	)
	(segment
		(start 49.82718 -173.46422)
		(end 50.5841 -172.7073)
		(width 0.508)
		(layer "B.Cu")
		(net "P5V_STBY")
	)
	(segment
		(start 97.028 -95.74149)
		(end 97.028 -109.22)
		(width 0.508)
		(layer "B.Cu")
		(net "P5V_STBY")
	)
	(segment
		(start 87.46236 -139.218924)
		(end 87.46236 -135.819388)
		(width 0.508)
		(layer "B.Cu")
		(net "P5V_STBY")
	)
	(segment
		(start 82.7532 -97.0788)
		(end 83.6422 -97.0788)
		(width 0.508)
		(layer "B.Cu")
		(net "P5V_STBY")
	)
	(segment
		(start 57.305702 -163.726876)
		(end 57.287668 -163.708842)
		(width 0.508)
		(layer "B.Cu")
		(net "P5V_STBY")
	)
	(segment
		(start 97.028 -109.22)
		(end 94.2086 -112.0394)
		(width 0.508)
		(layer "B.Cu")
		(net "P5V_STBY")
	)
	(segment
		(start 77.073506 -95.504)
		(end 80.137 -95.504)
		(width 0.508)
		(layer "B.Cu")
		(net "P5V_STBY")
	)
	(segment
		(start 60.02909 -171.42841)
		(end 60.327286 -171.42841)
		(width 0.508)
		(layer "B.Cu")
		(net "P5V_STBY")
	)
	(segment
		(start 207.97139 -12.875768)
		(end 212.799168 -12.875768)
		(width 0.508)
		(layer "B.Cu")
		(net "P5V_STBY")
	)
	(segment
		(start 83.6422 -97.0788)
		(end 85.2424 -95.4786)
		(width 0.508)
		(layer "B.Cu")
		(net "P5V_STBY")
	)
	(segment
		(start 45.50664 -173.46422)
		(end 49.82718 -173.46422)
		(width 0.508)
		(layer "B.Cu")
		(net "P5V_STBY")
	)
	(segment
		(start 82.1182 -94.9198)
		(end 82.3468 -95.1484)
		(width 0.508)
		(layer "B.Cu")
		(net "P5V_STBY")
	)
	(segment
		(start 93.048074 -93.05798)
		(end 94.34449 -93.05798)
		(width 0.508)
		(layer "B.Cu")
		(net "P5V_STBY")
	)
	(segment
		(start 87.0331 -165.400736)
		(end 85.513164 -166.920672)
		(width 0.508)
		(layer "In2.Cu")
		(net "P5V_STBY")
	)
	(segment
		(start 202.164188 -138.653012)
		(end 177.3174 -163.4998)
		(width 0.508)
		(layer "In2.Cu")
		(net "P5V_STBY")
	)
	(segment
		(start 89.478866 -149.49678)
		(end 89.750138 -149.768052)
		(width 0.508)
		(layer "In2.Cu")
		(net "P5V_STBY")
	)
	(segment
		(start 191.5922 -14.259814)
		(end 191.5922 -23.0759)
		(width 0.508)
		(layer "In2.Cu")
		(net "P5V_STBY")
	)
	(segment
		(start 89.478866 -147.394676)
		(end 89.478866 -149.49678)
		(width 0.508)
		(layer "In2.Cu")
		(net "P5V_STBY")
	)
	(segment
		(start 90.4494 -159.201612)
		(end 87.8078 -161.843212)
		(width 0.508)
		(layer "In2.Cu")
		(net "P5V_STBY")
	)
	(segment
		(start 74.3204 -186.00928)
		(end 73.05548 -187.2742)
		(width 0.508)
		(layer "In2.Cu")
		(net "P5V_STBY")
	)
	(segment
		(start 57.523634 -164.878766)
		(end 60.327286 -167.682418)
		(width 0.508)
		(layer "In2.Cu")
		(net "P5V_STBY")
	)
	(segment
		(start 90.4494 -151.669496)
		(end 90.4494 -159.201612)
		(width 0.508)
		(layer "In2.Cu")
		(net "P5V_STBY")
	)
	(segment
		(start 202.164188 -135.001)
		(end 202.164188 -138.653012)
		(width 0.508)
		(layer "In2.Cu")
		(net "P5V_STBY")
	)
	(segment
		(start 87.1728 -162.974782)
		(end 87.1728 -163.427664)
		(width 0.508)
		(layer "In2.Cu")
		(net "P5V_STBY")
	)
	(segment
		(start 152.6286 -4.698492)
		(end 153.720292 -3.6068)
		(width 0.508)
		(layer "In2.Cu")
		(net "P5V_STBY")
	)
	(segment
		(start 75.1586 -175.36922)
		(end 73.10628 -177.42154)
		(width 0.508)
		(layer "In2.Cu")
		(net "P5V_STBY")
	)
	(segment
		(start 68.169536 -168.378886)
		(end 67.0052 -169.543222)
		(width 0.508)
		(layer "In2.Cu")
		(net "P5V_STBY")
	)
	(segment
		(start 67.0052 -169.543222)
		(end 67.0052 -171.958)
		(width 0.508)
		(layer "In2.Cu")
		(net "P5V_STBY")
	)
	(segment
		(start 89.750138 -150.970234)
		(end 90.4494 -151.669496)
		(width 0.508)
		(layer "In2.Cu")
		(net "P5V_STBY")
	)
	(segment
		(start 85.513164 -168.461436)
		(end 85.2805 -168.6941)
		(width 0.508)
		(layer "In2.Cu")
		(net "P5V_STBY")
	)
	(segment
		(start 89.750138 -149.768052)
		(end 89.750138 -150.970234)
		(width 0.508)
		(layer "In2.Cu")
		(net "P5V_STBY")
	)
	(segment
		(start 192.133474 -13.71854)
		(end 191.5922 -14.259814)
		(width 0.508)
		(layer "In2.Cu")
		(net "P5V_STBY")
	)
	(segment
		(start 198.102728 -25.509728)
		(end 198.4375 -25.8445)
		(width 0.508)
		(layer "In2.Cu")
		(net "P5V_STBY")
	)
	(segment
		(start 153.720292 -3.6068)
		(end 185.90514 -3.6068)
		(width 0.508)
		(layer "In2.Cu")
		(net "P5V_STBY")
	)
	(segment
		(start 87.8078 -162.339782)
		(end 87.1728 -162.974782)
		(width 0.508)
		(layer "In2.Cu")
		(net "P5V_STBY")
	)
	(segment
		(start 187.147962 -4.849622)
		(end 187.147962 -13.230098)
		(width 0.508)
		(layer "In2.Cu")
		(net "P5V_STBY")
	)
	(segment
		(start 87.0331 -163.567364)
		(end 87.0331 -165.400736)
		(width 0.508)
		(layer "In2.Cu")
		(net "P5V_STBY")
	)
	(segment
		(start 73.10628 -177.42154)
		(end 73.10628 -182.479442)
		(width 0.508)
		(layer "In2.Cu")
		(net "P5V_STBY")
	)
	(segment
		(start 67.0052 -171.958)
		(end 67.6148 -172.5676)
		(width 0.508)
		(layer "In2.Cu")
		(net "P5V_STBY")
	)
	(segment
		(start 60.327286 -167.682418)
		(end 60.327286 -171.42841)
		(width 0.508)
		(layer "In2.Cu")
		(net "P5V_STBY")
	)
	(segment
		(start 152.6286 -7.5438)
		(end 152.6286 -4.698492)
		(width 0.508)
		(layer "In2.Cu")
		(net "P5V_STBY")
	)
	(segment
		(start 177.3174 -163.4998)
		(end 174.50181 -163.4998)
		(width 0.508)
		(layer "In2.Cu")
		(net "P5V_STBY")
	)
	(segment
		(start 87.1728 -163.427664)
		(end 87.0331 -163.567364)
		(width 0.508)
		(layer "In2.Cu")
		(net "P5V_STBY")
	)
	(segment
		(start 75.1586 -171.4754)
		(end 75.1586 -175.36922)
		(width 0.508)
		(layer "In2.Cu")
		(net "P5V_STBY")
	)
	(segment
		(start 74.3204 -183.693562)
		(end 74.3204 -186.00928)
		(width 0.508)
		(layer "In2.Cu")
		(net "P5V_STBY")
	)
	(segment
		(start 87.8078 -161.843212)
		(end 87.8078 -162.339782)
		(width 0.508)
		(layer "In2.Cu")
		(net "P5V_STBY")
	)
	(segment
		(start 85.2805 -168.6941)
		(end 85.2805 -168.8338)
		(width 0.508)
		(layer "In2.Cu")
		(net "P5V_STBY")
	)
	(segment
		(start 191.5922 -23.0759)
		(end 194.026028 -25.509728)
		(width 0.508)
		(layer "In2.Cu")
		(net "P5V_STBY")
	)
	(segment
		(start 85.513164 -166.920672)
		(end 85.513164 -168.461436)
		(width 0.508)
		(layer "In2.Cu")
		(net "P5V_STBY")
	)
	(segment
		(start 73.10628 -182.479442)
		(end 74.3204 -183.693562)
		(width 0.508)
		(layer "In2.Cu")
		(net "P5V_STBY")
	)
	(segment
		(start 73.3298 -169.6466)
		(end 75.1586 -171.4754)
		(width 0.508)
		(layer "In2.Cu")
		(net "P5V_STBY")
	)
	(segment
		(start 194.026028 -25.509728)
		(end 198.102728 -25.509728)
		(width 0.508)
		(layer "In2.Cu")
		(net "P5V_STBY")
	)
	(segment
		(start 185.90514 -3.6068)
		(end 187.147962 -4.849622)
		(width 0.508)
		(layer "In2.Cu")
		(net "P5V_STBY")
	)
	(segment
		(start 72.062086 -168.378886)
		(end 73.3298 -169.6466)
		(width 0.508)
		(layer "In5.Cu")
		(net "P5V_STBY")
	)
	(segment
		(start 187.147962 -13.230098)
		(end 191.645032 -13.230098)
		(width 0.508)
		(layer "In5.Cu")
		(net "P5V_STBY")
	)
	(segment
		(start 198.016876 -32.22371)
		(end 198.129398 -32.111188)
		(width 0.508)
		(layer "In5.Cu")
		(net "P5V_STBY")
	)
	(segment
		(start 80.695292 -168.8084)
		(end 80.15097 -168.264078)
		(width 0.508)
		(layer "In5.Cu")
		(net "P5V_STBY")
	)
	(segment
		(start 198.9074 -29.33446)
		(end 198.9455 -29.29636)
		(width 0.508)
		(layer "In5.Cu")
		(net "P5V_STBY")
	)
	(segment
		(start 198.348854 -30.7721)
		(end 198.8693 -30.251654)
		(width 0.508)
		(layer "In5.Cu")
		(net "P5V_STBY")
	)
	(segment
		(start 198.129398 -30.7721)
		(end 198.348854 -30.7721)
		(width 0.508)
		(layer "In5.Cu")
		(net "P5V_STBY")
	)
	(segment
		(start 152.05202 -13.323316)
		(end 152.253188 -13.122148)
		(width 0.508)
		(layer "In5.Cu")
		(net "P5V_STBY")
	)
	(segment
		(start 198.9455 -29.29636)
		(end 198.9455 -26.3525)
		(width 0.508)
		(layer "In5.Cu")
		(net "P5V_STBY")
	)
	(segment
		(start 84.914994 -168.8084)
		(end 80.695292 -168.8084)
		(width 0.508)
		(layer "In5.Cu")
		(net "P5V_STBY")
	)
	(segment
		(start 75.6158 -169.6466)
		(end 73.3298 -169.6466)
		(width 0.508)
		(layer "In5.Cu")
		(net "P5V_STBY")
	)
	(segment
		(start 60.327286 -171.42841)
		(end 61.75121 -171.42841)
		(width 0.508)
		(layer "In5.Cu")
		(net "P5V_STBY")
	)
	(segment
		(start 198.9455 -26.3525)
		(end 198.4375 -25.8445)
		(width 0.508)
		(layer "In5.Cu")
		(net "P5V_STBY")
	)
	(segment
		(start 198.129398 -32.111188)
		(end 198.129398 -30.7721)
		(width 0.508)
		(layer "In5.Cu")
		(net "P5V_STBY")
	)
	(segment
		(start 61.75121 -171.42841)
		(end 62.6237 -172.3009)
		(width 0.508)
		(layer "In5.Cu")
		(net "P5V_STBY")
	)
	(segment
		(start 76.998322 -168.264078)
		(end 75.6158 -169.6466)
		(width 0.508)
		(layer "In5.Cu")
		(net "P5V_STBY")
	)
	(segment
		(start 62.6237 -172.3009)
		(end 67.3481 -172.3009)
		(width 0.508)
		(layer "In5.Cu")
		(net "P5V_STBY")
	)
	(segment
		(start 198.8693 -29.91866)
		(end 198.9074 -29.88056)
		(width 0.508)
		(layer "In5.Cu")
		(net "P5V_STBY")
	)
	(segment
		(start 67.3481 -172.3009)
		(end 67.6148 -172.5676)
		(width 0.508)
		(layer "In5.Cu")
		(net "P5V_STBY")
	)
	(segment
		(start 80.15097 -168.264078)
		(end 76.998322 -168.264078)
		(width 0.508)
		(layer "In5.Cu")
		(net "P5V_STBY")
	)
	(segment
		(start 198.8693 -30.251654)
		(end 198.8693 -29.91866)
		(width 0.508)
		(layer "In5.Cu")
		(net "P5V_STBY")
	)
	(segment
		(start 144.38122 -12.70254)
		(end 145.001996 -13.323316)
		(width 0.508)
		(layer "In5.Cu")
		(net "P5V_STBY")
	)
	(segment
		(start 145.001996 -13.323316)
		(end 152.05202 -13.323316)
		(width 0.508)
		(layer "In5.Cu")
		(net "P5V_STBY")
	)
	(segment
		(start 84.940394 -168.8338)
		(end 84.914994 -168.8084)
		(width 0.508)
		(layer "In5.Cu")
		(net "P5V_STBY")
	)
	(segment
		(start 191.645032 -13.230098)
		(end 192.133474 -13.71854)
		(width 0.508)
		(layer "In5.Cu")
		(net "P5V_STBY")
	)
	(segment
		(start 85.2805 -168.8338)
		(end 84.940394 -168.8338)
		(width 0.508)
		(layer "In5.Cu")
		(net "P5V_STBY")
	)
	(segment
		(start 198.9074 -29.88056)
		(end 198.9074 -29.33446)
		(width 0.508)
		(layer "In5.Cu")
		(net "P5V_STBY")
	)
	(segment
		(start 68.169536 -168.378886)
		(end 72.062086 -168.378886)
		(width 0.508)
		(layer "In5.Cu")
		(net "P5V_STBY")
	)
	(segment
		(start 52.499514 -142.600426)
		(end 52.099972 -142.999968)
		(width 0.3556)
		(layer "F.Cu")
		(net "P3V3_STBY")
	)
	(segment
		(start 82.425286 -139.368022)
		(end 81.858358 -139.368022)
		(width 0.508)
		(layer "F.Cu")
		(net "P3V3_STBY")
	)
	(segment
		(start 87.236046 -136.527286)
		(end 86.80196 -136.0932)
		(width 0.508)
		(layer "F.Cu")
		(net "P3V3_STBY")
	)
	(segment
		(start 61.72708 -140.205206)
		(end 62.418722 -139.513564)
		(width 0.3048)
		(layer "F.Cu")
		(net "P3V3_STBY")
	)
	(segment
		(start 46.480476 -119.346218)
		(end 47.023782 -119.346218)
		(width 0.508)
		(layer "F.Cu")
		(net "P3V3_STBY")
	)
	(segment
		(start 50.500026 -140.599922)
		(end 50.500026 -140.600176)
		(width 0.3556)
		(layer "F.Cu")
		(net "P3V3_STBY")
	)
	(segment
		(start 68.3768 -177.6984)
		(end 68.89496 -177.18024)
		(width 0.4064)
		(layer "F.Cu")
		(net "P3V3_STBY")
	)
	(segment
		(start 52.099972 -146.19986)
		(end 52.099464 -146.19986)
		(width 0.254)
		(layer "F.Cu")
		(net "P3V3_STBY")
	)
	(segment
		(start 63.68796 -146.84756)
		(end 63.7286 -146.8882)
		(width 0.508)
		(layer "F.Cu")
		(net "P3V3_STBY")
	)
	(segment
		(start 52.499514 -141.800326)
		(end 52.099972 -142.199868)
		(width 0.3556)
		(layer "F.Cu")
		(net "P3V3_STBY")
	)
	(segment
		(start 52.9209 -125.8824)
		(end 52.9971 -125.8062)
		(width 0.4318)
		(layer "F.Cu")
		(net "P3V3_STBY")
	)
	(segment
		(start 84.727288 -134.97052)
		(end 84.797138 -134.90067)
		(width 0.508)
		(layer "F.Cu")
		(net "P3V3_STBY")
	)
	(segment
		(start 157.47492 -50.1777)
		(end 152.702006 -54.95036)
		(width 0.762)
		(layer "F.Cu")
		(net "P3V3_STBY")
	)
	(segment
		(start 176.9618 -120.2309)
		(end 176.9618 -120.904)
		(width 0.508)
		(layer "F.Cu")
		(net "P3V3_STBY")
	)
	(segment
		(start 197.5358 -18.8341)
		(end 197.5358 -17.932654)
		(width 0.508)
		(layer "F.Cu")
		(net "P3V3_STBY")
	)
	(segment
		(start 45.300138 -149.800056)
		(end 45.300138 -149.799802)
		(width 0.3556)
		(layer "F.Cu")
		(net "P3V3_STBY")
	)
	(segment
		(start 65.3542 -136.525)
		(end 65.3542 -136.6012)
		(width 0.508)
		(layer "F.Cu")
		(net "P3V3_STBY")
	)
	(segment
		(start 53.299614 -151.400002)
		(end 53.299614 -151.399748)
		(width 0.254)
		(layer "F.Cu")
		(net "P3V3_STBY")
	)
	(segment
		(start 64.1477 -171.6024)
		(end 64.7446 -171.6024)
		(width 0.508)
		(layer "F.Cu")
		(net "P3V3_STBY")
	)
	(segment
		(start 64.643 -147.193)
		(end 64.31788 -146.86788)
		(width 0.508)
		(layer "F.Cu")
		(net "P3V3_STBY")
	)
	(segment
		(start 42.3164 -131.3053)
		(end 42.3164 -130.4544)
		(width 0.508)
		(layer "F.Cu")
		(net "P3V3_STBY")
	)
	(segment
		(start 175.006 -128.9812)
		(end 175.0314 -129.0066)
		(width 0.508)
		(layer "F.Cu")
		(net "P3V3_STBY")
	)
	(segment
		(start 195.880736 -131.699)
		(end 195.880736 -130.788664)
		(width 0.508)
		(layer "F.Cu")
		(net "P3V3_STBY")
	)
	(segment
		(start 86.849712 -131.339844)
		(end 86.604094 -131.094226)
		(width 0.508)
		(layer "F.Cu")
		(net "P3V3_STBY")
	)
	(segment
		(start 69.469 -144.4879)
		(end 68.6435 -145.3134)
		(width 0.508)
		(layer "F.Cu")
		(net "P3V3_STBY")
	)
	(segment
		(start 32.4866 -165.4683)
		(end 32.4866 -165.9128)
		(width 0.508)
		(layer "F.Cu")
		(net "P3V3_STBY")
	)
	(segment
		(start 179.817776 -116.219224)
		(end 179.832 -116.205)
		(width 0.4064)
		(layer "F.Cu")
		(net "P3V3_STBY")
	)
	(segment
		(start 148.4757 -21.1201)
		(end 148.4757 -20.5105)
		(width 0.508)
		(layer "F.Cu")
		(net "P3V3_STBY")
	)
	(segment
		(start 147.9296 -19.9644)
		(end 148.4757 -20.5105)
		(width 0.508)
		(layer "F.Cu")
		(net "P3V3_STBY")
	)
	(segment
		(start 72.69353 -134.767066)
		(end 73.400158 -134.767066)
		(width 0.508)
		(layer "F.Cu")
		(net "P3V3_STBY")
	)
	(segment
		(start 91.567 -178.42484)
		(end 89.90076 -178.42484)
		(width 0.508)
		(layer "F.Cu")
		(net "P3V3_STBY")
	)
	(segment
		(start 59.944 -162.0393)
		(end 59.944 -164.4396)
		(width 0.508)
		(layer "F.Cu")
		(net "P3V3_STBY")
	)
	(segment
		(start 67.0941 -140.2334)
		(end 67.0941 -140.63472)
		(width 0.508)
		(layer "F.Cu")
		(net "P3V3_STBY")
	)
	(segment
		(start 88.478106 -147.7137)
		(end 88.526366 -147.66544)
		(width 0.508)
		(layer "F.Cu")
		(net "P3V3_STBY")
	)
	(segment
		(start 69.65823 -139.546076)
		(end 68.585334 -139.546076)
		(width 0.4064)
		(layer "F.Cu")
		(net "P3V3_STBY")
	)
	(segment
		(start 146.34464 -15.96009)
		(end 146.88439 -15.96009)
		(width 0.4064)
		(layer "F.Cu")
		(net "P3V3_STBY")
	)
	(segment
		(start 197.5358 -18.8341)
		(end 197.1167 -18.8341)
		(width 0.3556)
		(layer "F.Cu")
		(net "P3V3_STBY")
	)
	(segment
		(start 65.641474 -180.67909)
		(end 65.639442 -180.681122)
		(width 0.508)
		(layer "F.Cu")
		(net "P3V3_STBY")
	)
	(segment
		(start 70.724522 -164.809678)
		(end 70.724522 -164.412422)
		(width 0.508)
		(layer "F.Cu")
		(net "P3V3_STBY")
	)
	(segment
		(start 77.089 -147.8788)
		(end 77.0763 -147.8915)
		(width 0.508)
		(layer "F.Cu")
		(net "P3V3_STBY")
	)
	(segment
		(start 204.533246 -133.583426)
		(end 204.364336 -133.752336)
		(width 0.508)
		(layer "F.Cu")
		(net "P3V3_STBY")
	)
	(segment
		(start 46.100238 -140.20038)
		(end 46.100492 -140.20038)
		(width 0.3556)
		(layer "F.Cu")
		(net "P3V3_STBY")
	)
	(segment
		(start 77.4954 -168.7576)
		(end 77.3176 -168.9354)
		(width 0.508)
		(layer "F.Cu")
		(net "P3V3_STBY")
	)
	(segment
		(start 85.09 -57.655968)
		(end 85.220048 -57.786016)
		(width 0.508)
		(layer "F.Cu")
		(net "P3V3_STBY")
	)
	(segment
		(start 163.6014 -51.6509)
		(end 161.746946 -51.6509)
		(width 0.762)
		(layer "F.Cu")
		(net "P3V3_STBY")
	)
	(segment
		(start 32.4866 -165.9128)
		(end 33.2232 -166.6494)
		(width 0.508)
		(layer "F.Cu")
		(net "P3V3_STBY")
	)
	(segment
		(start 75.5142 -150.0886)
		(end 76.0603 -150.0886)
		(width 0.508)
		(layer "F.Cu")
		(net "P3V3_STBY")
	)
	(segment
		(start 179.832 -116.205)
		(end 178.7652 -116.205)
		(width 0.508)
		(layer "F.Cu")
		(net "P3V3_STBY")
	)
	(segment
		(start 99.453446 -142.2781)
		(end 97.865184 -142.2781)
		(width 0.508)
		(layer "F.Cu")
		(net "P3V3_STBY")
	)
	(segment
		(start 81.06029 -138.76655)
		(end 80.074008 -138.76655)
		(width 0.3048)
		(layer "F.Cu")
		(net "P3V3_STBY")
	)
	(segment
		(start 76.1746 -147.8915)
		(end 75.311 -147.8915)
		(width 0.508)
		(layer "F.Cu")
		(net "P3V3_STBY")
	)
	(segment
		(start 29.8958 -132.2832)
		(end 29.8958 -131.7625)
		(width 0.508)
		(layer "F.Cu")
		(net "P3V3_STBY")
	)
	(segment
		(start 52.499768 -143.400526)
		(end 52.499514 -143.400526)
		(width 0.3556)
		(layer "F.Cu")
		(net "P3V3_STBY")
	)
	(segment
		(start 197.1167 -18.8341)
		(end 196.6341 -18.3515)
		(width 0.3556)
		(layer "F.Cu")
		(net "P3V3_STBY")
	)
	(segment
		(start 152.702006 -80.375252)
		(end 151.205692 -81.871566)
		(width 0.762)
		(layer "F.Cu")
		(net "P3V3_STBY")
	)
	(segment
		(start 53.299614 -151.399748)
		(end 52.899818 -150.999952)
		(width 0.254)
		(layer "F.Cu")
		(net "P3V3_STBY")
	)
	(segment
		(start 86.50478 -180.784246)
		(end 87.736426 -179.5526)
		(width 0.508)
		(layer "F.Cu")
		(net "P3V3_STBY")
	)
	(segment
		(start 82.9818 -139.046712)
		(end 82.746596 -139.046712)
		(width 0.508)
		(layer "F.Cu")
		(net "P3V3_STBY")
	)
	(segment
		(start 52.5018 -176.6316)
		(end 52.5018 -177.038)
		(width 0.3556)
		(layer "F.Cu")
		(net "P3V3_STBY")
	)
	(segment
		(start 78.515464 -140.957046)
		(end 78.972156 -141.413738)
		(width 0.3048)
		(layer "F.Cu")
		(net "P3V3_STBY")
	)
	(segment
		(start 61.8236 -162.4203)
		(end 61.2902 -162.4203)
		(width 0.508)
		(layer "F.Cu")
		(net "P3V3_STBY")
	)
	(segment
		(start 93.251782 -152.73528)
		(end 93.251782 -151.401018)
		(width 0.254)
		(layer "F.Cu")
		(net "P3V3_STBY")
	)
	(segment
		(start 96.356932 -176.657)
		(end 96.603566 -176.903634)
		(width 0.3556)
		(layer "F.Cu")
		(net "P3V3_STBY")
	)
	(segment
		(start 82.584544 -131.906264)
		(end 82.584544 -132.72135)
		(width 0.508)
		(layer "F.Cu")
		(net "P3V3_STBY")
	)
	(segment
		(start 23.756874 -125.194314)
		(end 24.799798 -125.194314)
		(width 0.508)
		(layer "F.Cu")
		(net "P3V3_STBY")
	)
	(segment
		(start 88.402414 -155.60548)
		(end 89.881456 -155.60548)
		(width 0.254)
		(layer "F.Cu")
		(net "P3V3_STBY")
	)
	(segment
		(start 90.75166 -152.64638)
		(end 89.59088 -152.64638)
		(width 0.254)
		(layer "F.Cu")
		(net "P3V3_STBY")
	)
	(segment
		(start 86.80196 -136.0932)
		(end 86.599268 -135.890508)
		(width 0.508)
		(layer "F.Cu")
		(net "P3V3_STBY")
	)
	(segment
		(start 63.9826 -171.7675)
		(end 64.1477 -171.6024)
		(width 0.508)
		(layer "F.Cu")
		(net "P3V3_STBY")
	)
	(segment
		(start 71.374 -172.212)
		(end 71.7804 -172.6184)
		(width 0.508)
		(layer "F.Cu")
		(net "P3V3_STBY")
	)
	(segment
		(start 83.87842 -134.97052)
		(end 84.727288 -134.97052)
		(width 0.508)
		(layer "F.Cu")
		(net "P3V3_STBY")
	)
	(segment
		(start 75.48499 -150.11781)
		(end 75.5142 -150.0886)
		(width 0.508)
		(layer "F.Cu")
		(net "P3V3_STBY")
	)
	(segment
		(start 195.157344 -13.62964)
		(end 195.532248 -13.62964)
		(width 0.4064)
		(layer "F.Cu")
		(net "P3V3_STBY")
	)
	(segment
		(start 52.099972 -147.800314)
		(end 52.099972 -147.80006)
		(width 0.254)
		(layer "F.Cu")
		(net "P3V3_STBY")
	)
	(segment
		(start 147.9296 -17.0053)
		(end 147.9296 -19.9644)
		(width 0.508)
		(layer "F.Cu")
		(net "P3V3_STBY")
	)
	(segment
		(start 65.641474 -179.81676)
		(end 65.641474 -180.67909)
		(width 0.508)
		(layer "F.Cu")
		(net "P3V3_STBY")
	)
	(segment
		(start 52.499768 -144.200372)
		(end 52.499514 -144.200372)
		(width 0.3556)
		(layer "F.Cu")
		(net "P3V3_STBY")
	)
	(segment
		(start 52.499768 -142.600426)
		(end 52.499514 -142.600426)
		(width 0.3556)
		(layer "F.Cu")
		(net "P3V3_STBY")
	)
	(segment
		(start 37.112448 -130.314192)
		(end 38.128448 -130.314192)
		(width 0.508)
		(layer "F.Cu")
		(net "P3V3_STBY")
	)
	(segment
		(start 91.764866 -147.738338)
		(end 91.64828 -147.854924)
		(width 0.508)
		(layer "F.Cu")
		(net "P3V3_STBY")
	)
	(segment
		(start 94.25178 -159.585152)
		(end 94.25178 -158.47568)
		(width 0.254)
		(layer "F.Cu")
		(net "P3V3_STBY")
	)
	(segment
		(start 160.978088 -95.32747)
		(end 161.429954 -95.32747)
		(width 0.508)
		(layer "F.Cu")
		(net "P3V3_STBY")
	)
	(segment
		(start 194.37604 -14.75232)
		(end 194.37604 -14.410944)
		(width 0.4064)
		(layer "F.Cu")
		(net "P3V3_STBY")
	)
	(segment
		(start 88.392 -155.615894)
		(end 88.402414 -155.60548)
		(width 0.254)
		(layer "F.Cu")
		(net "P3V3_STBY")
	)
	(segment
		(start 26.90368 -122.414792)
		(end 26.90368 -121.182892)
		(width 0.508)
		(layer "F.Cu")
		(net "P3V3_STBY")
	)
	(segment
		(start 68.9483 -119.4562)
		(end 69.9516 -119.4562)
		(width 0.508)
		(layer "F.Cu")
		(net "P3V3_STBY")
	)
	(segment
		(start 204.979524 -14.176248)
		(end 204.247496 -14.176248)
		(width 0.381)
		(layer "F.Cu")
		(net "P3V3_STBY")
	)
	(segment
		(start 69.469 -144.1196)
		(end 69.469 -144.4879)
		(width 0.508)
		(layer "F.Cu")
		(net "P3V3_STBY")
	)
	(segment
		(start 68.1609 -117.3353)
		(end 68.1609 -118.2116)
		(width 0.508)
		(layer "F.Cu")
		(net "P3V3_STBY")
	)
	(segment
		(start 20.9931 -175.514)
		(end 20.4724 -174.9933)
		(width 0.508)
		(layer "F.Cu")
		(net "P3V3_STBY")
	)
	(segment
		(start 30.8737 -131.7625)
		(end 31.457392 -132.346192)
		(width 0.508)
		(layer "F.Cu")
		(net "P3V3_STBY")
	)
	(segment
		(start 47.023782 -119.346218)
		(end 47.498 -118.872)
		(width 0.508)
		(layer "F.Cu")
		(net "P3V3_STBY")
	)
	(segment
		(start 75.39609 -150.11781)
		(end 75.48499 -150.11781)
		(width 0.508)
		(layer "F.Cu")
		(net "P3V3_STBY")
	)
	(segment
		(start 69.6341 -163.322)
		(end 68.5927 -163.322)
		(width 0.508)
		(layer "F.Cu")
		(net "P3V3_STBY")
	)
	(segment
		(start 84.558632 -133.682486)
		(end 83.965034 -133.682486)
		(width 0.508)
		(layer "F.Cu")
		(net "P3V3_STBY")
	)
	(segment
		(start 70.724522 -164.809678)
		(end 71.374762 -164.809678)
		(width 0.508)
		(layer "F.Cu")
		(net "P3V3_STBY")
	)
	(segment
		(start 46.480476 -116.780818)
		(end 47.396908 -116.780818)
		(width 0.508)
		(layer "F.Cu")
		(net "P3V3_STBY")
	)
	(segment
		(start 73.4187 -158.03626)
		(end 73.9267 -157.52826)
		(width 0.508)
		(layer "F.Cu")
		(net "P3V3_STBY")
	)
	(segment
		(start 96.2787 -137.142474)
		(end 96.7359 -137.599674)
		(width 0.508)
		(layer "F.Cu")
		(net "P3V3_STBY")
	)
	(segment
		(start 161.746946 -51.6509)
		(end 160.273746 -50.1777)
		(width 0.762)
		(layer "F.Cu")
		(net "P3V3_STBY")
	)
	(segment
		(start 146.88439 -15.96009)
		(end 147.32 -16.3957)
		(width 0.4064)
		(layer "F.Cu")
		(net "P3V3_STBY")
	)
	(segment
		(start 30.3784 -154.80411)
		(end 30.3784 -154.1018)
		(width 0.508)
		(layer "F.Cu")
		(net "P3V3_STBY")
	)
	(segment
		(start 81.7372 -172.2501)
		(end 81.7372 -172.339)
		(width 0.508)
		(layer "F.Cu")
		(net "P3V3_STBY")
	)
	(segment
		(start 89.0778 -179.5526)
		(end 89.86012 -178.77028)
		(width 0.508)
		(layer "F.Cu")
		(net "P3V3_STBY")
	)
	(segment
		(start 31.33598 -154.1018)
		(end 31.33598 -153.444448)
		(width 0.508)
		(layer "F.Cu")
		(net "P3V3_STBY")
	)
	(segment
		(start 31.457392 -132.346192)
		(end 31.950152 -132.346192)
		(width 0.508)
		(layer "F.Cu")
		(net "P3V3_STBY")
	)
	(segment
		(start 90.02776 -124.27712)
		(end 90.24112 -124.27712)
		(width 0.508)
		(layer "F.Cu")
		(net "P3V3_STBY")
	)
	(segment
		(start 75.475084 -52.95011)
		(end 77.295502 -52.95011)
		(width 0.508)
		(layer "F.Cu")
		(net "P3V3_STBY")
	)
	(segment
		(start 29.8958 -131.7625)
		(end 30.8737 -131.7625)
		(width 0.508)
		(layer "F.Cu")
		(net "P3V3_STBY")
	)
	(segment
		(start 73.9267 -157.52826)
		(end 73.9267 -156.718)
		(width 0.508)
		(layer "F.Cu")
		(net "P3V3_STBY")
	)
	(segment
		(start 83.262216 -138.789664)
		(end 83.238848 -138.789664)
		(width 0.508)
		(layer "F.Cu")
		(net "P3V3_STBY")
	)
	(segment
		(start 96.783652 -177.08372)
		(end 97.84588 -177.08372)
		(width 0.508)
		(layer "F.Cu")
		(net "P3V3_STBY")
	)
	(segment
		(start 85.32241 -137.060686)
		(end 85.834474 -137.060686)
		(width 0.508)
		(layer "F.Cu")
		(net "P3V3_STBY")
	)
	(segment
		(start 71.284084 -141.5161)
		(end 71.200264 -141.59992)
		(width 0.508)
		(layer "F.Cu")
		(net "P3V3_STBY")
	)
	(segment
		(start 46.56328 -121.424192)
		(end 47.308008 -121.424192)
		(width 0.508)
		(layer "F.Cu")
		(net "P3V3_STBY")
	)
	(segment
		(start 49.299622 -148.999956)
		(end 49.299622 -148.999702)
		(width 0.3556)
		(layer "F.Cu")
		(net "P3V3_STBY")
	)
	(segment
		(start 43.37558 -117.804692)
		(end 42.994326 -118.185946)
		(width 0.508)
		(layer "F.Cu")
		(net "P3V3_STBY")
	)
	(segment
		(start 49.299622 -148.999702)
		(end 48.899826 -148.599906)
		(width 0.3556)
		(layer "F.Cu")
		(net "P3V3_STBY")
	)
	(segment
		(start 45.300138 -149.799802)
		(end 45.699934 -149.400006)
		(width 0.3556)
		(layer "F.Cu")
		(net "P3V3_STBY")
	)
	(segment
		(start 161.429954 -95.32747)
		(end 161.798 -94.959424)
		(width 0.508)
		(layer "F.Cu")
		(net "P3V3_STBY")
	)
	(segment
		(start 162.323018 -91.069414)
		(end 165.559486 -91.069414)
		(width 0.508)
		(layer "F.Cu")
		(net "P3V3_STBY")
	)
	(segment
		(start 33.5534 -166.3192)
		(end 33.2232 -166.6494)
		(width 0.508)
		(layer "F.Cu")
		(net "P3V3_STBY")
	)
	(segment
		(start 204.533246 -132.925058)
		(end 204.533246 -133.583426)
		(width 0.508)
		(layer "F.Cu")
		(net "P3V3_STBY")
	)
	(segment
		(start 52.499768 -148.20011)
		(end 52.099972 -147.800314)
		(width 0.254)
		(layer "F.Cu")
		(net "P3V3_STBY")
	)
	(segment
		(start 71.979536 -155.452826)
		(end 71.05523 -155.452826)
		(width 0.508)
		(layer "F.Cu")
		(net "P3V3_STBY")
	)
	(segment
		(start 84.8995 -149.973284)
		(end 84.2518 -149.325584)
		(width 0.508)
		(layer "F.Cu")
		(net "P3V3_STBY")
	)
	(segment
		(start 83.558888 -53.564536)
		(end 83.558888 -47.191168)
		(width 0.508)
		(layer "F.Cu")
		(net "P3V3_STBY")
	)
	(segment
		(start 64.389 -148.7678)
		(end 64.5922 -148.971)
		(width 0.508)
		(layer "F.Cu")
		(net "P3V3_STBY")
	)
	(segment
		(start 77.4954 -168.0337)
		(end 77.4954 -168.7576)
		(width 0.508)
		(layer "F.Cu")
		(net "P3V3_STBY")
	)
	(segment
		(start 87.4776 -128.3716)
		(end 87.72652 -128.3716)
		(width 0.508)
		(layer "F.Cu")
		(net "P3V3_STBY")
	)
	(segment
		(start 46.100238 -149.800056)
		(end 46.100238 -149.799802)
		(width 0.3556)
		(layer "F.Cu")
		(net "P3V3_STBY")
	)
	(segment
		(start 78.18628 -140.627862)
		(end 78.515464 -140.957046)
		(width 0.508)
		(layer "F.Cu")
		(net "P3V3_STBY")
	)
	(segment
		(start 96.603566 -176.903634)
		(end 96.783652 -177.08372)
		(width 0.508)
		(layer "F.Cu")
		(net "P3V3_STBY")
	)
	(segment
		(start 44.500038 -140.20038)
		(end 44.500292 -140.20038)
		(width 0.3556)
		(layer "F.Cu")
		(net "P3V3_STBY")
	)
	(segment
		(start 77.0763 -147.8915)
		(end 76.1746 -147.8915)
		(width 0.508)
		(layer "F.Cu")
		(net "P3V3_STBY")
	)
	(segment
		(start 89.3064 -148.649436)
		(end 89.52992 -148.872956)
		(width 0.508)
		(layer "F.Cu")
		(net "P3V3_STBY")
	)
	(segment
		(start 69.088 -117.2972)
		(end 69.088 -116.5225)
		(width 0.508)
		(layer "F.Cu")
		(net "P3V3_STBY")
	)
	(segment
		(start 60.8203 -161.9504)
		(end 60.0329 -161.9504)
		(width 0.508)
		(layer "F.Cu")
		(net "P3V3_STBY")
	)
	(segment
		(start 46.100238 -149.799802)
		(end 46.500034 -149.400006)
		(width 0.3556)
		(layer "F.Cu")
		(net "P3V3_STBY")
	)
	(segment
		(start 65.278 -139.2936)
		(end 65.614296 -139.629896)
		(width 0.508)
		(layer "F.Cu")
		(net "P3V3_STBY")
	)
	(segment
		(start 68.95338 -182.73268)
		(end 69.08038 -182.60568)
		(width 0.508)
		(layer "F.Cu")
		(net "P3V3_STBY")
	)
	(segment
		(start 57.3786 -160.1978)
		(end 57.3786 -159.2961)
		(width 0.508)
		(layer "F.Cu")
		(net "P3V3_STBY")
	)
	(segment
		(start 75.28941 -150.11781)
		(end 75.39609 -150.11781)
		(width 0.508)
		(layer "F.Cu")
		(net "P3V3_STBY")
	)
	(segment
		(start 77.295502 -52.95011)
		(end 77.688948 -53.343556)
		(width 0.508)
		(layer "F.Cu")
		(net "P3V3_STBY")
	)
	(segment
		(start 63.885064 -144.045432)
		(end 63.885064 -143.022066)
		(width 0.508)
		(layer "F.Cu")
		(net "P3V3_STBY")
	)
	(segment
		(start 84.276438 -46.473618)
		(end 86.322154 -46.473618)
		(width 0.508)
		(layer "F.Cu")
		(net "P3V3_STBY")
	)
	(segment
		(start 51.699922 -145.800318)
		(end 52.099972 -145.400268)
		(width 0.254)
		(layer "F.Cu")
		(net "P3V3_STBY")
	)
	(segment
		(start 167.4622 -92.972128)
		(end 165.976046 -91.485974)
		(width 0.508)
		(layer "F.Cu")
		(net "P3V3_STBY")
	)
	(segment
		(start 64.65062 -143.3322)
		(end 64.337692 -143.019272)
		(width 0.508)
		(layer "F.Cu")
		(net "P3V3_STBY")
	)
	(segment
		(start 44.500038 -141.800072)
		(end 44.100242 -142.199868)
		(width 0.3556)
		(layer "F.Cu")
		(net "P3V3_STBY")
	)
	(segment
		(start 75.7809 -132.454142)
		(end 75.77709 -132.450332)
		(width 0.508)
		(layer "F.Cu")
		(net "P3V3_STBY")
	)
	(segment
		(start 91.8464 -125.1077)
		(end 91.6432 -124.9045)
		(width 0.3556)
		(layer "F.Cu")
		(net "P3V3_STBY")
	)
	(segment
		(start 41.91 -163.6395)
		(end 41.91 -162.6616)
		(width 0.508)
		(layer "F.Cu")
		(net "P3V3_STBY")
	)
	(segment
		(start 45.300392 -140.20038)
		(end 45.699934 -140.599922)
		(width 0.3556)
		(layer "F.Cu")
		(net "P3V3_STBY")
	)
	(segment
		(start 90.8685 -124.9045)
		(end 90.7923 -124.8283)
		(width 0.3556)
		(layer "F.Cu")
		(net "P3V3_STBY")
	)
	(segment
		(start 52.959 -125.7681)
		(end 52.959 -124.8918)
		(width 0.508)
		(layer "F.Cu")
		(net "P3V3_STBY")
	)
	(segment
		(start 64.7192 -174.567596)
		(end 64.4652 -174.313596)
		(width 0.4064)
		(layer "F.Cu")
		(net "P3V3_STBY")
	)
	(segment
		(start 86.604094 -131.094226)
		(end 86.604094 -129.9464)
		(width 0.508)
		(layer "F.Cu")
		(net "P3V3_STBY")
	)
	(segment
		(start 147.9042 -21.6916)
		(end 148.4757 -21.1201)
		(width 0.508)
		(layer "F.Cu")
		(net "P3V3_STBY")
	)
	(segment
		(start 22.614636 -15.891256)
		(end 22.62378 -15.9004)
		(width 0.508)
		(layer "F.Cu")
		(net "P3V3_STBY")
	)
	(segment
		(start 179.817776 -117.96522)
		(end 179.817776 -116.219224)
		(width 0.4064)
		(layer "F.Cu")
		(net "P3V3_STBY")
	)
	(segment
		(start 94.766384 -129.2098)
		(end 95.06331 -129.506726)
		(width 0.254)
		(layer "F.Cu")
		(net "P3V3_STBY")
	)
	(segment
		(start 204.247496 -14.176248)
		(end 203.907644 -14.5161)
		(width 0.381)
		(layer "F.Cu")
		(net "P3V3_STBY")
	)
	(segment
		(start 64.31788 -146.86788)
		(end 63.74892 -146.86788)
		(width 0.508)
		(layer "F.Cu")
		(net "P3V3_STBY")
	)
	(segment
		(start 61.2902 -162.4203)
		(end 60.8203 -161.9504)
		(width 0.508)
		(layer "F.Cu")
		(net "P3V3_STBY")
	)
	(segment
		(start 52.5018 -175.551084)
		(end 52.5018 -176.6316)
		(width 0.3556)
		(layer "F.Cu")
		(net "P3V3_STBY")
	)
	(segment
		(start 91.92768 -125.1077)
		(end 91.8464 -125.1077)
		(width 0.3556)
		(layer "F.Cu")
		(net "P3V3_STBY")
	)
	(segment
		(start 66.857626 -140.892276)
		(end 66.856864 -140.893038)
		(width 0.508)
		(layer "F.Cu")
		(net "P3V3_STBY")
	)
	(segment
		(start 92.657168 -62.302136)
		(end 92.116148 -61.761116)
		(width 0.508)
		(layer "F.Cu")
		(net "P3V3_STBY")
	)
	(segment
		(start 151.205692 -81.871566)
		(end 151.205692 -93.6752)
		(width 0.762)
		(layer "F.Cu")
		(net "P3V3_STBY")
	)
	(segment
		(start 199.449436 -128.4224)
		(end 198.628 -128.4224)
		(width 0.508)
		(layer "F.Cu")
		(net "P3V3_STBY")
	)
	(segment
		(start 175.006 -127.8255)
		(end 175.006 -128.9812)
		(width 0.508)
		(layer "F.Cu")
		(net "P3V3_STBY")
	)
	(segment
		(start 86.599268 -135.890508)
		(end 86.599268 -135.121904)
		(width 0.508)
		(layer "F.Cu")
		(net "P3V3_STBY")
	)
	(segment
		(start 30.468062 -154.893772)
		(end 30.3784 -154.80411)
		(width 0.508)
		(layer "F.Cu")
		(net "P3V3_STBY")
	)
	(segment
		(start 83.312 -171.0309)
		(end 82.9564 -171.0309)
		(width 0.508)
		(layer "F.Cu")
		(net "P3V3_STBY")
	)
	(segment
		(start 68.1355 -118.1862)
		(end 65.806066 -118.1862)
		(width 0.508)
		(layer "F.Cu")
		(net "P3V3_STBY")
	)
	(segment
		(start 63.7921 -148.7678)
		(end 64.389 -148.7678)
		(width 0.508)
		(layer "F.Cu")
		(net "P3V3_STBY")
	)
	(segment
		(start 76.928726 -140.627862)
		(end 78.18628 -140.627862)
		(width 0.508)
		(layer "F.Cu")
		(net "P3V3_STBY")
	)
	(segment
		(start 9.85012 -13.08354)
		(end 9.85012 -13.98778)
		(width 0.508)
		(layer "F.Cu")
		(net "P3V3_STBY")
	)
	(segment
		(start 84.88426 -150.38324)
		(end 84.8995 -150.368)
		(width 0.3048)
		(layer "F.Cu")
		(net "P3V3_STBY")
	)
	(segment
		(start 64.7446 -171.6024)
		(end 64.7827 -171.6405)
		(width 0.508)
		(layer "F.Cu")
		(net "P3V3_STBY")
	)
	(segment
		(start 47.308008 -121.424192)
		(end 47.3964 -121.3358)
		(width 0.508)
		(layer "F.Cu")
		(net "P3V3_STBY")
	)
	(segment
		(start 77.09408 -139.72159)
		(end 76.928726 -139.886944)
		(width 0.508)
		(layer "F.Cu")
		(net "P3V3_STBY")
	)
	(segment
		(start 151.6253 -94.094808)
		(end 151.6253 -94.8182)
		(width 0.508)
		(layer "F.Cu")
		(net "P3V3_STBY")
	)
	(segment
		(start 68.1609 -118.2116)
		(end 68.1355 -118.1862)
		(width 0.508)
		(layer "F.Cu")
		(net "P3V3_STBY")
	)
	(segment
		(start 50.90033 -141.00048)
		(end 51.299872 -141.400022)
		(width 0.3556)
		(layer "F.Cu")
		(net "P3V3_STBY")
	)
	(segment
		(start 22.614636 -15.08379)
		(end 22.614636 -15.891256)
		(width 0.508)
		(layer "F.Cu")
		(net "P3V3_STBY")
	)
	(segment
		(start 61.72708 -140.349732)
		(end 61.72708 -140.205206)
		(width 0.3048)
		(layer "F.Cu")
		(net "P3V3_STBY")
	)
	(segment
		(start 43.3578 -131.3053)
		(end 43.3578 -130.4544)
		(width 0.508)
		(layer "F.Cu")
		(net "P3V3_STBY")
	)
	(segment
		(start 90.75166 -158.56458)
		(end 89.974928 -158.56458)
		(width 0.254)
		(layer "F.Cu")
		(net "P3V3_STBY")
	)
	(segment
		(start 60.0329 -161.9504)
		(end 59.944 -162.0393)
		(width 0.508)
		(layer "F.Cu")
		(net "P3V3_STBY")
	)
	(segment
		(start 31.1531 -161.6456)
		(end 30.7213 -162.0774)
		(width 0.508)
		(layer "F.Cu")
		(net "P3V3_STBY")
	)
	(segment
		(start 65.786 -137.033)
		(end 66.2305 -137.033)
		(width 0.508)
		(layer "F.Cu")
		(net "P3V3_STBY")
	)
	(segment
		(start 44.899834 -149.400006)
		(end 44.900088 -149.400006)
		(width 0.3556)
		(layer "F.Cu")
		(net "P3V3_STBY")
	)
	(segment
		(start 46.449996 -131.303014)
		(end 46.449996 -130.452114)
		(width 0.508)
		(layer "F.Cu")
		(net "P3V3_STBY")
	)
	(segment
		(start 96.288352 -137.132822)
		(end 96.2787 -137.142474)
		(width 0.508)
		(layer "F.Cu")
		(net "P3V3_STBY")
	)
	(segment
		(start 176.9872 -120.9294)
		(end 176.9872 -121.0056)
		(width 0.508)
		(layer "F.Cu")
		(net "P3V3_STBY")
	)
	(segment
		(start 44.100242 -142.199868)
		(end 44.099988 -142.199868)
		(width 0.3556)
		(layer "F.Cu")
		(net "P3V3_STBY")
	)
	(segment
		(start 58.801 -167.4114)
		(end 59.8043 -167.4114)
		(width 0.508)
		(layer "F.Cu")
		(net "P3V3_STBY")
	)
	(segment
		(start 76.0603 -150.0886)
		(end 76.2508 -149.8981)
		(width 0.508)
		(layer "F.Cu")
		(net "P3V3_STBY")
	)
	(segment
		(start 96.288352 -136.316974)
		(end 96.288352 -137.132822)
		(width 0.508)
		(layer "F.Cu")
		(net "P3V3_STBY")
	)
	(segment
		(start 52.499514 -144.200372)
		(end 52.099972 -144.599914)
		(width 0.3556)
		(layer "F.Cu")
		(net "P3V3_STBY")
	)
	(segment
		(start 66.857626 -140.871194)
		(end 66.857626 -140.892276)
		(width 0.508)
		(layer "F.Cu")
		(net "P3V3_STBY")
	)
	(segment
		(start 57.3786 -160.1978)
		(end 57.561988 -160.1978)
		(width 0.508)
		(layer "F.Cu")
		(net "P3V3_STBY")
	)
	(segment
		(start 144.1704 -20.828)
		(end 145.034 -21.6916)
		(width 0.508)
		(layer "F.Cu")
		(net "P3V3_STBY")
	)
	(segment
		(start 11.7094 -169.3037)
		(end 11.9761 -169.037)
		(width 0.508)
		(layer "F.Cu")
		(net "P3V3_STBY")
	)
	(segment
		(start 83.760564 -138.291316)
		(end 83.262216 -138.789664)
		(width 0.508)
		(layer "F.Cu")
		(net "P3V3_STBY")
	)
	(segment
		(start 87.72652 -128.3716)
		(end 88.343994 -128.989074)
		(width 0.508)
		(layer "F.Cu")
		(net "P3V3_STBY")
	)
	(segment
		(start 51.7271 -125.8824)
		(end 52.9209 -125.8824)
		(width 0.4318)
		(layer "F.Cu")
		(net "P3V3_STBY")
	)
	(segment
		(start 72.26173 -155.73502)
		(end 71.979536 -155.452826)
		(width 0.508)
		(layer "F.Cu")
		(net "P3V3_STBY")
	)
	(segment
		(start 152.702006 -54.95036)
		(end 152.702006 -80.375252)
		(width 0.762)
		(layer "F.Cu")
		(net "P3V3_STBY")
	)
	(segment
		(start 52.959 -124.8918)
		(end 52.92598 -124.85878)
		(width 0.508)
		(layer "F.Cu")
		(net "P3V3_STBY")
	)
	(segment
		(start 76.928726 -139.886944)
		(end 76.928726 -140.627862)
		(width 0.508)
		(layer "F.Cu")
		(net "P3V3_STBY")
	)
	(segment
		(start 93.198188 -62.302136)
		(end 92.657168 -62.302136)
		(width 0.508)
		(layer "F.Cu")
		(net "P3V3_STBY")
	)
	(segment
		(start 27.2034 -173.431454)
		(end 25.120854 -175.514)
		(width 0.508)
		(layer "F.Cu")
		(net "P3V3_STBY")
	)
	(segment
		(start 44.500292 -140.20038)
		(end 44.899834 -140.599922)
		(width 0.3556)
		(layer "F.Cu")
		(net "P3V3_STBY")
	)
	(segment
		(start 196.6341 -18.3515)
		(end 196.10324 -18.3515)
		(width 0.3556)
		(layer "F.Cu")
		(net "P3V3_STBY")
	)
	(segment
		(start 44.900088 -149.400006)
		(end 45.300138 -149.800056)
		(width 0.3556)
		(layer "F.Cu")
		(net "P3V3_STBY")
	)
	(segment
		(start 64.337692 -143.019272)
		(end 63.887858 -143.019272)
		(width 0.508)
		(layer "F.Cu")
		(net "P3V3_STBY")
	)
	(segment
		(start 50.500026 -140.600176)
		(end 50.90033 -141.00048)
		(width 0.3556)
		(layer "F.Cu")
		(net "P3V3_STBY")
	)
	(segment
		(start 84.816188 -133.940042)
		(end 84.558632 -133.682486)
		(width 0.508)
		(layer "F.Cu")
		(net "P3V3_STBY")
	)
	(segment
		(start 63.74892 -146.86788)
		(end 63.7286 -146.8882)
		(width 0.508)
		(layer "F.Cu")
		(net "P3V3_STBY")
	)
	(segment
		(start 65.3542 -136.6012)
		(end 65.786 -137.033)
		(width 0.508)
		(layer "F.Cu")
		(net "P3V3_STBY")
	)
	(segment
		(start 27.2034 -172.6184)
		(end 27.2034 -173.431454)
		(width 0.508)
		(layer "F.Cu")
		(net "P3V3_STBY")
	)
	(segment
		(start 32.2453 -134.6962)
		(end 31.3182 -134.6962)
		(width 0.508)
		(layer "F.Cu")
		(net "P3V3_STBY")
	)
	(segment
		(start 45.610272 -117.791992)
		(end 43.76928 -117.791992)
		(width 0.508)
		(layer "F.Cu")
		(net "P3V3_STBY")
	)
	(segment
		(start 97.865184 -142.2781)
		(end 97.7773 -142.365984)
		(width 0.508)
		(layer "F.Cu")
		(net "P3V3_STBY")
	)
	(segment
		(start 94.591632 -159.925004)
		(end 94.25178 -159.585152)
		(width 0.254)
		(layer "F.Cu")
		(net "P3V3_STBY")
	)
	(segment
		(start 176.9618 -120.904)
		(end 176.9872 -120.9294)
		(width 0.508)
		(layer "F.Cu")
		(net "P3V3_STBY")
	)
	(segment
		(start 84.8995 -150.368)
		(end 84.8995 -149.973284)
		(width 0.508)
		(layer "F.Cu")
		(net "P3V3_STBY")
	)
	(segment
		(start 42.994326 -118.185946)
		(end 41.665906 -118.185946)
		(width 0.508)
		(layer "F.Cu")
		(net "P3V3_STBY")
	)
	(segment
		(start 68.89496 -177.18024)
		(end 68.89496 -175.9839)
		(width 0.4064)
		(layer "F.Cu")
		(net "P3V3_STBY")
	)
	(segment
		(start 147.32 -16.3957)
		(end 147.9296 -17.0053)
		(width 0.508)
		(layer "F.Cu")
		(net "P3V3_STBY")
	)
	(segment
		(start 71.374762 -164.809678)
		(end 71.60514 -164.5793)
		(width 0.508)
		(layer "F.Cu")
		(net "P3V3_STBY")
	)
	(segment
		(start 85.220048 -57.786016)
		(end 86.27999 -57.786016)
		(width 0.508)
		(layer "F.Cu")
		(net "P3V3_STBY")
	)
	(segment
		(start 82.746596 -139.046712)
		(end 82.425286 -139.368022)
		(width 0.508)
		(layer "F.Cu")
		(net "P3V3_STBY")
	)
	(segment
		(start 77.48778 -133.352794)
		(end 75.847194 -133.352794)
		(width 0.254)
		(layer "F.Cu")
		(net "P3V3_STBY")
	)
	(segment
		(start 43.78198 -117.804692)
		(end 43.37558 -117.804692)
		(width 0.508)
		(layer "F.Cu")
		(net "P3V3_STBY")
	)
	(segment
		(start 73.0504 -150.368)
		(end 74.1934 -150.368)
		(width 0.508)
		(layer "F.Cu")
		(net "P3V3_STBY")
	)
	(segment
		(start 97.84588 -177.702972)
		(end 97.84588 -177.08372)
		(width 0.508)
		(layer "F.Cu")
		(net "P3V3_STBY")
	)
	(segment
		(start 88.526366 -147.66544)
		(end 88.646 -147.66544)
		(width 0.508)
		(layer "F.Cu")
		(net "P3V3_STBY")
	)
	(segment
		(start 74.1934 -150.368)
		(end 74.4728 -150.0886)
		(width 0.508)
		(layer "F.Cu")
		(net "P3V3_STBY")
	)
	(segment
		(start 31.228538 -153.337006)
		(end 31.228538 -152.888442)
		(width 0.508)
		(layer "F.Cu")
		(net "P3V3_STBY")
	)
	(segment
		(start 89.3064 -148.32584)
		(end 89.3064 -148.649436)
		(width 0.508)
		(layer "F.Cu")
		(net "P3V3_STBY")
	)
	(segment
		(start 46.778418 -127.220218)
		(end 46.5074 -126.9492)
		(width 0.508)
		(layer "F.Cu")
		(net "P3V3_STBY")
	)
	(segment
		(start 46.778418 -127.745236)
		(end 46.778418 -127.220218)
		(width 0.508)
		(layer "F.Cu")
		(net "P3V3_STBY")
	)
	(segment
		(start 71.7804 -172.6184)
		(end 71.7804 -173.2661)
		(width 0.508)
		(layer "F.Cu")
		(net "P3V3_STBY")
	)
	(segment
		(start 64.4652 -174.313596)
		(end 63.777114 -174.313596)
		(width 0.4064)
		(layer "F.Cu")
		(net "P3V3_STBY")
	)
	(segment
		(start 48.099472 -141.400022)
		(end 48.09998 -141.400022)
		(width 0.254)
		(layer "F.Cu")
		(net "P3V3_STBY")
	)
	(segment
		(start 165.559486 -91.069414)
		(end 165.976046 -91.485974)
		(width 0.508)
		(layer "F.Cu")
		(net "P3V3_STBY")
	)
	(segment
		(start 167.4622 -94.7674)
		(end 167.4622 -92.972128)
		(width 0.508)
		(layer "F.Cu")
		(net "P3V3_STBY")
	)
	(segment
		(start 54.899814 -148.999956)
		(end 54.899814 -148.999702)
		(width 0.3556)
		(layer "F.Cu")
		(net "P3V3_STBY")
	)
	(segment
		(start 86.487 -180.7845)
		(end 86.50478 -180.784246)
		(width 0.508)
		(layer "F.Cu")
		(net "P3V3_STBY")
	)
	(segment
		(start 9.85012 -13.98778)
		(end 9.80186 -14.03604)
		(width 0.508)
		(layer "F.Cu")
		(net "P3V3_STBY")
	)
	(segment
		(start 89.90076 -178.42484)
		(end 89.86012 -178.46548)
		(width 0.508)
		(layer "F.Cu")
		(net "P3V3_STBY")
	)
	(segment
		(start 69.088 -116.5225)
		(end 68.9483 -116.3828)
		(width 0.508)
		(layer "F.Cu")
		(net "P3V3_STBY")
	)
	(segment
		(start 194.37604 -14.410944)
		(end 195.157344 -13.62964)
		(width 0.4064)
		(layer "F.Cu")
		(net "P3V3_STBY")
	)
	(segment
		(start 178.7652 -116.205)
		(end 177.7746 -115.2144)
		(width 0.508)
		(layer "F.Cu")
		(net "P3V3_STBY")
	)
	(segment
		(start 81.858358 -139.368022)
		(end 81.661762 -139.368022)
		(width 0.3048)
		(layer "F.Cu")
		(net "P3V3_STBY")
	)
	(segment
		(start 57.561988 -160.1978)
		(end 58.133488 -159.6263)
		(width 0.508)
		(layer "F.Cu")
		(net "P3V3_STBY")
	)
	(segment
		(start 72.8218 -158.03626)
		(end 73.4187 -158.03626)
		(width 0.508)
		(layer "F.Cu")
		(net "P3V3_STBY")
	)
	(segment
		(start 68.8086 -170.3197)
		(end 68.8086 -169.4688)
		(width 0.508)
		(layer "F.Cu")
		(net "P3V3_STBY")
	)
	(segment
		(start 63.7921 -145.669)
		(end 63.68796 -145.77314)
		(width 0.508)
		(layer "F.Cu")
		(net "P3V3_STBY")
	)
	(segment
		(start 74.4601 -135.827008)
		(end 74.4601 -135.9535)
		(width 0.508)
		(layer "F.Cu")
		(net "P3V3_STBY")
	)
	(segment
		(start 36.068 -130.0607)
		(end 36.068 -129.18186)
		(width 0.508)
		(layer "F.Cu")
		(net "P3V3_STBY")
	)
	(segment
		(start 25.120854 -175.514)
		(end 20.9931 -175.514)
		(width 0.508)
		(layer "F.Cu")
		(net "P3V3_STBY")
	)
	(segment
		(start 151.205692 -93.6752)
		(end 151.403558 -93.873066)
		(width 0.762)
		(layer "F.Cu")
		(net "P3V3_STBY")
	)
	(segment
		(start 52.099464 -146.19986)
		(end 51.699922 -145.800318)
		(width 0.254)
		(layer "F.Cu")
		(net "P3V3_STBY")
	)
	(segment
		(start 30.2006 -132.588)
		(end 29.8958 -132.2832)
		(width 0.508)
		(layer "F.Cu")
		(net "P3V3_STBY")
	)
	(segment
		(start 161.798 -94.77883)
		(end 161.798 -94.959424)
		(width 0.508)
		(layer "F.Cu")
		(net "P3V3_STBY")
	)
	(segment
		(start 59.6265 -160.8328)
		(end 59.817 -161.0233)
		(width 0.508)
		(layer "F.Cu")
		(net "P3V3_STBY")
	)
	(segment
		(start 37.112448 -129.390648)
		(end 37.112448 -130.314192)
		(width 0.508)
		(layer "F.Cu")
		(net "P3V3_STBY")
	)
	(segment
		(start 87.8586 -147.7137)
		(end 88.478106 -147.7137)
		(width 0.508)
		(layer "F.Cu")
		(net "P3V3_STBY")
	)
	(segment
		(start 195.532248 -13.62964)
		(end 196.6087 -14.706092)
		(width 0.508)
		(layer "F.Cu")
		(net "P3V3_STBY")
	)
	(segment
		(start 43.76928 -117.791992)
		(end 43.78198 -117.804692)
		(width 0.508)
		(layer "F.Cu")
		(net "P3V3_STBY")
	)
	(segment
		(start 83.760564 -138.129264)
		(end 83.760564 -138.291316)
		(width 0.508)
		(layer "F.Cu")
		(net "P3V3_STBY")
	)
	(segment
		(start 89.86012 -178.77028)
		(end 89.86012 -178.46548)
		(width 0.508)
		(layer "F.Cu")
		(net "P3V3_STBY")
	)
	(segment
		(start 70.724522 -164.412422)
		(end 69.6341 -163.322)
		(width 0.508)
		(layer "F.Cu")
		(net "P3V3_STBY")
	)
	(segment
		(start 160.273746 -50.1777)
		(end 157.47492 -50.1777)
		(width 0.762)
		(layer "F.Cu")
		(net "P3V3_STBY")
	)
	(segment
		(start 82.9564 -171.0309)
		(end 81.7372 -172.2501)
		(width 0.508)
		(layer "F.Cu")
		(net "P3V3_STBY")
	)
	(segment
		(start 64.7192 -175.1076)
		(end 64.7192 -174.567596)
		(width 0.4064)
		(layer "F.Cu")
		(net "P3V3_STBY")
	)
	(segment
		(start 95.621856 -155.60548)
		(end 97.037398 -155.60548)
		(width 0.254)
		(layer "F.Cu")
		(net "P3V3_STBY")
	)
	(segment
		(start 75.7809 -133.2865)
		(end 75.7809 -132.454142)
		(width 0.508)
		(layer "F.Cu")
		(net "P3V3_STBY")
	)
	(segment
		(start 63.885064 -143.022066)
		(end 63.887858 -143.019272)
		(width 0.508)
		(layer "F.Cu")
		(net "P3V3_STBY")
	)
	(segment
		(start 62.418722 -135.331708)
		(end 62.418722 -134.148322)
		(width 0.508)
		(layer "F.Cu")
		(net "P3V3_STBY")
	)
	(segment
		(start 196.6087 -17.005554)
		(end 196.6087 -16.764)
		(width 0.508)
		(layer "F.Cu")
		(net "P3V3_STBY")
	)
	(segment
		(start 31.33598 -153.444448)
		(end 31.228538 -153.337006)
		(width 0.508)
		(layer "F.Cu")
		(net "P3V3_STBY")
	)
	(segment
		(start 59.817 -161.7345)
		(end 60.0329 -161.9504)
		(width 0.508)
		(layer "F.Cu")
		(net "P3V3_STBY")
	)
	(segment
		(start 63.68796 -145.77314)
		(end 63.68796 -146.84756)
		(width 0.508)
		(layer "F.Cu")
		(net "P3V3_STBY")
	)
	(segment
		(start 64.7827 -171.6405)
		(end 65.659 -171.6405)
		(width 0.508)
		(layer "F.Cu")
		(net "P3V3_STBY")
	)
	(segment
		(start 83.238848 -138.789664)
		(end 82.9818 -139.046712)
		(width 0.508)
		(layer "F.Cu")
		(net "P3V3_STBY")
	)
	(segment
		(start 63.867284 -141.417294)
		(end 63.867284 -140.653516)
		(width 0.508)
		(layer "F.Cu")
		(net "P3V3_STBY")
	)
	(segment
		(start 92.116148 -61.761116)
		(end 91.895168 -61.761116)
		(width 0.508)
		(layer "F.Cu")
		(net "P3V3_STBY")
	)
	(segment
		(start 58.133488 -159.6263)
		(end 58.3946 -159.6263)
		(width 0.508)
		(layer "F.Cu")
		(net "P3V3_STBY")
	)
	(segment
		(start 86.27999 -57.786016)
		(end 86.410038 -57.655968)
		(width 0.508)
		(layer "F.Cu")
		(net "P3V3_STBY")
	)
	(segment
		(start 59.817 -161.0233)
		(end 59.817 -161.7345)
		(width 0.508)
		(layer "F.Cu")
		(net "P3V3_STBY")
	)
	(segment
		(start 57.928764 -167.377618)
		(end 58.767218 -167.377618)
		(width 0.508)
		(layer "F.Cu")
		(net "P3V3_STBY")
	)
	(segment
		(start 82.209894 -132.72135)
		(end 82.584544 -132.72135)
		(width 0.3556)
		(layer "F.Cu")
		(net "P3V3_STBY")
	)
	(segment
		(start 46.100492 -140.20038)
		(end 46.500034 -140.599922)
		(width 0.3556)
		(layer "F.Cu")
		(net "P3V3_STBY")
	)
	(segment
		(start 97.59188 -177.956972)
		(end 97.84588 -177.702972)
		(width 0.508)
		(layer "F.Cu")
		(net "P3V3_STBY")
	)
	(segment
		(start 73.400158 -134.767066)
		(end 74.4601 -135.827008)
		(width 0.508)
		(layer "F.Cu")
		(net "P3V3_STBY")
	)
	(segment
		(start 52.280058 -175.329342)
		(end 52.5018 -175.551084)
		(width 0.3556)
		(layer "F.Cu")
		(net "P3V3_STBY")
	)
	(segment
		(start 78.972156 -141.413738)
		(end 79.710534 -141.413738)
		(width 0.3048)
		(layer "F.Cu")
		(net "P3V3_STBY")
	)
	(segment
		(start 92.18168 -125.3617)
		(end 91.92768 -125.1077)
		(width 0.3556)
		(layer "F.Cu")
		(net "P3V3_STBY")
	)
	(segment
		(start 80.73898 -133.352794)
		(end 81.57845 -133.352794)
		(width 0.3556)
		(layer "F.Cu")
		(net "P3V3_STBY")
	)
	(segment
		(start 74.0918 -187.198)
		(end 74.0918 -186.3471)
		(width 0.508)
		(layer "F.Cu")
		(net "P3V3_STBY")
	)
	(segment
		(start 89.974928 -158.56458)
		(end 89.5096 -159.029908)
		(width 0.254)
		(layer "F.Cu")
		(net "P3V3_STBY")
	)
	(segment
		(start 58.767218 -167.377618)
		(end 58.801 -167.4114)
		(width 0.508)
		(layer "F.Cu")
		(net "P3V3_STBY")
	)
	(segment
		(start 35.7378 -166.0017)
		(end 35.7378 -167.0558)
		(width 0.508)
		(layer "F.Cu")
		(net "P3V3_STBY")
	)
	(segment
		(start 75.2602 -150.0886)
		(end 75.28941 -150.11781)
		(width 0.508)
		(layer "F.Cu")
		(net "P3V3_STBY")
	)
	(segment
		(start 87.736426 -179.5526)
		(end 89.0778 -179.5526)
		(width 0.508)
		(layer "F.Cu")
		(net "P3V3_STBY")
	)
	(segment
		(start 151.403558 -93.873066)
		(end 151.6253 -94.094808)
		(width 0.508)
		(layer "F.Cu")
		(net "P3V3_STBY")
	)
	(segment
		(start 90.24112 -124.27712)
		(end 90.7923 -124.8283)
		(width 0.508)
		(layer "F.Cu")
		(net "P3V3_STBY")
	)
	(segment
		(start 96.7359 -137.599674)
		(end 96.7359 -137.9474)
		(width 0.508)
		(layer "F.Cu")
		(net "P3V3_STBY")
	)
	(segment
		(start 83.558888 -47.191168)
		(end 84.276438 -46.473618)
		(width 0.508)
		(layer "F.Cu")
		(net "P3V3_STBY")
	)
	(segment
		(start 145.034 -21.6916)
		(end 147.9042 -21.6916)
		(width 0.508)
		(layer "F.Cu")
		(net "P3V3_STBY")
	)
	(segment
		(start 75.847194 -133.352794)
		(end 75.7809 -133.2865)
		(width 0.254)
		(layer "F.Cu")
		(net "P3V3_STBY")
	)
	(segment
		(start 91.64828 -147.854924)
		(end 91.64828 -149.043644)
		(width 0.508)
		(layer "F.Cu")
		(net "P3V3_STBY")
	)
	(segment
		(start 65.614296 -139.629896)
		(end 65.614296 -140.223494)
		(width 0.508)
		(layer "F.Cu")
		(net "P3V3_STBY")
	)
	(segment
		(start 91.6432 -124.9045)
		(end 90.8685 -124.9045)
		(width 0.3556)
		(layer "F.Cu")
		(net "P3V3_STBY")
	)
	(segment
		(start 52.099972 -145.400268)
		(end 52.099972 -145.400014)
		(width 0.254)
		(layer "F.Cu")
		(net "P3V3_STBY")
	)
	(segment
		(start 93.05036 -125.3617)
		(end 92.18168 -125.3617)
		(width 0.3556)
		(layer "F.Cu")
		(net "P3V3_STBY")
	)
	(segment
		(start 93.8022 -129.2098)
		(end 94.766384 -129.2098)
		(width 0.254)
		(layer "F.Cu")
		(net "P3V3_STBY")
	)
	(segment
		(start 69.0499 -124.5362)
		(end 70.0278 -124.5362)
		(width 0.508)
		(layer "F.Cu")
		(net "P3V3_STBY")
	)
	(segment
		(start 83.1215 -150.38324)
		(end 84.88426 -150.38324)
		(width 0.3048)
		(layer "F.Cu")
		(net "P3V3_STBY")
	)
	(segment
		(start 87.702898 -136.527286)
		(end 87.236046 -136.527286)
		(width 0.508)
		(layer "F.Cu")
		(net "P3V3_STBY")
	)
	(segment
		(start 95.15094 -176.657)
		(end 96.356932 -176.657)
		(width 0.3556)
		(layer "F.Cu")
		(net "P3V3_STBY")
	)
	(segment
		(start 45.300138 -140.20038)
		(end 45.300392 -140.20038)
		(width 0.3556)
		(layer "F.Cu")
		(net "P3V3_STBY")
	)
	(segment
		(start 41.8592 -161.8107)
		(end 41.8592 -162.6108)
		(width 0.508)
		(layer "F.Cu")
		(net "P3V3_STBY")
	)
	(segment
		(start 52.15763 -177.38217)
		(end 51.875944 -177.38217)
		(width 0.3556)
		(layer "F.Cu")
		(net "P3V3_STBY")
	)
	(segment
		(start 54.899814 -148.999702)
		(end 54.500018 -148.599906)
		(width 0.3556)
		(layer "F.Cu")
		(net "P3V3_STBY")
	)
	(segment
		(start 52.099972 -148.599906)
		(end 52.499768 -148.20011)
		(width 0.254)
		(layer "F.Cu")
		(net "P3V3_STBY")
	)
	(segment
		(start 52.280058 -174.994824)
		(end 52.280058 -175.329342)
		(width 0.3556)
		(layer "F.Cu")
		(net "P3V3_STBY")
	)
	(segment
		(start 74.4728 -150.0886)
		(end 75.2602 -150.0886)
		(width 0.508)
		(layer "F.Cu")
		(net "P3V3_STBY")
	)
	(segment
		(start 88.646 -147.66544)
		(end 89.3064 -148.32584)
		(width 0.508)
		(layer "F.Cu")
		(net "P3V3_STBY")
	)
	(segment
		(start 196.6087 -14.706092)
		(end 196.6087 -16.764)
		(width 0.508)
		(layer "F.Cu")
		(net "P3V3_STBY")
	)
	(segment
		(start 191.287146 -133.735064)
		(end 191.287146 -134.691628)
		(width 0.508)
		(layer "F.Cu")
		(net "P3V3_STBY")
	)
	(segment
		(start 81.57845 -133.352794)
		(end 82.209894 -132.72135)
		(width 0.3556)
		(layer "F.Cu")
		(net "P3V3_STBY")
	)
	(segment
		(start 52.9971 -125.8062)
		(end 52.959 -125.7681)
		(width 0.508)
		(layer "F.Cu")
		(net "P3V3_STBY")
	)
	(segment
		(start 11.7094 -170.569636)
		(end 11.7094 -169.3037)
		(width 0.508)
		(layer "F.Cu")
		(net "P3V3_STBY")
	)
	(segment
		(start 52.499514 -143.400526)
		(end 52.099972 -143.800068)
		(width 0.3556)
		(layer "F.Cu")
		(net "P3V3_STBY")
	)
	(segment
		(start 71.200264 -141.59992)
		(end 70.311518 -141.59992)
		(width 0.508)
		(layer "F.Cu")
		(net "P3V3_STBY")
	)
	(segment
		(start 161.203894 -94.184724)
		(end 161.798 -94.77883)
		(width 0.508)
		(layer "F.Cu")
		(net "P3V3_STBY")
	)
	(segment
		(start 36.068 -129.18186)
		(end 36.06292 -129.18186)
		(width 0.508)
		(layer "F.Cu")
		(net "P3V3_STBY")
	)
	(segment
		(start 62.418722 -139.513564)
		(end 62.418722 -138.928602)
		(width 0.3048)
		(layer "F.Cu")
		(net "P3V3_STBY")
	)
	(segment
		(start 30.7213 -162.0774)
		(end 30.099 -162.0774)
		(width 0.508)
		(layer "F.Cu")
		(net "P3V3_STBY")
	)
	(segment
		(start 47.69993 -141.00048)
		(end 48.099472 -141.400022)
		(width 0.254)
		(layer "F.Cu")
		(net "P3V3_STBY")
	)
	(segment
		(start 45.432726 -131.303522)
		(end 45.432726 -130.452622)
		(width 0.508)
		(layer "F.Cu")
		(net "P3V3_STBY")
	)
	(segment
		(start 95.06331 -129.506726)
		(end 95.945706 -129.506726)
		(width 0.254)
		(layer "F.Cu")
		(net "P3V3_STBY")
	)
	(segment
		(start 142.9385 -20.828)
		(end 144.1704 -20.828)
		(width 0.508)
		(layer "F.Cu")
		(net "P3V3_STBY")
	)
	(segment
		(start 52.5018 -177.038)
		(end 52.15763 -177.38217)
		(width 0.3556)
		(layer "F.Cu")
		(net "P3V3_STBY")
	)
	(segment
		(start 96.7359 -137.9474)
		(end 96.7105 -137.9728)
		(width 0.508)
		(layer "F.Cu")
		(net "P3V3_STBY")
	)
	(segment
		(start 85.834474 -137.060686)
		(end 86.80196 -136.0932)
		(width 0.508)
		(layer "F.Cu")
		(net "P3V3_STBY")
	)
	(segment
		(start 52.499768 -141.800326)
		(end 52.499514 -141.800326)
		(width 0.3556)
		(layer "F.Cu")
		(net "P3V3_STBY")
	)
	(segment
		(start 68.20408 -182.73268)
		(end 68.95338 -182.73268)
		(width 0.508)
		(layer "F.Cu")
		(net "P3V3_STBY")
	)
	(segment
		(start 41.91 -162.6616)
		(end 41.8592 -162.6108)
		(width 0.508)
		(layer "F.Cu")
		(net "P3V3_STBY")
	)
	(segment
		(start 81.661762 -139.368022)
		(end 81.06029 -138.76655)
		(width 0.3048)
		(layer "F.Cu")
		(net "P3V3_STBY")
	)
	(segment
		(start 33.5534 -165.4683)
		(end 33.5534 -166.3192)
		(width 0.508)
		(layer "F.Cu")
		(net "P3V3_STBY")
	)
	(segment
		(start 64.91478 -156.624274)
		(end 64.077088 -156.624274)
		(width 0.508)
		(layer "F.Cu")
		(net "P3V3_STBY")
	)
	(segment
		(start 67.0941 -140.63472)
		(end 66.857626 -140.871194)
		(width 0.508)
		(layer "F.Cu")
		(net "P3V3_STBY")
	)
	(segment
		(start 62.418722 -134.148322)
		(end 62.2046 -133.9342)
		(width 0.508)
		(layer "F.Cu")
		(net "P3V3_STBY")
	)
	(segment
		(start 97.037398 -155.60548)
		(end 97.12452 -155.518358)
		(width 0.254)
		(layer "F.Cu")
		(net "P3V3_STBY")
	)
	(segment
		(start 197.5358 -17.932654)
		(end 196.6087 -17.005554)
		(width 0.508)
		(layer "F.Cu")
		(net "P3V3_STBY")
	)
	(via
		(at 33.2232 -166.6494)
		(size 0.508)
		(drill 0.254)
		(layers "F.Cu" "B.Cu")
		(net "P3V3_STBY")
	)
	(via
		(at 48.133 -162.4838)
		(size 0.508)
		(drill 0.254)
		(layers "F.Cu" "B.Cu")
		(net "P3V3_STBY")
	)
	(via
		(at 46.100238 -140.20038)
		(size 0.4572)
		(drill 0.2032)
		(layers "F.Cu" "B.Cu")
		(net "P3V3_STBY")
	)
	(via
		(at 77.09408 -139.72159)
		(size 0.508)
		(drill 0.254)
		(layers "F.Cu" "B.Cu")
		(net "P3V3_STBY")
	)
	(via
		(at 68.20408 -182.73268)
		(size 0.508)
		(drill 0.254)
		(layers "F.Cu" "B.Cu")
		(net "P3V3_STBY")
	)
	(via
		(at 70.724522 -164.809678)
		(size 0.508)
		(drill 0.254)
		(layers "F.Cu" "B.Cu")
		(net "P3V3_STBY")
	)
	(via
		(at 65.3542 -136.525)
		(size 0.508)
		(drill 0.254)
		(layers "F.Cu" "B.Cu")
		(net "P3V3_STBY")
	)
	(via
		(at 68.3768 -177.6984)
		(size 0.508)
		(drill 0.254)
		(layers "F.Cu" "B.Cu")
		(net "P3V3_STBY")
	)
	(via
		(at 69.088 -117.2972)
		(size 0.508)
		(drill 0.254)
		(layers "F.Cu" "B.Cu")
		(net "P3V3_STBY")
	)
	(via
		(at 63.373 -185.1914)
		(size 0.7112)
		(drill 0.4064)
		(layers "F.Cu" "B.Cu")
		(net "P3V3_STBY")
	)
	(via
		(at 195.880736 -130.788664)
		(size 0.508)
		(drill 0.254)
		(layers "F.Cu" "B.Cu")
		(net "P3V3_STBY")
	)
	(via
		(at 74.0918 -187.198)
		(size 0.508)
		(drill 0.254)
		(layers "F.Cu" "B.Cu")
		(net "P3V3_STBY")
	)
	(via
		(at 57.3786 -160.1978)
		(size 0.508)
		(drill 0.254)
		(layers "F.Cu" "B.Cu")
		(net "P3V3_STBY")
	)
	(via
		(at 58.801 -167.4114)
		(size 0.508)
		(drill 0.254)
		(layers "F.Cu" "B.Cu")
		(net "P3V3_STBY")
	)
	(via
		(at 98.12147 -147.738338)
		(size 0.508)
		(drill 0.254)
		(layers "F.Cu" "B.Cu")
		(net "P3V3_STBY")
	)
	(via
		(at 57.949846 -152.423876)
		(size 0.508)
		(drill 0.254)
		(layers "F.Cu" "B.Cu")
		(net "P3V3_STBY")
	)
	(via
		(at 43.942 -162.6616)
		(size 0.508)
		(drill 0.254)
		(layers "F.Cu" "B.Cu")
		(net "P3V3_STBY")
	)
	(via
		(at 91.895168 -61.761116)
		(size 0.508)
		(drill 0.254)
		(layers "F.Cu" "B.Cu")
		(net "P3V3_STBY")
	)
	(via
		(at 69.4436 -150.089108)
		(size 0.508)
		(drill 0.254)
		(layers "F.Cu" "B.Cu")
		(net "P3V3_STBY")
	)
	(via
		(at 52.499768 -148.20011)
		(size 0.4572)
		(drill 0.2032)
		(layers "F.Cu" "B.Cu")
		(net "P3V3_STBY")
	)
	(via
		(at 51.023266 -156.143706)
		(size 0.508)
		(drill 0.254)
		(layers "F.Cu" "B.Cu")
		(net "P3V3_STBY")
	)
	(via
		(at 50.90033 -141.00048)
		(size 0.4572)
		(drill 0.2032)
		(layers "F.Cu" "B.Cu")
		(net "P3V3_STBY")
	)
	(via
		(at 177.7746 -115.2144)
		(size 0.508)
		(drill 0.254)
		(layers "F.Cu" "B.Cu")
		(net "P3V3_STBY")
	)
	(via
		(at 47.69993 -141.00048)
		(size 0.4572)
		(drill 0.2032)
		(layers "F.Cu" "B.Cu")
		(net "P3V3_STBY")
	)
	(via
		(at 72.8218 -158.03626)
		(size 0.508)
		(drill 0.254)
		(layers "F.Cu" "B.Cu")
		(net "P3V3_STBY")
	)
	(via
		(at 40.2336 -130.4544)
		(size 0.508)
		(drill 0.254)
		(layers "F.Cu" "B.Cu")
		(net "P3V3_STBY")
	)
	(via
		(at 26.90368 -121.182892)
		(size 0.508)
		(drill 0.254)
		(layers "F.Cu" "B.Cu")
		(net "P3V3_STBY")
	)
	(via
		(at 71.374 -172.212)
		(size 0.508)
		(drill 0.254)
		(layers "F.Cu" "B.Cu")
		(net "P3V3_STBY")
	)
	(via
		(at 59.5122 -147.9042)
		(size 0.508)
		(drill 0.254)
		(layers "F.Cu" "B.Cu")
		(net "P3V3_STBY")
	)
	(via
		(at 64.65062 -143.3322)
		(size 0.508)
		(drill 0.254)
		(layers "F.Cu" "B.Cu")
		(net "P3V3_STBY")
	)
	(via
		(at 65.776348 -156.561536)
		(size 0.508)
		(drill 0.254)
		(layers "F.Cu" "B.Cu")
		(net "P3V3_STBY")
	)
	(via
		(at 78.867 -184.404)
		(size 0.7112)
		(drill 0.4064)
		(layers "F.Cu" "B.Cu")
		(net "P3V3_STBY")
	)
	(via
		(at 58.7248 -146.5072)
		(size 0.508)
		(drill 0.254)
		(layers "F.Cu" "B.Cu")
		(net "P3V3_STBY")
	)
	(via
		(at 52.92598 -124.85878)
		(size 0.508)
		(drill 0.254)
		(layers "F.Cu" "B.Cu")
		(net "P3V3_STBY")
	)
	(via
		(at 79.17561 -5.180838)
		(size 0.508)
		(drill 0.254)
		(layers "F.Cu" "B.Cu")
		(net "P3V3_STBY")
	)
	(via
		(at 25.9715 -115.57)
		(size 0.508)
		(drill 0.254)
		(layers "F.Cu" "B.Cu")
		(net "P3V3_STBY")
	)
	(via
		(at 64.7192 -175.1076)
		(size 0.508)
		(drill 0.254)
		(layers "F.Cu" "B.Cu")
		(net "P3V3_STBY")
	)
	(via
		(at 46.5074 -126.9492)
		(size 0.508)
		(drill 0.254)
		(layers "F.Cu" "B.Cu")
		(net "P3V3_STBY")
	)
	(via
		(at 61.64834 -153.57348)
		(size 0.508)
		(drill 0.254)
		(layers "F.Cu" "B.Cu")
		(net "P3V3_STBY")
	)
	(via
		(at 35.7378 -167.0558)
		(size 0.508)
		(drill 0.254)
		(layers "F.Cu" "B.Cu")
		(net "P3V3_STBY")
	)
	(via
		(at 86.604094 -129.9464)
		(size 0.508)
		(drill 0.254)
		(layers "F.Cu" "B.Cu")
		(net "P3V3_STBY")
	)
	(via
		(at 58.784236 -142.962376)
		(size 0.508)
		(drill 0.254)
		(layers "F.Cu" "B.Cu")
		(net "P3V3_STBY")
	)
	(via
		(at 40.1574 -125.222)
		(size 0.508)
		(drill 0.254)
		(layers "F.Cu" "B.Cu")
		(net "P3V3_STBY")
	)
	(via
		(at 66.856864 -140.893038)
		(size 0.508)
		(drill 0.254)
		(layers "F.Cu" "B.Cu")
		(net "P3V3_STBY")
	)
	(via
		(at 82.746596 -139.046712)
		(size 0.508)
		(drill 0.254)
		(layers "F.Cu" "B.Cu")
		(net "P3V3_STBY")
	)
	(via
		(at 85.060028 -54.831996)
		(size 0.7112)
		(drill 0.4064)
		(layers "F.Cu" "B.Cu")
		(net "P3V3_STBY")
	)
	(via
		(at 87.4776 -128.3716)
		(size 0.508)
		(drill 0.254)
		(layers "F.Cu" "B.Cu")
		(net "P3V3_STBY")
	)
	(via
		(at 148.4757 -20.5105)
		(size 0.508)
		(drill 0.254)
		(layers "F.Cu" "B.Cu")
		(net "P3V3_STBY")
	)
	(via
		(at 72.69353 -134.767066)
		(size 0.508)
		(drill 0.254)
		(layers "F.Cu" "B.Cu")
		(net "P3V3_STBY")
	)
	(via
		(at 52.5018 -176.6316)
		(size 0.508)
		(drill 0.254)
		(layers "F.Cu" "B.Cu")
		(net "P3V3_STBY")
	)
	(via
		(at 52.499768 -142.600426)
		(size 0.4572)
		(drill 0.2032)
		(layers "F.Cu" "B.Cu")
		(net "P3V3_STBY")
	)
	(via
		(at 87.777828 -96.741996)
		(size 0.508)
		(drill 0.254)
		(layers "F.Cu" "B.Cu")
		(net "P3V3_STBY")
	)
	(via
		(at 53.299614 -151.400002)
		(size 0.4572)
		(drill 0.2032)
		(layers "F.Cu" "B.Cu")
		(net "P3V3_STBY")
	)
	(via
		(at 97.282 -146.558)
		(size 0.508)
		(drill 0.254)
		(layers "F.Cu" "B.Cu")
		(net "P3V3_STBY")
	)
	(via
		(at 51.699922 -145.800318)
		(size 0.4572)
		(drill 0.2032)
		(layers "F.Cu" "B.Cu")
		(net "P3V3_STBY")
	)
	(via
		(at 29.7688 -125.7808)
		(size 0.508)
		(drill 0.254)
		(layers "F.Cu" "B.Cu")
		(net "P3V3_STBY")
	)
	(via
		(at 167.4622 -94.7674)
		(size 0.508)
		(drill 0.254)
		(layers "F.Cu" "B.Cu")
		(net "P3V3_STBY")
	)
	(via
		(at 77.3176 -168.9354)
		(size 0.508)
		(drill 0.254)
		(layers "F.Cu" "B.Cu")
		(net "P3V3_STBY")
	)
	(via
		(at 68.585334 -139.546076)
		(size 0.508)
		(drill 0.254)
		(layers "F.Cu" "B.Cu")
		(net "P3V3_STBY")
	)
	(via
		(at 44.500038 -141.800072)
		(size 0.4572)
		(drill 0.2032)
		(layers "F.Cu" "B.Cu")
		(net "P3V3_STBY")
	)
	(via
		(at 195.532248 -13.62964)
		(size 0.508)
		(drill 0.254)
		(layers "F.Cu" "B.Cu")
		(net "P3V3_STBY")
	)
	(via
		(at 57.9501 -133.5405)
		(size 0.508)
		(drill 0.254)
		(layers "F.Cu" "B.Cu")
		(net "P3V3_STBY")
	)
	(via
		(at 198.628 -128.4224)
		(size 0.508)
		(drill 0.254)
		(layers "F.Cu" "B.Cu")
		(net "P3V3_STBY")
	)
	(via
		(at 27.2034 -172.6184)
		(size 0.508)
		(drill 0.254)
		(layers "F.Cu" "B.Cu")
		(net "P3V3_STBY")
	)
	(via
		(at 71.284084 -141.5161)
		(size 0.508)
		(drill 0.254)
		(layers "F.Cu" "B.Cu")
		(net "P3V3_STBY")
	)
	(via
		(at 176.9872 -121.0056)
		(size 0.508)
		(drill 0.254)
		(layers "F.Cu" "B.Cu")
		(net "P3V3_STBY")
	)
	(via
		(at 43.78198 -117.804692)
		(size 0.508)
		(drill 0.254)
		(layers "F.Cu" "B.Cu")
		(net "P3V3_STBY")
	)
	(via
		(at 44.4246 -126.9492)
		(size 0.508)
		(drill 0.254)
		(layers "F.Cu" "B.Cu")
		(net "P3V3_STBY")
	)
	(via
		(at 161.798 -94.959424)
		(size 0.508)
		(drill 0.254)
		(layers "F.Cu" "B.Cu")
		(net "P3V3_STBY")
	)
	(via
		(at 86.80196 -136.0932)
		(size 0.508)
		(drill 0.254)
		(layers "F.Cu" "B.Cu")
		(net "P3V3_STBY")
	)
	(via
		(at 77.597 -184.404)
		(size 0.7112)
		(drill 0.4064)
		(layers "F.Cu" "B.Cu")
		(net "P3V3_STBY")
	)
	(via
		(at 30.099 -162.0774)
		(size 0.508)
		(drill 0.254)
		(layers "F.Cu" "B.Cu")
		(net "P3V3_STBY")
	)
	(via
		(at 93.3704 -176.9872)
		(size 0.508)
		(drill 0.254)
		(layers "F.Cu" "B.Cu")
		(net "P3V3_STBY")
	)
	(via
		(at 64.7827 -171.6405)
		(size 0.508)
		(drill 0.254)
		(layers "F.Cu" "B.Cu")
		(net "P3V3_STBY")
	)
	(via
		(at 91.764866 -147.738338)
		(size 0.508)
		(drill 0.254)
		(layers "F.Cu" "B.Cu")
		(net "P3V3_STBY")
	)
	(via
		(at 31.3182 -134.6962)
		(size 0.508)
		(drill 0.254)
		(layers "F.Cu" "B.Cu")
		(net "P3V3_STBY")
	)
	(via
		(at 72.26173 -155.73502)
		(size 0.508)
		(drill 0.254)
		(layers "F.Cu" "B.Cu")
		(net "P3V3_STBY")
	)
	(via
		(at 24.799798 -125.194314)
		(size 0.508)
		(drill 0.254)
		(layers "F.Cu" "B.Cu")
		(net "P3V3_STBY")
	)
	(via
		(at 85.09 -57.655968)
		(size 0.508)
		(drill 0.254)
		(layers "F.Cu" "B.Cu")
		(net "P3V3_STBY")
	)
	(via
		(at 203.907644 -14.5161)
		(size 0.508)
		(drill 0.254)
		(layers "F.Cu" "B.Cu")
		(net "P3V3_STBY")
	)
	(via
		(at 70.0278 -124.5362)
		(size 0.508)
		(drill 0.254)
		(layers "F.Cu" "B.Cu")
		(net "P3V3_STBY")
	)
	(via
		(at 78.867 -183.134)
		(size 0.7112)
		(drill 0.4064)
		(layers "F.Cu" "B.Cu")
		(net "P3V3_STBY")
	)
	(via
		(at 94.713552 -52.837588)
		(size 0.508)
		(drill 0.254)
		(layers "F.Cu" "B.Cu")
		(net "P3V3_STBY")
	)
	(via
		(at 75.77709 -132.450332)
		(size 0.508)
		(drill 0.254)
		(layers "F.Cu" "B.Cu")
		(net "P3V3_STBY")
	)
	(via
		(at 46.449996 -130.452114)
		(size 0.508)
		(drill 0.254)
		(layers "F.Cu" "B.Cu")
		(net "P3V3_STBY")
	)
	(via
		(at 43.3578 -130.4544)
		(size 0.508)
		(drill 0.254)
		(layers "F.Cu" "B.Cu")
		(net "P3V3_STBY")
	)
	(via
		(at 33.1216 -137.134346)
		(size 0.6096)
		(drill 0.3048)
		(layers "F.Cu" "B.Cu")
		(net "P3V3_STBY")
	)
	(via
		(at 93.8022 -129.2098)
		(size 0.508)
		(drill 0.254)
		(layers "F.Cu" "B.Cu")
		(net "P3V3_STBY")
	)
	(via
		(at 42.3164 -130.4544)
		(size 0.508)
		(drill 0.254)
		(layers "F.Cu" "B.Cu")
		(net "P3V3_STBY")
	)
	(via
		(at 37.133022 -121.142252)
		(size 0.508)
		(drill 0.254)
		(layers "F.Cu" "B.Cu")
		(net "P3V3_STBY")
	)
	(via
		(at 54.899814 -148.999956)
		(size 0.4572)
		(drill 0.2032)
		(layers "F.Cu" "B.Cu")
		(net "P3V3_STBY")
	)
	(via
		(at 89.59088 -152.64638)
		(size 0.508)
		(drill 0.254)
		(layers "F.Cu" "B.Cu")
		(net "P3V3_STBY")
	)
	(via
		(at 52.499768 -141.800326)
		(size 0.4572)
		(drill 0.2032)
		(layers "F.Cu" "B.Cu")
		(net "P3V3_STBY")
	)
	(via
		(at 47.396908 -116.780818)
		(size 0.508)
		(drill 0.254)
		(layers "F.Cu" "B.Cu")
		(net "P3V3_STBY")
	)
	(via
		(at 157.47492 -50.1777)
		(size 0.508)
		(drill 0.254)
		(layers "F.Cu" "B.Cu")
		(net "P3V3_STBY")
	)
	(via
		(at 77.597 -183.134)
		(size 0.7112)
		(drill 0.4064)
		(layers "F.Cu" "B.Cu")
		(net "P3V3_STBY")
	)
	(via
		(at 77.089 -147.8788)
		(size 0.508)
		(drill 0.254)
		(layers "F.Cu" "B.Cu")
		(net "P3V3_STBY")
	)
	(via
		(at 53.0098 -158.787846)
		(size 0.508)
		(drill 0.254)
		(layers "F.Cu" "B.Cu")
		(net "P3V3_STBY")
	)
	(via
		(at 49.17694 -162.57016)
		(size 0.508)
		(drill 0.254)
		(layers "F.Cu" "B.Cu")
		(net "P3V3_STBY")
	)
	(via
		(at 45.432726 -130.452622)
		(size 0.508)
		(drill 0.254)
		(layers "F.Cu" "B.Cu")
		(net "P3V3_STBY")
	)
	(via
		(at 80.38211 -181.880002)
		(size 0.508)
		(drill 0.254)
		(layers "F.Cu" "B.Cu")
		(net "P3V3_STBY")
	)
	(via
		(at 58.674 -145.2626)
		(size 0.508)
		(drill 0.254)
		(layers "F.Cu" "B.Cu")
		(net "P3V3_STBY")
	)
	(via
		(at 65.278 -139.2936)
		(size 0.508)
		(drill 0.254)
		(layers "F.Cu" "B.Cu")
		(net "P3V3_STBY")
	)
	(via
		(at 94.591632 -159.925004)
		(size 0.508)
		(drill 0.254)
		(layers "F.Cu" "B.Cu")
		(net "P3V3_STBY")
	)
	(via
		(at 31.33598 -154.1018)
		(size 0.508)
		(drill 0.254)
		(layers "F.Cu" "B.Cu")
		(net "P3V3_STBY")
	)
	(via
		(at 92.583 -133.41604)
		(size 0.508)
		(drill 0.254)
		(layers "F.Cu" "B.Cu")
		(net "P3V3_STBY")
	)
	(via
		(at 84.816188 -133.940042)
		(size 0.508)
		(drill 0.254)
		(layers "F.Cu" "B.Cu")
		(net "P3V3_STBY")
	)
	(via
		(at 89.5096 -159.029908)
		(size 0.508)
		(drill 0.254)
		(layers "F.Cu" "B.Cu")
		(net "P3V3_STBY")
	)
	(via
		(at 65.639442 -180.681122)
		(size 0.508)
		(drill 0.254)
		(layers "F.Cu" "B.Cu")
		(net "P3V3_STBY")
	)
	(via
		(at 37.158422 -120.075452)
		(size 0.508)
		(drill 0.254)
		(layers "F.Cu" "B.Cu")
		(net "P3V3_STBY")
	)
	(via
		(at 84.2518 -149.325584)
		(size 0.508)
		(drill 0.254)
		(layers "F.Cu" "B.Cu")
		(net "P3V3_STBY")
	)
	(via
		(at 64.5922 -148.971)
		(size 0.508)
		(drill 0.254)
		(layers "F.Cu" "B.Cu")
		(net "P3V3_STBY")
	)
	(via
		(at 63.373 -182.753)
		(size 0.7112)
		(drill 0.4064)
		(layers "F.Cu" "B.Cu")
		(net "P3V3_STBY")
	)
	(via
		(at 68.1609 -117.3353)
		(size 0.508)
		(drill 0.254)
		(layers "F.Cu" "B.Cu")
		(net "P3V3_STBY")
	)
	(via
		(at 63.373 -183.9722)
		(size 0.7112)
		(drill 0.4064)
		(layers "F.Cu" "B.Cu")
		(net "P3V3_STBY")
	)
	(via
		(at 86.487 -180.7845)
		(size 0.508)
		(drill 0.254)
		(layers "F.Cu" "B.Cu")
		(net "P3V3_STBY")
	)
	(via
		(at 37.1602 -127.6604)
		(size 0.508)
		(drill 0.254)
		(layers "F.Cu" "B.Cu")
		(net "P3V3_STBY")
	)
	(via
		(at 63.373 -186.4106)
		(size 0.7112)
		(drill 0.4064)
		(layers "F.Cu" "B.Cu")
		(net "P3V3_STBY")
	)
	(via
		(at 64.643 -147.193)
		(size 0.508)
		(drill 0.254)
		(layers "F.Cu" "B.Cu")
		(net "P3V3_STBY")
	)
	(via
		(at 45.300138 -140.20038)
		(size 0.4572)
		(drill 0.2032)
		(layers "F.Cu" "B.Cu")
		(net "P3V3_STBY")
	)
	(via
		(at 30.2006 -132.588)
		(size 0.508)
		(drill 0.254)
		(layers "F.Cu" "B.Cu")
		(net "P3V3_STBY")
	)
	(via
		(at 36.06292 -129.18186)
		(size 0.508)
		(drill 0.254)
		(layers "F.Cu" "B.Cu")
		(net "P3V3_STBY")
	)
	(via
		(at 39.370254 -130.481578)
		(size 0.508)
		(drill 0.254)
		(layers "F.Cu" "B.Cu")
		(net "P3V3_STBY")
	)
	(via
		(at 62.418722 -138.928602)
		(size 0.508)
		(drill 0.254)
		(layers "F.Cu" "B.Cu")
		(net "P3V3_STBY")
	)
	(via
		(at 92.1258 -140.0048)
		(size 0.508)
		(drill 0.254)
		(layers "F.Cu" "B.Cu")
		(net "P3V3_STBY")
	)
	(via
		(at 46.100238 -149.800056)
		(size 0.4572)
		(drill 0.2032)
		(layers "F.Cu" "B.Cu")
		(net "P3V3_STBY")
	)
	(via
		(at 43.392852 -122.367548)
		(size 0.508)
		(drill 0.254)
		(layers "F.Cu" "B.Cu")
		(net "P3V3_STBY")
	)
	(via
		(at 37.0586 -162.8902)
		(size 0.508)
		(drill 0.254)
		(layers "F.Cu" "B.Cu")
		(net "P3V3_STBY")
	)
	(via
		(at 175.0314 -129.0066)
		(size 0.508)
		(drill 0.254)
		(layers "F.Cu" "B.Cu")
		(net "P3V3_STBY")
	)
	(via
		(at 63.373 -187.6298)
		(size 0.7112)
		(drill 0.4064)
		(layers "F.Cu" "B.Cu")
		(net "P3V3_STBY")
	)
	(via
		(at 93.251782 -151.401018)
		(size 0.508)
		(drill 0.254)
		(layers "F.Cu" "B.Cu")
		(net "P3V3_STBY")
	)
	(via
		(at 191.287146 -134.691628)
		(size 0.508)
		(drill 0.254)
		(layers "F.Cu" "B.Cu")
		(net "P3V3_STBY")
	)
	(via
		(at 44.500038 -140.20038)
		(size 0.4572)
		(drill 0.2032)
		(layers "F.Cu" "B.Cu")
		(net "P3V3_STBY")
	)
	(via
		(at 68.8086 -169.4688)
		(size 0.508)
		(drill 0.254)
		(layers "F.Cu" "B.Cu")
		(net "P3V3_STBY")
	)
	(via
		(at 37.112448 -129.390648)
		(size 0.508)
		(drill 0.254)
		(layers "F.Cu" "B.Cu")
		(net "P3V3_STBY")
	)
	(via
		(at 54.5846 -134.4676)
		(size 0.508)
		(drill 0.254)
		(layers "F.Cu" "B.Cu")
		(net "P3V3_STBY")
	)
	(via
		(at 52.499768 -143.400526)
		(size 0.4572)
		(drill 0.2032)
		(layers "F.Cu" "B.Cu")
		(net "P3V3_STBY")
	)
	(via
		(at 44.4754 -134.3914)
		(size 0.508)
		(drill 0.254)
		(layers "F.Cu" "B.Cu")
		(net "P3V3_STBY")
	)
	(via
		(at 151.403558 -93.873066)
		(size 0.508)
		(drill 0.254)
		(layers "F.Cu" "B.Cu")
		(net "P3V3_STBY")
	)
	(via
		(at 97.7773 -142.365984)
		(size 0.508)
		(drill 0.254)
		(layers "F.Cu" "B.Cu")
		(net "P3V3_STBY")
	)
	(via
		(at 62.2046 -133.9342)
		(size 0.508)
		(drill 0.254)
		(layers "F.Cu" "B.Cu")
		(net "P3V3_STBY")
	)
	(via
		(at 9.80186 -14.03604)
		(size 0.508)
		(drill 0.254)
		(layers "F.Cu" "B.Cu")
		(net "P3V3_STBY")
	)
	(via
		(at 22.62378 -15.9004)
		(size 0.508)
		(drill 0.254)
		(layers "F.Cu" "B.Cu")
		(net "P3V3_STBY")
	)
	(via
		(at 69.469 -144.1196)
		(size 0.508)
		(drill 0.254)
		(layers "F.Cu" "B.Cu")
		(net "P3V3_STBY")
	)
	(via
		(at 59.944 -164.4396)
		(size 0.508)
		(drill 0.254)
		(layers "F.Cu" "B.Cu")
		(net "P3V3_STBY")
	)
	(via
		(at 49.299622 -148.999956)
		(size 0.4572)
		(drill 0.2032)
		(layers "F.Cu" "B.Cu")
		(net "P3V3_STBY")
	)
	(via
		(at 84.836 -97.2058)
		(size 0.508)
		(drill 0.254)
		(layers "F.Cu" "B.Cu")
		(net "P3V3_STBY")
	)
	(via
		(at 75.39609 -150.11781)
		(size 0.508)
		(drill 0.254)
		(layers "F.Cu" "B.Cu")
		(net "P3V3_STBY")
	)
	(via
		(at 91.9734 -145.9738)
		(size 0.508)
		(drill 0.254)
		(layers "F.Cu" "B.Cu")
		(net "P3V3_STBY")
	)
	(via
		(at 82.584544 -131.906264)
		(size 0.508)
		(drill 0.254)
		(layers "F.Cu" "B.Cu")
		(net "P3V3_STBY")
	)
	(via
		(at 47.3964 -121.3358)
		(size 0.508)
		(drill 0.254)
		(layers "F.Cu" "B.Cu")
		(net "P3V3_STBY")
	)
	(via
		(at 69.9516 -119.4562)
		(size 0.508)
		(drill 0.254)
		(layers "F.Cu" "B.Cu")
		(net "P3V3_STBY")
	)
	(via
		(at 30.3784 -154.1018)
		(size 0.508)
		(drill 0.254)
		(layers "F.Cu" "B.Cu")
		(net "P3V3_STBY")
	)
	(via
		(at 169.29989 -6.641846)
		(size 0.508)
		(drill 0.254)
		(layers "F.Cu" "B.Cu")
		(net "P3V3_STBY")
	)
	(via
		(at 47.498 -118.872)
		(size 0.508)
		(drill 0.254)
		(layers "F.Cu" "B.Cu")
		(net "P3V3_STBY")
	)
	(via
		(at 88.646 -147.66544)
		(size 0.508)
		(drill 0.254)
		(layers "F.Cu" "B.Cu")
		(net "P3V3_STBY")
	)
	(via
		(at 52.499768 -144.200372)
		(size 0.4572)
		(drill 0.2032)
		(layers "F.Cu" "B.Cu")
		(net "P3V3_STBY")
	)
	(via
		(at 97.59188 -177.956972)
		(size 0.508)
		(drill 0.254)
		(layers "F.Cu" "B.Cu")
		(net "P3V3_STBY")
	)
	(via
		(at 41.8592 -162.6108)
		(size 0.508)
		(drill 0.254)
		(layers "F.Cu" "B.Cu")
		(net "P3V3_STBY")
	)
	(via
		(at 77.688948 -53.343556)
		(size 0.7112)
		(drill 0.4064)
		(layers "F.Cu" "B.Cu")
		(net "P3V3_STBY")
	)
	(via
		(at 84.797138 -134.90067)
		(size 0.508)
		(drill 0.254)
		(layers "F.Cu" "B.Cu")
		(net "P3V3_STBY")
	)
	(via
		(at 163.6014 -51.6509)
		(size 0.508)
		(drill 0.254)
		(layers "F.Cu" "B.Cu")
		(net "P3V3_STBY")
	)
	(via
		(at 165.976046 -91.485974)
		(size 0.6604)
		(drill 0.3302)
		(layers "F.Cu" "B.Cu")
		(net "P3V3_STBY")
	)
	(via
		(at 48.60798 -154.48026)
		(size 0.508)
		(drill 0.254)
		(layers "F.Cu" "B.Cu")
		(net "P3V3_STBY")
	)
	(via
		(at 97.12452 -155.518358)
		(size 0.508)
		(drill 0.254)
		(layers "F.Cu" "B.Cu")
		(net "P3V3_STBY")
	)
	(via
		(at 77.4192 -130.2512)
		(size 0.508)
		(drill 0.254)
		(layers "F.Cu" "B.Cu")
		(net "P3V3_STBY")
	)
	(via
		(at 204.364336 -133.752336)
		(size 0.508)
		(drill 0.254)
		(layers "F.Cu" "B.Cu")
		(net "P3V3_STBY")
	)
	(via
		(at 88.392 -155.615894)
		(size 0.508)
		(drill 0.254)
		(layers "F.Cu" "B.Cu")
		(net "P3V3_STBY")
	)
	(via
		(at 81.7372 -172.339)
		(size 0.508)
		(drill 0.254)
		(layers "F.Cu" "B.Cu")
		(net "P3V3_STBY")
	)
	(via
		(at 64.91478 -156.624274)
		(size 0.508)
		(drill 0.254)
		(layers "F.Cu" "B.Cu")
		(net "P3V3_STBY")
	)
	(via
		(at 85.060028 -56.101996)
		(size 0.7112)
		(drill 0.4064)
		(layers "F.Cu" "B.Cu")
		(net "P3V3_STBY")
	)
	(via
		(at 63.867284 -140.653516)
		(size 0.508)
		(drill 0.254)
		(layers "F.Cu" "B.Cu")
		(net "P3V3_STBY")
	)
	(via
		(at 45.300138 -149.800056)
		(size 0.4572)
		(drill 0.2032)
		(layers "F.Cu" "B.Cu")
		(net "P3V3_STBY")
	)
	(via
		(at 90.7923 -124.8283)
		(size 0.508)
		(drill 0.254)
		(layers "F.Cu" "B.Cu")
		(net "P3V3_STBY")
	)
	(via
		(at 96.2787 -137.142474)
		(size 0.508)
		(drill 0.254)
		(layers "F.Cu" "B.Cu")
		(net "P3V3_STBY")
	)
	(via
		(at 37.158422 -117.941852)
		(size 0.508)
		(drill 0.254)
		(layers "F.Cu" "B.Cu")
		(net "P3V3_STBY")
	)
	(via
		(at 11.9761 -169.037)
		(size 0.508)
		(drill 0.254)
		(layers "F.Cu" "B.Cu")
		(net "P3V3_STBY")
	)
	(segment
		(start 52.97424 -125.89002)
		(end 53.50764 -126.42342)
		(width 0.3556)
		(layer "B.Cu")
		(net "P3V3_STBY")
	)
	(segment
		(start 147.3835 -16.49476)
		(end 149.527006 -16.49476)
		(width 0.4064)
		(layer "B.Cu")
		(net "P3V3_STBY")
	)
	(segment
		(start 92.8116 -146.3421)
		(end 92.3417 -146.3421)
		(width 0.508)
		(layer "B.Cu")
		(net "P3V3_STBY")
	)
	(segment
		(start 163.6014 -51.6509)
		(end 164.465 -51.6509)
		(width 0.508)
		(layer "B.Cu")
		(net "P3V3_STBY")
	)
	(segment
		(start 63.45301 -150.9395)
		(end 63.45301 -150.11019)
		(width 0.508)
		(layer "B.Cu")
		(net "P3V3_STBY")
	)
	(segment
		(start 95.4024 -151.9936)
		(end 95.106744 -152.289256)
		(width 0.508)
		(layer "B.Cu")
		(net "P3V3_STBY")
	)
	(segment
		(start 92.583 -133.41604)
		(end 92.39504 -133.604)
		(width 0.3556)
		(layer "B.Cu")
		(net "P3V3_STBY")
	)
	(segment
		(start 91.04122 -135.87984)
		(end 90.970608 -135.87984)
		(width 0.3556)
		(layer "B.Cu")
		(net "P3V3_STBY")
	)
	(segment
		(start 69.469 -144.1196)
		(end 69.469 -144.881854)
		(width 0.508)
		(layer "B.Cu")
		(net "P3V3_STBY")
	)
	(segment
		(start 54.6354 -134.5184)
		(end 54.5846 -134.4676)
		(width 0.508)
		(layer "B.Cu")
		(net "P3V3_STBY")
	)
	(segment
		(start 40.7035 -124.6759)
		(end 40.1574 -125.222)
		(width 0.508)
		(layer "B.Cu")
		(net "P3V3_STBY")
	)
	(segment
		(start 61.46038 -153.76144)
		(end 61.64834 -153.57348)
		(width 0.508)
		(layer "B.Cu")
		(net "P3V3_STBY")
	)
	(segment
		(start 37.1602 -126.8857)
		(end 37.1602 -127.6604)
		(width 0.508)
		(layer "B.Cu")
		(net "P3V3_STBY")
	)
	(segment
		(start 30.5689 -124.51334)
		(end 30.19806 -124.51334)
		(width 0.3556)
		(layer "B.Cu")
		(net "P3V3_STBY")
	)
	(segment
		(start 77.7875 -130.6195)
		(end 77.4192 -130.2512)
		(width 0.508)
		(layer "B.Cu")
		(net "P3V3_STBY")
	)
	(segment
		(start 91.324684 -138.48588)
		(end 91.324684 -137.88517)
		(width 0.508)
		(layer "B.Cu")
		(net "P3V3_STBY")
	)
	(segment
		(start 98.5139 -177.9778)
		(end 97.612708 -177.9778)
		(width 0.508)
		(layer "B.Cu")
		(net "P3V3_STBY")
	)
	(segment
		(start 164.465 -51.6509)
		(end 164.49421 -51.68011)
		(width 0.3048)
		(layer "B.Cu")
		(net "P3V3_STBY")
	)
	(segment
		(start 93.3704 -178.2953)
		(end 93.3704 -176.9872)
		(width 0.508)
		(layer "B.Cu")
		(net "P3V3_STBY")
	)
	(segment
		(start 93.246702 -159.081978)
		(end 93.734636 -159.081978)
		(width 0.508)
		(layer "B.Cu")
		(net "P3V3_STBY")
	)
	(segment
		(start 91.71178 -178.31816)
		(end 93.34754 -178.31816)
		(width 0.3556)
		(layer "B.Cu")
		(net "P3V3_STBY")
	)
	(segment
		(start 179.9082 -114.1095)
		(end 179.8701 -114.1476)
		(width 0.508)
		(layer "B.Cu")
		(net "P3V3_STBY")
	)
	(segment
		(start 64.528954 -143.347186)
		(end 64.651128 -143.347186)
		(width 0.508)
		(layer "B.Cu")
		(net "P3V3_STBY")
	)
	(segment
		(start 86.307422 -53.584602)
		(end 85.060028 -54.831996)
		(width 0.508)
		(layer "B.Cu")
		(net "P3V3_STBY")
	)
	(segment
		(start 89.81186 -152.4254)
		(end 91.8464 -152.4254)
		(width 0.508)
		(layer "B.Cu")
		(net "P3V3_STBY")
	)
	(segment
		(start 167.244776 -94.984824)
		(end 167.4622 -94.7674)
		(width 0.508)
		(layer "B.Cu")
		(net "P3V3_STBY")
	)
	(segment
		(start 53.04536 -124.7394)
		(end 52.92598 -124.85878)
		(width 0.508)
		(layer "B.Cu")
		(net "P3V3_STBY")
	)
	(segment
		(start 81.7372 -172.2755)
		(end 82.361786 -171.650914)
		(width 0.3556)
		(layer "B.Cu")
		(net "P3V3_STBY")
	)
	(segment
		(start 38.01491 -120.075452)
		(end 37.158422 -120.075452)
		(width 0.508)
		(layer "B.Cu")
		(net "P3V3_STBY")
	)
	(segment
		(start 64.34074 -143.5354)
		(end 64.528954 -143.347186)
		(width 0.508)
		(layer "B.Cu")
		(net "P3V3_STBY")
	)
	(segment
		(start 88.3666 -137.1092)
		(end 88.3666 -138.4808)
		(width 0.508)
		(layer "B.Cu")
		(net "P3V3_STBY")
	)
	(segment
		(start 149.7584 -16.726154)
		(end 149.542246 -16.51)
		(width 0.508)
		(layer "B.Cu")
		(net "P3V3_STBY")
	)
	(segment
		(start 91.2495 -137.4394)
		(end 91.3257 -137.5156)
		(width 0.3556)
		(layer "B.Cu")
		(net "P3V3_STBY")
	)
	(segment
		(start 82.361786 -171.650914)
		(end 82.877406 -171.650914)
		(width 0.3556)
		(layer "B.Cu")
		(net "P3V3_STBY")
	)
	(segment
		(start 149.542246 -15.8242)
		(end 150.114 -15.252446)
		(width 0.508)
		(layer "B.Cu")
		(net "P3V3_STBY")
	)
	(segment
		(start 93.1164 -175.807878)
		(end 93.1164 -176.617122)
		(width 0.508)
		(layer "B.Cu")
		(net "P3V3_STBY")
	)
	(segment
		(start 169.29989 -8.33501)
		(end 169.29989 -6.641846)
		(width 0.508)
		(layer "B.Cu")
		(net "P3V3_STBY")
	)
	(segment
		(start 168.160954 -9.4742)
		(end 168.160954 -9.473946)
		(width 0.508)
		(layer "B.Cu")
		(net "P3V3_STBY")
	)
	(segment
		(start 93.37548 -152.289256)
		(end 91.982544 -152.289256)
		(width 0.508)
		(layer "B.Cu")
		(net "P3V3_STBY")
	)
	(segment
		(start 203.513944 -14.9098)
		(end 203.907644 -14.5161)
		(width 0.508)
		(layer "B.Cu")
		(net "P3V3_STBY")
	)
	(segment
		(start 43.038522 -161.366962)
		(end 43.040808 -161.364676)
		(width 0.508)
		(layer "B.Cu")
		(net "P3V3_STBY")
	)
	(segment
		(start 94.242636 -159.576008)
		(end 94.591632 -159.925004)
		(width 0.508)
		(layer "B.Cu")
		(net "P3V3_STBY")
	)
	(segment
		(start 90.8431 -133.1849)
		(end 91.32316 -132.70484)
		(width 0.3556)
		(layer "B.Cu")
		(net "P3V3_STBY")
	)
	(segment
		(start 83.102196 -98.010472)
		(end 84.031328 -98.010472)
		(width 0.508)
		(layer "B.Cu")
		(net "P3V3_STBY")
	)
	(segment
		(start 97.992946 -142.58163)
		(end 97.992946 -145.847054)
		(width 0.508)
		(layer "B.Cu")
		(net "P3V3_STBY")
	)
	(segment
		(start 86.487 -180.8988)
		(end 85.505798 -181.880002)
		(width 0.508)
		(layer "B.Cu")
		(net "P3V3_STBY")
	)
	(segment
		(start 61.07684 -153.76144)
		(end 61.46038 -153.76144)
		(width 0.508)
		(layer "B.Cu")
		(net "P3V3_STBY")
	)
	(segment
		(start 62.418722 -138.928602)
		(end 62.3951 -138.90498)
		(width 0.508)
		(layer "B.Cu")
		(net "P3V3_STBY")
	)
	(segment
		(start 61.4553 -141.859)
		(end 61.4553 -140.8176)
		(width 0.508)
		(layer "B.Cu")
		(net "P3V3_STBY")
	)
	(segment
		(start 88.3666 -138.4808)
		(end 91.5162 -141.6304)
		(width 0.508)
		(layer "B.Cu")
		(net "P3V3_STBY")
	)
	(segment
		(start 63.4365 -143.7386)
		(end 63.6397 -143.5354)
		(width 0.508)
		(layer "B.Cu")
		(net "P3V3_STBY")
	)
	(segment
		(start 63.45301 -150.11019)
		(end 64.5922 -148.971)
		(width 0.508)
		(layer "B.Cu")
		(net "P3V3_STBY")
	)
	(segment
		(start 195.532248 -13.62964)
		(end 196.812408 -14.9098)
		(width 0.508)
		(layer "B.Cu")
		(net "P3V3_STBY")
	)
	(segment
		(start 85.67039 -51.426364)
		(end 86.227666 -51.98364)
		(width 0.508)
		(layer "B.Cu")
		(net "P3V3_STBY")
	)
	(segment
		(start 92.1258 -140.0048)
		(end 91.8972 -140.0048)
		(width 0.508)
		(layer "B.Cu")
		(net "P3V3_STBY")
	)
	(segment
		(start 81.7245 -172.3517)
		(end 81.7372 -172.339)
		(width 0.3556)
		(layer "B.Cu")
		(net "P3V3_STBY")
	)
	(segment
		(start 69.46646 -149.314408)
		(end 69.46646 -149.98954)
		(width 0.508)
		(layer "B.Cu")
		(net "P3V3_STBY")
	)
	(segment
		(start 91.68638 -175.11776)
		(end 93.52026 -175.11776)
		(width 0.3556)
		(layer "B.Cu")
		(net "P3V3_STBY")
	)
	(segment
		(start 93.3704 -176.871122)
		(end 93.3704 -176.9872)
		(width 0.508)
		(layer "B.Cu")
		(net "P3V3_STBY")
	)
	(segment
		(start 149.527006 -16.49476)
		(end 149.542246 -16.51)
		(width 0.4064)
		(layer "B.Cu")
		(net "P3V3_STBY")
	)
	(segment
		(start 48.999394 -161.721292)
		(end 48.999394 -162.392614)
		(width 0.508)
		(layer "B.Cu")
		(net "P3V3_STBY")
	)
	(segment
		(start 58.5216 -148.8186)
		(end 59.436 -147.9042)
		(width 0.508)
		(layer "B.Cu")
		(net "P3V3_STBY")
	)
	(segment
		(start 37.98951 -121.142252)
		(end 37.133022 -121.142252)
		(width 0.508)
		(layer "B.Cu")
		(net "P3V3_STBY")
	)
	(segment
		(start 91.982544 -152.289256)
		(end 91.8972 -152.3746)
		(width 0.508)
		(layer "B.Cu")
		(net "P3V3_STBY")
	)
	(segment
		(start 168.160954 -9.473946)
		(end 169.29989 -8.33501)
		(width 0.508)
		(layer "B.Cu")
		(net "P3V3_STBY")
	)
	(segment
		(start 58.414412 -143.3322)
		(end 58.784236 -142.962376)
		(width 0.508)
		(layer "B.Cu")
		(net "P3V3_STBY")
	)
	(segment
		(start 89.2048 -153.03246)
		(end 89.59088 -152.64638)
		(width 0.508)
		(layer "B.Cu")
		(net "P3V3_STBY")
	)
	(segment
		(start 59.7916 -147.9042)
		(end 59.9567 -148.0693)
		(width 0.508)
		(layer "B.Cu")
		(net "P3V3_STBY")
	)
	(segment
		(start 53.50764 -126.42342)
		(end 54.36616 -126.42342)
		(width 0.3556)
		(layer "B.Cu")
		(net "P3V3_STBY")
	)
	(segment
		(start 59.9567 -148.0693)
		(end 60.4774 -148.0693)
		(width 0.508)
		(layer "B.Cu")
		(net "P3V3_STBY")
	)
	(segment
		(start 92.8116 -129.0447)
		(end 93.6371 -129.0447)
		(width 0.508)
		(layer "B.Cu")
		(net "P3V3_STBY")
	)
	(segment
		(start 43.392852 -122.367548)
		(end 42.13479 -122.367548)
		(width 0.508)
		(layer "B.Cu")
		(net "P3V3_STBY")
	)
	(segment
		(start 28.9179 -126.3142)
		(end 29.2354 -126.3142)
		(width 0.508)
		(layer "B.Cu")
		(net "P3V3_STBY")
	)
	(segment
		(start 63.6397 -143.5354)
		(end 64.34074 -143.5354)
		(width 0.508)
		(layer "B.Cu")
		(net "P3V3_STBY")
	)
	(segment
		(start 85.505798 -181.880002)
		(end 80.38211 -181.880002)
		(width 0.508)
		(layer "B.Cu")
		(net "P3V3_STBY")
	)
	(segment
		(start 93.1164 -176.617122)
		(end 93.3704 -176.871122)
		(width 0.508)
		(layer "B.Cu")
		(net "P3V3_STBY")
	)
	(segment
		(start 178.8414 -114.1476)
		(end 177.7746 -115.2144)
		(width 0.508)
		(layer "B.Cu")
		(net "P3V3_STBY")
	)
	(segment
		(start 59.055 -133.5405)
		(end 57.9501 -133.5405)
		(width 0.508)
		(layer "B.Cu")
		(net "P3V3_STBY")
	)
	(segment
		(start 89.952322 -133.35)
		(end 90.4367 -133.35)
		(width 0.508)
		(layer "B.Cu")
		(net "P3V3_STBY")
	)
	(segment
		(start 91.324684 -139.432284)
		(end 91.324684 -138.48588)
		(width 0.508)
		(layer "B.Cu")
		(net "P3V3_STBY")
	)
	(segment
		(start 86.487 -180.7845)
		(end 86.487 -180.8988)
		(width 0.508)
		(layer "B.Cu")
		(net "P3V3_STBY")
	)
	(segment
		(start 64.651128 -143.3322)
		(end 64.65062 -143.3322)
		(width 0.508)
		(layer "B.Cu")
		(net "P3V3_STBY")
	)
	(segment
		(start 64.651128 -143.347186)
		(end 64.651128 -143.3322)
		(width 0.508)
		(layer "B.Cu")
		(net "P3V3_STBY")
	)
	(segment
		(start 51.023266 -156.143706)
		(end 50.795682 -156.143706)
		(width 0.508)
		(layer "B.Cu")
		(net "P3V3_STBY")
	)
	(segment
		(start 88.8746 -136.6012)
		(end 88.3666 -137.1092)
		(width 0.3556)
		(layer "B.Cu")
		(net "P3V3_STBY")
	)
	(segment
		(start 52.705 -125.89002)
		(end 52.97424 -125.89002)
		(width 0.3556)
		(layer "B.Cu")
		(net "P3V3_STBY")
	)
	(segment
		(start 63.440818 -144.769078)
		(end 63.440818 -143.742918)
		(width 0.508)
		(layer "B.Cu")
		(net "P3V3_STBY")
	)
	(segment
		(start 93.52026 -175.11776)
		(end 93.5355 -175.133)
		(width 0.3556)
		(layer "B.Cu")
		(net "P3V3_STBY")
	)
	(segment
		(start 148.4757 -20.5105)
		(end 148.4757 -19.6596)
		(width 0.508)
		(layer "B.Cu")
		(net "P3V3_STBY")
	)
	(segment
		(start 148.4757 -19.6596)
		(end 149.7584 -18.3769)
		(width 0.508)
		(layer "B.Cu")
		(net "P3V3_STBY")
	)
	(segment
		(start 48.999394 -162.392614)
		(end 49.17694 -162.57016)
		(width 0.508)
		(layer "B.Cu")
		(net "P3V3_STBY")
	)
	(segment
		(start 167.652954 -9.9822)
		(end 168.160954 -9.4742)
		(width 0.508)
		(layer "B.Cu")
		(net "P3V3_STBY")
	)
	(segment
		(start 93.5355 -175.388778)
		(end 93.1164 -175.807878)
		(width 0.508)
		(layer "B.Cu")
		(net "P3V3_STBY")
	)
	(segment
		(start 42.798238 -161.366962)
		(end 41.8592 -162.306)
		(width 0.508)
		(layer "B.Cu")
		(net "P3V3_STBY")
	)
	(segment
		(start 90.4367 -133.35)
		(end 90.5764 -133.1849)
		(width 0.508)
		(layer "B.Cu")
		(net "P3V3_STBY")
	)
	(segment
		(start 43.392852 -121.599452)
		(end 42.644822 -120.851422)
		(width 0.3556)
		(layer "B.Cu")
		(net "P3V3_STBY")
	)
	(segment
		(start 84.031328 -98.010472)
		(end 84.836 -97.2058)
		(width 0.508)
		(layer "B.Cu")
		(net "P3V3_STBY")
	)
	(segment
		(start 86.227666 -51.98364)
		(end 86.307422 -52.394358)
		(width 0.508)
		(layer "B.Cu")
		(net "P3V3_STBY")
	)
	(segment
		(start 89.3826 -133.919722)
		(end 89.952322 -133.35)
		(width 0.508)
		(layer "B.Cu")
		(net "P3V3_STBY")
	)
	(segment
		(start 43.038522 -161.366962)
		(end 42.798238 -161.366962)
		(width 0.508)
		(layer "B.Cu")
		(net "P3V3_STBY")
	)
	(segment
		(start 161.7726 -94.984824)
		(end 161.798 -94.959424)
		(width 0.508)
		(layer "B.Cu")
		(net "P3V3_STBY")
	)
	(segment
		(start 44.736766 -142.0368)
		(end 44.500038 -141.800072)
		(width 0.508)
		(layer "B.Cu")
		(net "P3V3_STBY")
	)
	(segment
		(start 150.114 -13.6906)
		(end 153.8224 -9.9822)
		(width 0.508)
		(layer "B.Cu")
		(net "P3V3_STBY")
	)
	(segment
		(start 69.4436 -150.0124)
		(end 69.4436 -150.089108)
		(width 0.508)
		(layer "B.Cu")
		(net "P3V3_STBY")
	)
	(segment
		(start 44.4246 -127.7747)
		(end 44.4246 -126.9492)
		(width 0.508)
		(layer "B.Cu")
		(net "P3V3_STBY")
	)
	(segment
		(start 95.106744 -152.289256)
		(end 93.37548 -152.289256)
		(width 0.508)
		(layer "B.Cu")
		(net "P3V3_STBY")
	)
	(segment
		(start 79.7941 -130.69824)
		(end 78.84414 -130.69824)
		(width 0.3556)
		(layer "B.Cu")
		(net "P3V3_STBY")
	)
	(segment
		(start 91.8972 -140.0048)
		(end 91.324684 -139.432284)
		(width 0.508)
		(layer "B.Cu")
		(net "P3V3_STBY")
	)
	(segment
		(start 179.8701 -114.1476)
		(end 178.8414 -114.1476)
		(width 0.508)
		(layer "B.Cu")
		(net "P3V3_STBY")
	)
	(segment
		(start 63.565786 -140.653516)
		(end 63.867284 -140.653516)
		(width 0.508)
		(layer "B.Cu")
		(net "P3V3_STBY")
	)
	(segment
		(start 28.7528 -160.7312)
		(end 30.099 -162.0774)
		(width 0.508)
		(layer "B.Cu")
		(net "P3V3_STBY")
	)
	(segment
		(start 67.75577 -139.596876)
		(end 68.534534 -139.596876)
		(width 0.508)
		(layer "B.Cu")
		(net "P3V3_STBY")
	)
	(segment
		(start 60.807092 -154.031188)
		(end 61.07684 -153.76144)
		(width 0.508)
		(layer "B.Cu")
		(net "P3V3_STBY")
	)
	(segment
		(start 84.794852 -51.426364)
		(end 85.67039 -51.426364)
		(width 0.508)
		(layer "B.Cu")
		(net "P3V3_STBY")
	)
	(segment
		(start 92.39504 -133.604)
		(end 90.9955 -133.604)
		(width 0.3556)
		(layer "B.Cu")
		(net "P3V3_STBY")
	)
	(segment
		(start 88.646 -146.627596)
		(end 88.646 -147.66544)
		(width 0.508)
		(layer "B.Cu")
		(net "P3V3_STBY")
	)
	(segment
		(start 57.7723 -145.2626)
		(end 58.674 -145.2626)
		(width 0.508)
		(layer "B.Cu")
		(net "P3V3_STBY")
	)
	(segment
		(start 98.5139 -178.346354)
		(end 98.5139 -177.9778)
		(width 0.508)
		(layer "B.Cu")
		(net "P3V3_STBY")
	)
	(segment
		(start 87.892128 -96.856296)
		(end 87.777828 -96.741996)
		(width 0.508)
		(layer "B.Cu")
		(net "P3V3_STBY")
	)
	(segment
		(start 93.804486 -159.012128)
		(end 94.242636 -159.012128)
		(width 0.508)
		(layer "B.Cu")
		(net "P3V3_STBY")
	)
	(segment
		(start 60.658248 -154.031188)
		(end 60.807092 -154.031188)
		(width 0.508)
		(layer "B.Cu")
		(net "P3V3_STBY")
	)
	(segment
		(start 90.970608 -135.87984)
		(end 90.249248 -136.6012)
		(width 0.3556)
		(layer "B.Cu")
		(net "P3V3_STBY")
	)
	(segment
		(start 160.1978 -94.985586)
		(end 160.198562 -94.984824)
		(width 0.508)
		(layer "B.Cu")
		(net "P3V3_STBY")
	)
	(segment
		(start 41.8592 -162.306)
		(end 41.8592 -162.6108)
		(width 0.508)
		(layer "B.Cu")
		(net "P3V3_STBY")
	)
	(segment
		(start 57.8485 -148.8186)
		(end 58.5216 -148.8186)
		(width 0.508)
		(layer "B.Cu")
		(net "P3V3_STBY")
	)
	(segment
		(start 90.5764 -133.1849)
		(end 90.8431 -133.1849)
		(width 0.3556)
		(layer "B.Cu")
		(net "P3V3_STBY")
	)
	(segment
		(start 196.812408 -14.9098)
		(end 203.513944 -14.9098)
		(width 0.508)
		(layer "B.Cu")
		(net "P3V3_STBY")
	)
	(segment
		(start 69.469 -144.1196)
		(end 69.215 -143.8656)
		(width 0.508)
		(layer "B.Cu")
		(net "P3V3_STBY")
	)
	(segment
		(start 29.6926 -151.765)
		(end 28.7528 -152.7048)
		(width 0.508)
		(layer "B.Cu")
		(net "P3V3_STBY")
	)
	(segment
		(start 91.04122 -135.87984)
		(end 91.2495 -136.08812)
		(width 0.3556)
		(layer "B.Cu")
		(net "P3V3_STBY")
	)
	(segment
		(start 57.949592 -152.423876)
		(end 57.5691 -152.043384)
		(width 0.508)
		(layer "B.Cu")
		(net "P3V3_STBY")
	)
	(segment
		(start 69.469 -144.881854)
		(end 68.820538 -145.530316)
		(width 0.508)
		(layer "B.Cu")
		(net "P3V3_STBY")
	)
	(segment
		(start 57.86755 -146.511264)
		(end 58.720736 -146.511264)
		(width 0.508)
		(layer "B.Cu")
		(net "P3V3_STBY")
	)
	(segment
		(start 69.46646 -149.98954)
		(end 69.4436 -150.0124)
		(width 0.508)
		(layer "B.Cu")
		(net "P3V3_STBY")
	)
	(segment
		(start 90.9955 -133.604)
		(end 90.5764 -133.1849)
		(width 0.3556)
		(layer "B.Cu")
		(net "P3V3_STBY")
	)
	(segment
		(start 79.015844 -52.302156)
		(end 83.91906 -52.302156)
		(width 0.508)
		(layer "B.Cu")
		(net "P3V3_STBY")
	)
	(segment
		(start 88.692228 -96.856296)
		(end 87.892128 -96.856296)
		(width 0.508)
		(layer "B.Cu")
		(net "P3V3_STBY")
	)
	(segment
		(start 161.798 -94.959424)
		(end 161.8234 -94.984824)
		(width 0.508)
		(layer "B.Cu")
		(net "P3V3_STBY")
	)
	(segment
		(start 43.392852 -122.367548)
		(end 43.392852 -121.599452)
		(width 0.3556)
		(layer "B.Cu")
		(net "P3V3_STBY")
	)
	(segment
		(start 98.77298 -178.605434)
		(end 98.5139 -178.346354)
		(width 0.508)
		(layer "B.Cu")
		(net "P3V3_STBY")
	)
	(segment
		(start 152.516078 -94.985586)
		(end 160.1978 -94.985586)
		(width 0.508)
		(layer "B.Cu")
		(net "P3V3_STBY")
	)
	(segment
		(start 47.6758 -154.26944)
		(end 48.39716 -154.26944)
		(width 0.508)
		(layer "B.Cu")
		(net "P3V3_STBY")
	)
	(segment
		(start 93.734636 -159.081978)
		(end 93.804486 -159.012128)
		(width 0.508)
		(layer "B.Cu")
		(net "P3V3_STBY")
	)
	(segment
		(start 94.242636 -159.012128)
		(end 94.242636 -159.576008)
		(width 0.508)
		(layer "B.Cu")
		(net "P3V3_STBY")
	)
	(segment
		(start 57.5691 -152.043384)
		(end 57.5691 -151.6888)
		(width 0.508)
		(layer "B.Cu")
		(net "P3V3_STBY")
	)
	(segment
		(start 63.440818 -143.742918)
		(end 63.4365 -143.7386)
		(width 0.508)
		(layer "B.Cu")
		(net "P3V3_STBY")
	)
	(segment
		(start 46.5074 -127.7747)
		(end 46.5074 -126.9492)
		(width 0.508)
		(layer "B.Cu")
		(net "P3V3_STBY")
	)
	(segment
		(start 92.3417 -146.3421)
		(end 91.9734 -145.9738)
		(width 0.508)
		(layer "B.Cu")
		(net "P3V3_STBY")
	)
	(segment
		(start 96.7359 -146.8755)
		(end 96.139 -146.8755)
		(width 0.508)
		(layer "B.Cu")
		(net "P3V3_STBY")
	)
	(segment
		(start 86.307422 -52.394358)
		(end 86.307422 -53.584602)
		(width 0.508)
		(layer "B.Cu")
		(net "P3V3_STBY")
	)
	(segment
		(start 68.534534 -139.596876)
		(end 68.585334 -139.546076)
		(width 0.508)
		(layer "B.Cu")
		(net "P3V3_STBY")
	)
	(segment
		(start 69.215 -143.8656)
		(end 69.215 -143.845788)
		(width 0.508)
		(layer "B.Cu")
		(net "P3V3_STBY")
	)
	(segment
		(start 149.7584 -18.3769)
		(end 149.7584 -16.726154)
		(width 0.508)
		(layer "B.Cu")
		(net "P3V3_STBY")
	)
	(segment
		(start 52.916074 -158.69412)
		(end 53.0098 -158.787846)
		(width 0.508)
		(layer "B.Cu")
		(net "P3V3_STBY")
	)
	(segment
		(start 53.78958 -124.7394)
		(end 53.04536 -124.7394)
		(width 0.508)
		(layer "B.Cu")
		(net "P3V3_STBY")
	)
	(segment
		(start 91.8464 -152.4254)
		(end 91.8972 -152.3746)
		(width 0.508)
		(layer "B.Cu")
		(net "P3V3_STBY")
	)
	(segment
		(start 97.612708 -177.9778)
		(end 97.59188 -177.956972)
		(width 0.508)
		(layer "B.Cu")
		(net "P3V3_STBY")
	)
	(segment
		(start 62.2808 -174.8409)
		(end 64.4525 -174.8409)
		(width 0.508)
		(layer "B.Cu")
		(net "P3V3_STBY")
	)
	(segment
		(start 78.7654 -130.6195)
		(end 78.2066 -130.6195)
		(width 0.508)
		(layer "B.Cu")
		(net "P3V3_STBY")
	)
	(segment
		(start 97.282 -146.558)
		(end 97.0534 -146.558)
		(width 0.508)
		(layer "B.Cu")
		(net "P3V3_STBY")
	)
	(segment
		(start 149.542246 -16.51)
		(end 149.542246 -15.8242)
		(width 0.508)
		(layer "B.Cu")
		(net "P3V3_STBY")
	)
	(segment
		(start 78.2066 -130.6195)
		(end 77.7875 -130.6195)
		(width 0.508)
		(layer "B.Cu")
		(net "P3V3_STBY")
	)
	(segment
		(start 91.3257 -137.884154)
		(end 91.3257 -137.5156)
		(width 0.508)
		(layer "B.Cu")
		(net "P3V3_STBY")
	)
	(segment
		(start 83.91906 -52.302156)
		(end 84.794852 -51.426364)
		(width 0.508)
		(layer "B.Cu")
		(net "P3V3_STBY")
	)
	(segment
		(start 150.114 -15.252446)
		(end 150.114 -13.6906)
		(width 0.508)
		(layer "B.Cu")
		(net "P3V3_STBY")
	)
	(segment
		(start 62.52083 -141.698472)
		(end 63.565786 -140.653516)
		(width 0.508)
		(layer "B.Cu")
		(net "P3V3_STBY")
	)
	(segment
		(start 28.7528 -152.7048)
		(end 28.7528 -160.7312)
		(width 0.508)
		(layer "B.Cu")
		(net "P3V3_STBY")
	)
	(segment
		(start 91.2495 -136.08812)
		(end 91.2495 -137.4394)
		(width 0.3556)
		(layer "B.Cu")
		(net "P3V3_STBY")
	)
	(segment
		(start 93.34754 -178.31816)
		(end 93.3704 -178.2953)
		(width 0.3556)
		(layer "B.Cu")
		(net "P3V3_STBY")
	)
	(segment
		(start 77.974444 -53.343556)
		(end 79.015844 -52.302156)
		(width 0.508)
		(layer "B.Cu")
		(net "P3V3_STBY")
	)
	(segment
		(start 91.324684 -137.88517)
		(end 91.3257 -137.884154)
		(width 0.508)
		(layer "B.Cu")
		(net "P3V3_STBY")
	)
	(segment
		(start 93.5355 -175.133)
		(end 93.5355 -175.388778)
		(width 0.508)
		(layer "B.Cu")
		(net "P3V3_STBY")
	)
	(segment
		(start 81.7372 -172.339)
		(end 81.7372 -172.2755)
		(width 0.3556)
		(layer "B.Cu")
		(net "P3V3_STBY")
	)
	(segment
		(start 50.14976 -155.497784)
		(end 50.14976 -155.3718)
		(width 0.508)
		(layer "B.Cu")
		(net "P3V3_STBY")
	)
	(segment
		(start 98.77298 -179.35956)
		(end 98.77298 -178.605434)
		(width 0.508)
		(layer "B.Cu")
		(net "P3V3_STBY")
	)
	(segment
		(start 88.282018 -146.263614)
		(end 88.646 -146.627596)
		(width 0.508)
		(layer "B.Cu")
		(net "P3V3_STBY")
	)
	(segment
		(start 59.5122 -147.9042)
		(end 59.7916 -147.9042)
		(width 0.508)
		(layer "B.Cu")
		(net "P3V3_STBY")
	)
	(segment
		(start 69.215 -143.845788)
		(end 68.792344 -143.423132)
		(width 0.508)
		(layer "B.Cu")
		(net "P3V3_STBY")
	)
	(segment
		(start 59.436 -147.9042)
		(end 59.5122 -147.9042)
		(width 0.508)
		(layer "B.Cu")
		(net "P3V3_STBY")
	)
	(segment
		(start 52.705 -125.07976)
		(end 52.705 -125.89002)
		(width 0.508)
		(layer "B.Cu")
		(net "P3V3_STBY")
	)
	(segment
		(start 52.19446 -158.69412)
		(end 52.916074 -158.69412)
		(width 0.508)
		(layer "B.Cu")
		(net "P3V3_STBY")
	)
	(segment
		(start 29.2354 -126.3142)
		(end 29.7688 -125.7808)
		(width 0.508)
		(layer "B.Cu")
		(net "P3V3_STBY")
	)
	(segment
		(start 164.49421 -51.68011)
		(end 164.49421 -53.6575)
		(width 0.3048)
		(layer "B.Cu")
		(net "P3V3_STBY")
	)
	(segment
		(start 61.4553 -141.859)
		(end 62.360302 -141.859)
		(width 0.508)
		(layer "B.Cu")
		(net "P3V3_STBY")
	)
	(segment
		(start 97.7773 -142.365984)
		(end 97.992946 -142.58163)
		(width 0.508)
		(layer "B.Cu")
		(net "P3V3_STBY")
	)
	(segment
		(start 90.249248 -136.6012)
		(end 88.8746 -136.6012)
		(width 0.3556)
		(layer "B.Cu")
		(net "P3V3_STBY")
	)
	(segment
		(start 89.2048 -155.6004)
		(end 89.2048 -153.03246)
		(width 0.508)
		(layer "B.Cu")
		(net "P3V3_STBY")
	)
	(segment
		(start 63.444628 -147.083018)
		(end 64.533018 -147.083018)
		(width 0.508)
		(layer "B.Cu")
		(net "P3V3_STBY")
	)
	(segment
		(start 45.5676 -142.0368)
		(end 44.736766 -142.0368)
		(width 0.508)
		(layer "B.Cu")
		(net "P3V3_STBY")
	)
	(segment
		(start 42.644822 -120.851422)
		(end 42.007028 -120.851422)
		(width 0.3556)
		(layer "B.Cu")
		(net "P3V3_STBY")
	)
	(segment
		(start 43.040808 -161.364676)
		(end 43.040808 -159.975804)
		(width 0.508)
		(layer "B.Cu")
		(net "P3V3_STBY")
	)
	(segment
		(start 160.198562 -94.984824)
		(end 161.7726 -94.984824)
		(width 0.508)
		(layer "B.Cu")
		(net "P3V3_STBY")
	)
	(segment
		(start 77.688948 -53.343556)
		(end 77.974444 -53.343556)
		(width 0.508)
		(layer "B.Cu")
		(net "P3V3_STBY")
	)
	(segment
		(start 161.8234 -94.984824)
		(end 167.244776 -94.984824)
		(width 0.508)
		(layer "B.Cu")
		(net "P3V3_STBY")
	)
	(segment
		(start 29.7688 -124.9426)
		(end 29.7688 -125.7808)
		(width 0.3556)
		(layer "B.Cu")
		(net "P3V3_STBY")
	)
	(segment
		(start 62.3951 -138.90498)
		(end 62.3951 -137.9474)
		(width 0.508)
		(layer "B.Cu")
		(net "P3V3_STBY")
	)
	(segment
		(start 68.792344 -143.423132)
		(end 68.792344 -143.400526)
		(width 0.508)
		(layer "B.Cu")
		(net "P3V3_STBY")
	)
	(segment
		(start 48.39716 -154.26944)
		(end 48.60798 -154.48026)
		(width 0.508)
		(layer "B.Cu")
		(net "P3V3_STBY")
	)
	(segment
		(start 64.533018 -147.083018)
		(end 64.643 -147.193)
		(width 0.508)
		(layer "B.Cu")
		(net "P3V3_STBY")
	)
	(segment
		(start 151.403558 -93.873066)
		(end 152.516078 -94.985586)
		(width 0.508)
		(layer "B.Cu")
		(net "P3V3_STBY")
	)
	(segment
		(start 62.360302 -141.859)
		(end 62.52083 -141.698472)
		(width 0.508)
		(layer "B.Cu")
		(net "P3V3_STBY")
	)
	(segment
		(start 81.7245 -173.2026)
		(end 81.7245 -172.3517)
		(width 0.3556)
		(layer "B.Cu")
		(net "P3V3_STBY")
	)
	(segment
		(start 78.84414 -130.69824)
		(end 78.7654 -130.6195)
		(width 0.3556)
		(layer "B.Cu")
		(net "P3V3_STBY")
	)
	(segment
		(start 82.877406 -171.650914)
		(end 82.8802 -171.64812)
		(width 0.3556)
		(layer "B.Cu")
		(net "P3V3_STBY")
	)
	(segment
		(start 89.3826 -134.3279)
		(end 89.3826 -133.919722)
		(width 0.508)
		(layer "B.Cu")
		(net "P3V3_STBY")
	)
	(segment
		(start 58.0136 -143.3322)
		(end 58.414412 -143.3322)
		(width 0.508)
		(layer "B.Cu")
		(net "P3V3_STBY")
	)
	(segment
		(start 58.720736 -146.511264)
		(end 58.7248 -146.5072)
		(width 0.508)
		(layer "B.Cu")
		(net "P3V3_STBY")
	)
	(segment
		(start 41.3512 -124.6759)
		(end 40.7035 -124.6759)
		(width 0.508)
		(layer "B.Cu")
		(net "P3V3_STBY")
	)
	(segment
		(start 57.949846 -152.423876)
		(end 57.949592 -152.423876)
		(width 0.508)
		(layer "B.Cu")
		(net "P3V3_STBY")
	)
	(segment
		(start 97.992946 -145.847054)
		(end 97.282 -146.558)
		(width 0.508)
		(layer "B.Cu")
		(net "P3V3_STBY")
	)
	(segment
		(start 38.01491 -117.941852)
		(end 37.158422 -117.941852)
		(width 0.508)
		(layer "B.Cu")
		(net "P3V3_STBY")
	)
	(segment
		(start 97.0534 -146.558)
		(end 96.7359 -146.8755)
		(width 0.508)
		(layer "B.Cu")
		(net "P3V3_STBY")
	)
	(segment
		(start 52.92598 -124.85878)
		(end 52.705 -125.07976)
		(width 0.508)
		(layer "B.Cu")
		(net "P3V3_STBY")
	)
	(segment
		(start 93.6371 -129.0447)
		(end 93.8022 -129.2098)
		(width 0.508)
		(layer "B.Cu")
		(net "P3V3_STBY")
	)
	(segment
		(start 153.8224 -9.9822)
		(end 167.652954 -9.9822)
		(width 0.508)
		(layer "B.Cu")
		(net "P3V3_STBY")
	)
	(segment
		(start 64.4525 -174.8409)
		(end 64.7192 -175.1076)
		(width 0.508)
		(layer "B.Cu")
		(net "P3V3_STBY")
	)
	(segment
		(start 50.795682 -156.143706)
		(end 50.14976 -155.497784)
		(width 0.508)
		(layer "B.Cu")
		(net "P3V3_STBY")
	)
	(segment
		(start 30.19806 -124.51334)
		(end 29.7688 -124.9426)
		(width 0.3556)
		(layer "B.Cu")
		(net "P3V3_STBY")
	)
	(segment
		(start 35.738308 -128.857248)
		(end 36.06292 -129.18186)
		(width 0.508)
		(layer "B.Cu")
		(net "P3V3_STBY")
	)
	(segment
		(start 54.6354 -135.2677)
		(end 54.6354 -134.5184)
		(width 0.508)
		(layer "B.Cu")
		(net "P3V3_STBY")
	)
	(segment
		(start 35.738308 -125.123194)
		(end 35.738308 -128.857248)
		(width 0.508)
		(layer "B.Cu")
		(net "P3V3_STBY")
	)
	(segment
		(start 91.32316 -132.70484)
		(end 92.1639 -132.70484)
		(width 0.3556)
		(layer "B.Cu")
		(net "P3V3_STBY")
	)
	(segment
		(start 89.59088 -152.64638)
		(end 89.81186 -152.4254)
		(width 0.508)
		(layer "B.Cu")
		(net "P3V3_STBY")
	)
	(segment
		(start 91.5162 -141.6304)
		(end 91.5162 -141.8209)
		(width 0.508)
		(layer "B.Cu")
		(net "P3V3_STBY")
	)
	(segment
		(start 175.0314 -128.21285)
		(end 176.9618 -126.28245)
		(width 0.762)
		(layer "In2.Cu")
		(net "P3V3_STBY")
	)
	(segment
		(start 79.560674 -47.845726)
		(end 78.5876 -48.8188)
		(width 0.508)
		(layer "In2.Cu")
		(net "P3V3_STBY")
	)
	(segment
		(start 76.89088 -7.465568)
		(end 76.89088 -8.363204)
		(width 0.508)
		(layer "In2.Cu")
		(net "P3V3_STBY")
	)
	(segment
		(start 25.9715 -115.57)
		(end 25.9715 -77.229208)
		(width 0.508)
		(layer "In2.Cu")
		(net "P3V3_STBY")
	)
	(segment
		(start 176.9872 -120.9294)
		(end 176.9618 -120.904)
		(width 0.762)
		(layer "In2.Cu")
		(net "P3V3_STBY")
	)
	(segment
		(start 177.7746 -116.205)
		(end 177.7746 -115.2144)
		(width 0.762)
		(layer "In2.Cu")
		(net "P3V3_STBY")
	)
	(segment
		(start 168.972992 -96.278192)
		(end 168.972992 -99.440492)
		(width 0.762)
		(layer "In2.Cu")
		(net "P3V3_STBY")
	)
	(segment
		(start 11.348212 -14.0462)
		(end 11.325352 -14.02334)
		(width 0.508)
		(layer "In2.Cu")
		(net "P3V3_STBY")
	)
	(segment
		(start 11.325352 -14.02334)
		(end 10.777728 -14.02334)
		(width 0.508)
		(layer "In2.Cu")
		(net "P3V3_STBY")
	)
	(segment
		(start 10.777728 -14.02334)
		(end 10.754868 -14.0462)
		(width 0.508)
		(layer "In2.Cu")
		(net "P3V3_STBY")
	)
	(segment
		(start 176.47031 -112.79251)
		(end 177.7746 -114.0968)
		(width 0.762)
		(layer "In2.Cu")
		(net "P3V3_STBY")
	)
	(segment
		(start 168.972992 -99.440492)
		(end 176.47031 -106.93781)
		(width 0.762)
		(layer "In2.Cu")
		(net "P3V3_STBY")
	)
	(segment
		(start 26.035 -19.31162)
		(end 22.62378 -15.9004)
		(width 0.508)
		(layer "In2.Cu")
		(net "P3V3_STBY")
	)
	(segment
		(start 175.0314 -129.0066)
		(end 175.0314 -128.21285)
		(width 0.762)
		(layer "In2.Cu")
		(net "P3V3_STBY")
	)
	(segment
		(start 176.9618 -117.0178)
		(end 177.7746 -116.205)
		(width 0.762)
		(layer "In2.Cu")
		(net "P3V3_STBY")
	)
	(segment
		(start 176.47031 -106.93781)
		(end 176.47031 -112.79251)
		(width 0.762)
		(layer "In2.Cu")
		(net "P3V3_STBY")
	)
	(segment
		(start 75.908916 -41.666414)
		(end 79.560674 -45.318172)
		(width 0.508)
		(layer "In2.Cu")
		(net "P3V3_STBY")
	)
	(segment
		(start 20.76958 -14.0462)
		(end 11.348212 -14.0462)
		(width 0.508)
		(layer "In2.Cu")
		(net "P3V3_STBY")
	)
	(segment
		(start 25.9715 -77.229208)
		(end 17.336262 -68.59397)
		(width 0.508)
		(layer "In2.Cu")
		(net "P3V3_STBY")
	)
	(segment
		(start 176.9618 -126.28245)
		(end 176.9618 -121.031)
		(width 0.762)
		(layer "In2.Cu")
		(net "P3V3_STBY")
	)
	(segment
		(start 167.4622 -94.7674)
		(end 168.972992 -96.278192)
		(width 0.762)
		(layer "In2.Cu")
		(net "P3V3_STBY")
	)
	(segment
		(start 151.3078 -44.01058)
		(end 157.47492 -50.1777)
		(width 0.508)
		(layer "In2.Cu")
		(net "P3V3_STBY")
	)
	(segment
		(start 148.4757 -20.5105)
		(end 151.3078 -23.3426)
		(width 0.508)
		(layer "In2.Cu")
		(net "P3V3_STBY")
	)
	(segment
		(start 9.81202 -14.0462)
		(end 9.80186 -14.03604)
		(width 0.508)
		(layer "In2.Cu")
		(net "P3V3_STBY")
	)
	(segment
		(start 17.336262 -68.59397)
		(end 17.336262 -56.327548)
		(width 0.508)
		(layer "In2.Cu")
		(net "P3V3_STBY")
	)
	(segment
		(start 176.9618 -120.904)
		(end 176.9618 -117.0178)
		(width 0.762)
		(layer "In2.Cu")
		(net "P3V3_STBY")
	)
	(segment
		(start 78.5876 -48.8188)
		(end 78.5876 -52.832)
		(width 0.508)
		(layer "In2.Cu")
		(net "P3V3_STBY")
	)
	(segment
		(start 79.560674 -45.318172)
		(end 79.560674 -47.845726)
		(width 0.508)
		(layer "In2.Cu")
		(net "P3V3_STBY")
	)
	(segment
		(start 10.754868 -14.0462)
		(end 9.81202 -14.0462)
		(width 0.508)
		(layer "In2.Cu")
		(net "P3V3_STBY")
	)
	(segment
		(start 22.62378 -15.9004)
		(end 20.76958 -14.0462)
		(width 0.508)
		(layer "In2.Cu")
		(net "P3V3_STBY")
	)
	(segment
		(start 78.076044 -53.343556)
		(end 77.688948 -53.343556)
		(width 0.508)
		(layer "In2.Cu")
		(net "P3V3_STBY")
	)
	(segment
		(start 78.5876 -52.832)
		(end 78.076044 -53.343556)
		(width 0.508)
		(layer "In2.Cu")
		(net "P3V3_STBY")
	)
	(segment
		(start 79.17561 -5.180838)
		(end 76.89088 -7.465568)
		(width 0.508)
		(layer "In2.Cu")
		(net "P3V3_STBY")
	)
	(segment
		(start 17.336262 -56.327548)
		(end 26.035 -47.62881)
		(width 0.508)
		(layer "In2.Cu")
		(net "P3V3_STBY")
	)
	(segment
		(start 176.9618 -121.031)
		(end 176.9872 -121.0056)
		(width 0.762)
		(layer "In2.Cu")
		(net "P3V3_STBY")
	)
	(segment
		(start 26.035 -47.62881)
		(end 26.035 -19.31162)
		(width 0.508)
		(layer "In2.Cu")
		(net "P3V3_STBY")
	)
	(segment
		(start 75.908916 -9.345168)
		(end 75.908916 -41.666414)
		(width 0.508)
		(layer "In2.Cu")
		(net "P3V3_STBY")
	)
	(segment
		(start 76.89088 -8.363204)
		(end 75.908916 -9.345168)
		(width 0.508)
		(layer "In2.Cu")
		(net "P3V3_STBY")
	)
	(segment
		(start 177.7746 -114.0968)
		(end 177.7746 -115.2144)
		(width 0.762)
		(layer "In2.Cu")
		(net "P3V3_STBY")
	)
	(segment
		(start 151.3078 -23.3426)
		(end 151.3078 -44.01058)
		(width 0.508)
		(layer "In2.Cu")
		(net "P3V3_STBY")
	)
	(segment
		(start 176.9872 -121.0056)
		(end 176.9872 -120.9294)
		(width 0.762)
		(layer "In2.Cu")
		(net "P3V3_STBY")
	)
	(segment
		(start 195.532248 -13.62964)
		(end 194.75704 -13.62964)
		(width 0.508)
		(layer "In5.Cu")
		(net "P3V3_STBY")
	)
	(segment
		(start 186.964066 -10.10158)
		(end 183.912764 -7.050278)
		(width 0.508)
		(layer "In5.Cu")
		(net "P3V3_STBY")
	)
	(segment
		(start 191.22898 -10.10158)
		(end 186.964066 -10.10158)
		(width 0.508)
		(layer "In5.Cu")
		(net "P3V3_STBY")
	)
	(segment
		(start 164.907722 -2.690622)
		(end 168.858946 -6.641846)
		(width 0.508)
		(layer "In5.Cu")
		(net "P3V3_STBY")
	)
	(segment
		(start 168.858946 -6.641846)
		(end 169.29989 -6.641846)
		(width 0.508)
		(layer "In5.Cu")
		(net "P3V3_STBY")
	)
	(segment
		(start 80.927448 -3.8608)
		(end 82.097626 -2.690622)
		(width 0.508)
		(layer "In5.Cu")
		(net "P3V3_STBY")
	)
	(segment
		(start 183.912764 -7.050278)
		(end 172.958506 -7.050278)
		(width 0.508)
		(layer "In5.Cu")
		(net "P3V3_STBY")
	)
	(segment
		(start 80.495648 -3.8608)
		(end 80.927448 -3.8608)
		(width 0.508)
		(layer "In5.Cu")
		(net "P3V3_STBY")
	)
	(segment
		(start 79.17561 -5.180838)
		(end 80.495648 -3.8608)
		(width 0.508)
		(layer "In5.Cu")
		(net "P3V3_STBY")
	)
	(segment
		(start 172.958506 -7.050278)
		(end 172.550074 -6.641846)
		(width 0.508)
		(layer "In5.Cu")
		(net "P3V3_STBY")
	)
	(segment
		(start 194.75704 -13.62964)
		(end 191.22898 -10.10158)
		(width 0.508)
		(layer "In5.Cu")
		(net "P3V3_STBY")
	)
	(segment
		(start 172.550074 -6.641846)
		(end 169.29989 -6.641846)
		(width 0.508)
		(layer "In5.Cu")
		(net "P3V3_STBY")
	)
	(segment
		(start 82.097626 -2.690622)
		(end 164.907722 -2.690622)
		(width 0.508)
		(layer "In5.Cu")
		(net "P3V3_STBY")
	)
	(segment
		(start 42.3164 -130.4544)
		(end 43.3578 -130.4544)
		(width 0.508)
		(layer "In5.Cu")
		(net "P3V3_STBY")
	)
	(segment
		(start 166.1922 -128.0414)
		(end 165.0619 -128.0414)
		(width 0.254)
		(layer "F.Cu")
		(net "P1V8_STBY_VFB_R")
	)
	(segment
		(start 165.0619 -128.0414)
		(end 165.0619 -127.68326)
		(width 0.254)
		(layer "F.Cu")
		(net "P1V8_STBY_VFB_R")
	)
	(segment
		(start 165.7858 -126.95936)
		(end 165.7858 -126.8984)
		(width 0.254)
		(layer "F.Cu")
		(net "P1V8_STBY_VFB_R")
	)
	(segment
		(start 165.0619 -127.68326)
		(end 165.7858 -126.95936)
		(width 0.254)
		(layer "F.Cu")
		(net "P1V8_STBY_VFB_R")
	)
	(via
		(at 164.7952 -138.684)
		(size 0.6096)
		(drill 0.3048)
		(layers "F.Cu" "B.Cu")
		(net "P1V8_STBY_VFB_R")
	)
	(via
		(at 166.1922 -128.0414)
		(size 0.508)
		(drill 0.254)
		(layers "F.Cu" "B.Cu")
		(net "P1V8_STBY_VFB_R")
	)
	(segment
		(start 163.83 -140.4493)
		(end 164.7952 -139.4841)
		(width 0.254)
		(layer "B.Cu")
		(net "P1V8_STBY_VFB_R")
	)
	(segment
		(start 165.9382 -135.07593)
		(end 164.7952 -136.21893)
		(width 0.254)
		(layer "B.Cu")
		(net "P1V8_STBY_VFB_R")
	)
	(segment
		(start 166.1922 -128.0414)
		(end 165.9382 -128.2954)
		(width 0.254)
		(layer "B.Cu")
		(net "P1V8_STBY_VFB_R")
	)
	(segment
		(start 164.7952 -139.4841)
		(end 164.7952 -138.684)
		(width 0.254)
		(layer "B.Cu")
		(net "P1V8_STBY_VFB_R")
	)
	(segment
		(start 164.7952 -136.21893)
		(end 164.7952 -138.684)
		(width 0.254)
		(layer "B.Cu")
		(net "P1V8_STBY_VFB_R")
	)
	(segment
		(start 165.9382 -128.2954)
		(end 165.9382 -135.07593)
		(width 0.254)
		(layer "B.Cu")
		(net "P1V8_STBY_VFB_R")
	)
	(segment
		(start 161.53638 -141.6304)
		(end 161.53638 -141.552422)
		(width 0.254)
		(layer "F.Cu")
		(net "P1V8_STBY_VFB")
	)
	(segment
		(start 161.377376 -141.552422)
		(end 160.687512 -140.862558)
		(width 0.254)
		(layer "F.Cu")
		(net "P1V8_STBY_VFB")
	)
	(segment
		(start 162.3949 -141.605)
		(end 161.56178 -141.605)
		(width 0.254)
		(layer "F.Cu")
		(net "P1V8_STBY_VFB")
	)
	(segment
		(start 160.199578 -140.374624)
		(end 160.199578 -138.83386)
		(width 0.254)
		(layer "F.Cu")
		(net "P1V8_STBY_VFB")
	)
	(segment
		(start 160.199578 -138.83386)
		(end 160.048702 -138.682984)
		(width 0.254)
		(layer "F.Cu")
		(net "P1V8_STBY_VFB")
	)
	(segment
		(start 161.56178 -141.605)
		(end 161.53638 -141.6304)
		(width 0.254)
		(layer "F.Cu")
		(net "P1V8_STBY_VFB")
	)
	(segment
		(start 160.687512 -140.862558)
		(end 160.199578 -140.374624)
		(width 0.254)
		(layer "F.Cu")
		(net "P1V8_STBY_VFB")
	)
	(segment
		(start 162.4203 -140.6398)
		(end 162.3949 -140.6652)
		(width 0.254)
		(layer "F.Cu")
		(net "P1V8_STBY_VFB")
	)
	(segment
		(start 161.53638 -141.552422)
		(end 161.377376 -141.552422)
		(width 0.254)
		(layer "F.Cu")
		(net "P1V8_STBY_VFB")
	)
	(segment
		(start 162.3949 -140.6652)
		(end 162.3949 -141.605)
		(width 0.254)
		(layer "F.Cu")
		(net "P1V8_STBY_VFB")
	)
	(segment
		(start 160.048702 -138.682984)
		(end 160.048702 -138.213846)
		(width 0.254)
		(layer "F.Cu")
		(net "P1V8_STBY_VFB")
	)
	(via
		(at 161.53638 -141.6304)
		(size 0.508)
		(drill 0.254)
		(layers "F.Cu" "B.Cu")
		(net "P1V8_STBY_VFB")
	)
	(via
		(at 162.6616 -141.6304)
		(size 0.6096)
		(drill 0.3048)
		(layers "F.Cu" "B.Cu")
		(net "P1V8_STBY_VFB")
	)
	(segment
		(start 163.83 -141.3383)
		(end 163.5379 -141.6304)
		(width 0.254)
		(layer "B.Cu")
		(net "P1V8_STBY_VFB")
	)
	(segment
		(start 162.6616 -141.6304)
		(end 161.53638 -141.6304)
		(width 0.254)
		(layer "B.Cu")
		(net "P1V8_STBY_VFB")
	)
	(segment
		(start 163.5379 -141.6304)
		(end 162.6616 -141.6304)
		(width 0.254)
		(layer "B.Cu")
		(net "P1V8_STBY_VFB")
	)
	(via
		(at 161.41192 -133.63702)
		(size 0.6604)
		(drill 0.3302)
		(layers "F.Cu" "B.Cu")
		(net "P1V8_STBY_VBST")
	)
	(segment
		(start 153.38044 -132.471922)
		(end 153.12644 -132.725922)
		(width 0.508)
		(layer "F.Cu")
		(net "P1V8_STBY_SNB")
	)
	(segment
		(start 154.98064 -132.471922)
		(end 153.38044 -132.471922)
		(width 0.508)
		(layer "F.Cu")
		(net "P1V8_STBY_SNB")
	)
	(segment
		(start 153.12644 -134.249922)
		(end 153.12644 -132.725922)
		(width 0.508)
		(layer "F.Cu")
		(net "P1V8_STBY_SNB")
	)
	(via
		(at 153.12644 -132.725922)
		(size 0.6604)
		(drill 0.3302)
		(layers "F.Cu" "B.Cu")
		(net "P1V8_STBY_SNB")
	)
	(segment
		(start 49.299622 -140.20038)
		(end 48.90008 -140.599922)
		(width 0.254)
		(layer "F.Cu")
		(net "P1V8_STBY")
	)
	(segment
		(start 158.7754 -126.9492)
		(end 159.0294 -127.2032)
		(width 0.254)
		(layer "F.Cu")
		(net "P1V8_STBY")
	)
	(segment
		(start 49.70018 -140.599922)
		(end 49.699926 -140.599922)
		(width 0.254)
		(layer "F.Cu")
		(net "P1V8_STBY")
	)
	(segment
		(start 163.957 -127.2032)
		(end 164.2618 -126.8984)
		(width 0.254)
		(layer "F.Cu")
		(net "P1V8_STBY")
	)
	(segment
		(start 56.6293 -163.0426)
		(end 56.7436 -162.9283)
		(width 0.508)
		(layer "F.Cu")
		(net "P1V8_STBY")
	)
	(segment
		(start 158.7754 -125.513592)
		(end 158.7754 -125.558804)
		(width 0.254)
		(layer "F.Cu")
		(net "P1V8_STBY")
	)
	(segment
		(start 159.0294 -127.2032)
		(end 163.957 -127.2032)
		(width 0.254)
		(layer "F.Cu")
		(net "P1V8_STBY")
	)
	(segment
		(start 48.90008 -140.599922)
		(end 48.899826 -140.599922)
		(width 0.254)
		(layer "F.Cu")
		(net "P1V8_STBY")
	)
	(segment
		(start 50.099722 -140.20038)
		(end 49.70018 -140.599922)
		(width 0.254)
		(layer "F.Cu")
		(net "P1V8_STBY")
	)
	(segment
		(start 156.5275 -117.602)
		(end 157.39237 -117.602)
		(width 0.254)
		(layer "F.Cu")
		(net "P1V8_STBY")
	)
	(segment
		(start 158.7754 -125.558804)
		(end 158.7754 -126.9492)
		(width 0.254)
		(layer "F.Cu")
		(net "P1V8_STBY")
	)
	(segment
		(start 56.6293 -164.5666)
		(end 56.6293 -163.0426)
		(width 0.508)
		(layer "F.Cu")
		(net "P1V8_STBY")
	)
	(via
		(at 19.1262 -171.2722)
		(size 0.7112)
		(drill 0.4064)
		(layers "F.Cu" "B.Cu")
		(net "P1V8_STBY")
	)
	(via
		(at 81.936844 -166.053516)
		(size 0.7112)
		(drill 0.4064)
		(layers "F.Cu" "B.Cu")
		(net "P1V8_STBY")
	)
	(via
		(at 159.893 -119.761)
		(size 0.7112)
		(drill 0.4064)
		(layers "F.Cu" "B.Cu")
		(net "P1V8_STBY")
	)
	(via
		(at 20.6502 -171.4754)
		(size 0.7112)
		(drill 0.4064)
		(layers "F.Cu" "B.Cu")
		(net "P1V8_STBY")
	)
	(via
		(at 163.195 -118.0338)
		(size 0.7112)
		(drill 0.4064)
		(layers "F.Cu" "B.Cu")
		(net "P1V8_STBY")
	)
	(via
		(at 159.247332 -123.550426)
		(size 0.7112)
		(drill 0.4064)
		(layers "F.Cu" "B.Cu")
		(net "P1V8_STBY")
	)
	(via
		(at 211.328 -132.334)
		(size 0.7112)
		(drill 0.4064)
		(layers "F.Cu" "B.Cu")
		(net "P1V8_STBY")
	)
	(via
		(at 163.195 -114.0714)
		(size 0.7112)
		(drill 0.4064)
		(layers "F.Cu" "B.Cu")
		(net "P1V8_STBY")
	)
	(via
		(at 50.099722 -140.20038)
		(size 0.4572)
		(drill 0.2032)
		(layers "F.Cu" "B.Cu")
		(net "P1V8_STBY")
	)
	(via
		(at 64.680592 -189.347602)
		(size 0.508)
		(drill 0.254)
		(layers "F.Cu" "B.Cu")
		(net "P1V8_STBY")
	)
	(via
		(at 78.279244 -166.053516)
		(size 0.7112)
		(drill 0.4064)
		(layers "F.Cu" "B.Cu")
		(net "P1V8_STBY")
	)
	(via
		(at 211.328 -131.064)
		(size 0.7112)
		(drill 0.4064)
		(layers "F.Cu" "B.Cu")
		(net "P1V8_STBY")
	)
	(via
		(at 161.29 -121.031)
		(size 0.7112)
		(drill 0.4064)
		(layers "F.Cu" "B.Cu")
		(net "P1V8_STBY")
	)
	(via
		(at 210.058 -131.064)
		(size 0.7112)
		(drill 0.4064)
		(layers "F.Cu" "B.Cu")
		(net "P1V8_STBY")
	)
	(via
		(at 19.1262 -172.5422)
		(size 0.7112)
		(drill 0.4064)
		(layers "F.Cu" "B.Cu")
		(net "P1V8_STBY")
	)
	(via
		(at 79.498444 -166.053516)
		(size 0.7112)
		(drill 0.4064)
		(layers "F.Cu" "B.Cu")
		(net "P1V8_STBY")
	)
	(via
		(at 161.29 -119.634)
		(size 0.7112)
		(drill 0.4064)
		(layers "F.Cu" "B.Cu")
		(net "P1V8_STBY")
	)
	(via
		(at 161.29 -122.555)
		(size 0.7112)
		(drill 0.4064)
		(layers "F.Cu" "B.Cu")
		(net "P1V8_STBY")
	)
	(via
		(at 159.893 -122.555)
		(size 0.7112)
		(drill 0.4064)
		(layers "F.Cu" "B.Cu")
		(net "P1V8_STBY")
	)
	(via
		(at 163.2204 -116.713)
		(size 0.7112)
		(drill 0.4064)
		(layers "F.Cu" "B.Cu")
		(net "P1V8_STBY")
	)
	(via
		(at 157.8864 -123.601226)
		(size 0.7112)
		(drill 0.4064)
		(layers "F.Cu" "B.Cu")
		(net "P1V8_STBY")
	)
	(via
		(at 20.6502 -172.7454)
		(size 0.7112)
		(drill 0.4064)
		(layers "F.Cu" "B.Cu")
		(net "P1V8_STBY")
	)
	(via
		(at 154.5844 -92.1004)
		(size 0.508)
		(drill 0.254)
		(layers "F.Cu" "B.Cu")
		(net "P1V8_STBY")
	)
	(via
		(at 163.2458 -115.4176)
		(size 0.7112)
		(drill 0.4064)
		(layers "F.Cu" "B.Cu")
		(net "P1V8_STBY")
	)
	(via
		(at 49.299622 -140.20038)
		(size 0.4572)
		(drill 0.2032)
		(layers "F.Cu" "B.Cu")
		(net "P1V8_STBY")
	)
	(via
		(at 80.717644 -166.053516)
		(size 0.7112)
		(drill 0.4064)
		(layers "F.Cu" "B.Cu")
		(net "P1V8_STBY")
	)
	(via
		(at 159.893 -121.158)
		(size 0.7112)
		(drill 0.4064)
		(layers "F.Cu" "B.Cu")
		(net "P1V8_STBY")
	)
	(via
		(at 56.6293 -164.5666)
		(size 0.508)
		(drill 0.254)
		(layers "F.Cu" "B.Cu")
		(net "P1V8_STBY")
	)
	(via
		(at 210.058 -132.334)
		(size 0.7112)
		(drill 0.4064)
		(layers "F.Cu" "B.Cu")
		(net "P1V8_STBY")
	)
	(via
		(at 211.198206 -129.687828)
		(size 0.6604)
		(drill 0.3302)
		(layers "F.Cu" "B.Cu")
		(net "P1V8_STBY")
	)
	(segment
		(start 154.5844 -92.1004)
		(end 154.8765 -91.8083)
		(width 0.508)
		(layer "B.Cu")
		(net "P1V8_STBY")
	)
	(segment
		(start 154.8765 -91.8083)
		(end 154.8765 -91.1606)
		(width 0.508)
		(layer "B.Cu")
		(net "P1V8_STBY")
	)
	(segment
		(start 154.8765 -91.1606)
		(end 154.813 -91.2241)
		(width 0.3556)
		(layer "B.Cu")
		(net "P1V8_STBY")
	)
	(segment
		(start 49.292002 -140.208)
		(end 49.299622 -140.20038)
		(width 0.508)
		(layer "B.Cu")
		(net "P1V8_STBY")
	)
	(segment
		(start 51.10988 -140.335)
		(end 50.234342 -140.335)
		(width 0.508)
		(layer "B.Cu")
		(net "P1V8_STBY")
	)
	(segment
		(start 48.49622 -140.208)
		(end 49.292002 -140.208)
		(width 0.508)
		(layer "B.Cu")
		(net "P1V8_STBY")
	)
	(segment
		(start 50.234342 -140.335)
		(end 50.099722 -140.20038)
		(width 0.508)
		(layer "B.Cu")
		(net "P1V8_STBY")
	)
	(segment
		(start 154.813 -91.2241)
		(end 153.430986 -91.2241)
		(width 0.3556)
		(layer "B.Cu")
		(net "P1V8_STBY")
	)
	(segment
		(start 57.758584 -153.094944)
		(end 57.758584 -155.349194)
		(width 0.508)
		(layer "In2.Cu")
		(net "P1V8_STBY")
	)
	(segment
		(start 57.340246 -152.676606)
		(end 57.758584 -153.094944)
		(width 0.508)
		(layer "In2.Cu")
		(net "P1V8_STBY")
	)
	(segment
		(start 57.758584 -155.349194)
		(end 59.782202 -157.372812)
		(width 0.508)
		(layer "In2.Cu")
		(net "P1V8_STBY")
	)
	(segment
		(start 51.48453 -140.758418)
		(end 51.48453 -141.242542)
		(width 0.508)
		(layer "In2.Cu")
		(net "P1V8_STBY")
	)
	(segment
		(start 57.907936 -163.287964)
		(end 56.6293 -164.5666)
		(width 0.508)
		(layer "In2.Cu")
		(net "P1V8_STBY")
	)
	(segment
		(start 59.782202 -157.372812)
		(end 65.191386 -157.372812)
		(width 0.508)
		(layer "In2.Cu")
		(net "P1V8_STBY")
	)
	(segment
		(start 51.115468 -141.611604)
		(end 51.115468 -144.031208)
		(width 0.508)
		(layer "In2.Cu")
		(net "P1V8_STBY")
	)
	(segment
		(start 62.76594 -163.287964)
		(end 57.907936 -163.287964)
		(width 0.508)
		(layer "In2.Cu")
		(net "P1V8_STBY")
	)
	(segment
		(start 60.3504 -174.650654)
		(end 60.3504 -177.063654)
		(width 0.508)
		(layer "In2.Cu")
		(net "P1V8_STBY")
	)
	(segment
		(start 56.6293 -165.227)
		(end 56.63438 -165.23208)
		(width 0.508)
		(layer "In2.Cu")
		(net "P1V8_STBY")
	)
	(segment
		(start 51.917092 -144.832832)
		(end 54.758844 -144.832832)
		(width 0.508)
		(layer "In2.Cu")
		(net "P1V8_STBY")
	)
	(segment
		(start 65.191386 -157.372812)
		(end 65.616582 -157.798008)
		(width 0.508)
		(layer "In2.Cu")
		(net "P1V8_STBY")
	)
	(segment
		(start 65.616582 -157.798008)
		(end 65.616582 -160.437322)
		(width 0.508)
		(layer "In2.Cu")
		(net "P1V8_STBY")
	)
	(segment
		(start 56.63438 -170.934634)
		(end 60.3504 -174.650654)
		(width 0.508)
		(layer "In2.Cu")
		(net "P1V8_STBY")
	)
	(segment
		(start 50.099722 -140.20038)
		(end 50.926492 -140.20038)
		(width 0.508)
		(layer "In2.Cu")
		(net "P1V8_STBY")
	)
	(segment
		(start 60.3504 -177.063654)
		(end 64.680592 -181.393846)
		(width 0.508)
		(layer "In2.Cu")
		(net "P1V8_STBY")
	)
	(segment
		(start 57.340246 -147.414234)
		(end 57.340246 -152.676606)
		(width 0.508)
		(layer "In2.Cu")
		(net "P1V8_STBY")
	)
	(segment
		(start 51.115468 -144.031208)
		(end 51.917092 -144.832832)
		(width 0.508)
		(layer "In2.Cu")
		(net "P1V8_STBY")
	)
	(segment
		(start 56.6293 -164.5666)
		(end 56.6293 -165.227)
		(width 0.508)
		(layer "In2.Cu")
		(net "P1V8_STBY")
	)
	(segment
		(start 54.758844 -144.832832)
		(end 57.340246 -147.414234)
		(width 0.508)
		(layer "In2.Cu")
		(net "P1V8_STBY")
	)
	(segment
		(start 65.616582 -160.437322)
		(end 62.76594 -163.287964)
		(width 0.508)
		(layer "In2.Cu")
		(net "P1V8_STBY")
	)
	(segment
		(start 51.48453 -141.242542)
		(end 51.115468 -141.611604)
		(width 0.508)
		(layer "In2.Cu")
		(net "P1V8_STBY")
	)
	(segment
		(start 56.63438 -165.23208)
		(end 56.63438 -170.934634)
		(width 0.508)
		(layer "In2.Cu")
		(net "P1V8_STBY")
	)
	(segment
		(start 50.926492 -140.20038)
		(end 51.48453 -140.758418)
		(width 0.508)
		(layer "In2.Cu")
		(net "P1V8_STBY")
	)
	(segment
		(start 64.680592 -181.393846)
		(end 64.680592 -189.347602)
		(width 0.508)
		(layer "In2.Cu")
		(net "P1V8_STBY")
	)
	(segment
		(start 49.299622 -140.20038)
		(end 50.099722 -140.20038)
		(width 0.508)
		(layer "In2.Cu")
		(net "P1V8_STBY")
	)
	(segment
		(start 202.40117 -65.901316)
		(end 201.99985 -65.499996)
		(width 0.127)
		(layer "F.Cu")
		(net "OSC_REF_CLK")
	)
	(segment
		(start 204.00264 -65.901316)
		(end 202.40117 -65.901316)
		(width 0.127)
		(layer "F.Cu")
		(net "OSC_REF_CLK")
	)
	(via
		(at 204.00264 -65.901316)
		(size 0.508)
		(drill 0.254)
		(layers "F.Cu" "B.Cu")
		(net "OSC_REF_CLK")
	)
	(segment
		(start 204.549756 -65.3542)
		(end 204.8256 -65.3542)
		(width 0.127)
		(layer "B.Cu")
		(net "OSC_REF_CLK")
	)
	(segment
		(start 204.00264 -65.901316)
		(end 204.549756 -65.3542)
		(width 0.127)
		(layer "B.Cu")
		(net "OSC_REF_CLK")
	)
	(segment
		(start 44.099988 -145.400014)
		(end 43.699938 -144.999964)
		(width 0.3556)
		(layer "F.Cu")
		(net "MPLLAV33")
	)
	(segment
		(start 41.699688 -140.599922)
		(end 41.299638 -140.999972)
		(width 0.3048)
		(layer "F.Cu")
		(net "MPLLAV33")
	)
	(segment
		(start 40.899842 -140.600176)
		(end 41.299638 -140.999972)
		(width 0.3048)
		(layer "F.Cu")
		(net "MPLLAV33")
	)
	(segment
		(start 41.699942 -140.599922)
		(end 41.699688 -140.599922)
		(width 0.3048)
		(layer "F.Cu")
		(net "MPLLAV33")
	)
	(segment
		(start 40.899842 -140.599922)
		(end 40.899842 -140.600176)
		(width 0.3048)
		(layer "F.Cu")
		(net "MPLLAV33")
	)
	(via
		(at 35.1409 -148.3995)
		(size 0.6096)
		(drill 0.3048)
		(layers "F.Cu" "B.Cu")
		(net "MPLLAV33")
	)
	(via
		(at 43.699938 -144.999964)
		(size 0.4572)
		(drill 0.2032)
		(layers "F.Cu" "B.Cu")
		(net "MPLLAV33")
	)
	(via
		(at 41.299638 -140.999972)
		(size 0.4572)
		(drill 0.2032)
		(layers "F.Cu" "B.Cu")
		(net "MPLLAV33")
	)
	(segment
		(start 38.4429 -145.996152)
		(end 38.912292 -145.52676)
		(width 0.508)
		(layer "B.Cu")
		(net "MPLLAV33")
	)
	(segment
		(start 35.687 -147.8534)
		(end 38.031674 -147.8534)
		(width 0.508)
		(layer "B.Cu")
		(net "MPLLAV33")
	)
	(segment
		(start 38.425628 -147.476972)
		(end 38.4429 -147.4597)
		(width 0.508)
		(layer "B.Cu")
		(net "MPLLAV33")
	)
	(segment
		(start 33.9344 -150.3807)
		(end 32.9819 -150.3807)
		(width 0.508)
		(layer "B.Cu")
		(net "MPLLAV33")
	)
	(segment
		(start 38.912292 -145.52676)
		(end 39.2811 -145.52676)
		(width 0.508)
		(layer "B.Cu")
		(net "MPLLAV33")
	)
	(segment
		(start 38.031674 -147.8534)
		(end 38.408102 -147.476972)
		(width 0.508)
		(layer "B.Cu")
		(net "MPLLAV33")
	)
	(segment
		(start 38.408102 -147.476972)
		(end 38.425628 -147.476972)
		(width 0.508)
		(layer "B.Cu")
		(net "MPLLAV33")
	)
	(segment
		(start 35.1409 -148.3995)
		(end 35.687 -147.8534)
		(width 0.508)
		(layer "B.Cu")
		(net "MPLLAV33")
	)
	(segment
		(start 43.645836 -144.999964)
		(end 43.699938 -144.999964)
		(width 0.381)
		(layer "B.Cu")
		(net "MPLLAV33")
	)
	(segment
		(start 41.6814 -141.381734)
		(end 41.299638 -140.999972)
		(width 0.1016)
		(layer "B.Cu")
		(net "MPLLAV33")
	)
	(segment
		(start 34.8234 -150.3807)
		(end 34.8234 -148.717)
		(width 0.508)
		(layer "B.Cu")
		(net "MPLLAV33")
	)
	(segment
		(start 38.4429 -147.4597)
		(end 38.4429 -145.996152)
		(width 0.508)
		(layer "B.Cu")
		(net "MPLLAV33")
	)
	(segment
		(start 33.9344 -150.3807)
		(end 34.8234 -150.3807)
		(width 0.508)
		(layer "B.Cu")
		(net "MPLLAV33")
	)
	(segment
		(start 34.8234 -148.717)
		(end 35.1409 -148.3995)
		(width 0.508)
		(layer "B.Cu")
		(net "MPLLAV33")
	)
	(segment
		(start 43.11904 -145.52676)
		(end 43.645836 -144.999964)
		(width 0.381)
		(layer "B.Cu")
		(net "MPLLAV33")
	)
	(segment
		(start 32.9819 -150.3807)
		(end 32.7914 -150.1902)
		(width 0.508)
		(layer "B.Cu")
		(net "MPLLAV33")
	)
	(segment
		(start 41.6814 -145.52676)
		(end 43.11904 -145.52676)
		(width 0.381)
		(layer "B.Cu")
		(net "MPLLAV33")
	)
	(segment
		(start 39.2811 -145.52676)
		(end 41.6814 -145.52676)
		(width 0.381)
		(layer "B.Cu")
		(net "MPLLAV33")
	)
	(segment
		(start 32.4104 -149.8092)
		(end 32.7914 -150.1902)
		(width 0.508)
		(layer "B.Cu")
		(net "MPLLAV33")
	)
	(segment
		(start 41.6814 -145.52676)
		(end 41.6814 -141.381734)
		(width 0.1016)
		(layer "B.Cu")
		(net "MPLLAV33")
	)
	(segment
		(start 31.1404 -149.8092)
		(end 32.4104 -149.8092)
		(width 0.508)
		(layer "B.Cu")
		(net "MPLLAV33")
	)
	(segment
		(start 179.268628 -62.1792)
		(end 178.816 -62.1792)
		(width 0.127)
		(layer "F.Cu")
		(net "MEM_CLK_SEL")
	)
	(segment
		(start 177.8127 -62.1792)
		(end 178.816 -62.1792)
		(width 0.127)
		(layer "F.Cu")
		(net "MEM_CLK_SEL")
	)
	(segment
		(start 181.65699 -63.44285)
		(end 180.532278 -63.44285)
		(width 0.127)
		(layer "F.Cu")
		(net "MEM_CLK_SEL")
	)
	(segment
		(start 181.99989 -63.09995)
		(end 181.65699 -63.44285)
		(width 0.127)
		(layer "F.Cu")
		(net "MEM_CLK_SEL")
	)
	(segment
		(start 180.532278 -63.44285)
		(end 179.268628 -62.1792)
		(width 0.127)
		(layer "F.Cu")
		(net "MEM_CLK_SEL")
	)
	(via
		(at 178.816 -62.1792)
		(size 0.6604)
		(drill 0.3302)
		(layers "F.Cu" "B.Cu")
		(net "MEM_CLK_SEL")
	)
	(segment
		(start 11.32967 -141.863064)
		(end 11.20267 -141.736064)
		(width 0.127)
		(layer "F.Cu")
		(net "MEMWEN")
	)
	(segment
		(start 17.291558 -140.218668)
		(end 16.296132 -140.218668)
		(width 0.127)
		(layer "F.Cu")
		(net "MEMWEN")
	)
	(segment
		(start 11.32967 -142.220696)
		(end 11.32967 -141.863064)
		(width 0.127)
		(layer "F.Cu")
		(net "MEMWEN")
	)
	(segment
		(start 11.0744 -141.736064)
		(end 10.347198 -141.008862)
		(width 0.127)
		(layer "F.Cu")
		(net "MEMWEN")
	)
	(segment
		(start 11.96467 -141.736064)
		(end 11.83767 -141.863064)
		(width 0.127)
		(layer "F.Cu")
		(net "MEMWEN")
	)
	(segment
		(start 12.85367 -141.863064)
		(end 12.85367 -142.220696)
		(width 0.127)
		(layer "F.Cu")
		(net "MEMWEN")
	)
	(segment
		(start 11.83767 -142.220696)
		(end 11.71067 -142.347696)
		(width 0.127)
		(layer "F.Cu")
		(net "MEMWEN")
	)
	(segment
		(start 12.85367 -142.220696)
		(end 12.72667 -142.347696)
		(width 0.127)
		(layer "F.Cu")
		(net "MEMWEN")
	)
	(segment
		(start 12.34567 -141.863064)
		(end 12.21867 -141.736064)
		(width 0.127)
		(layer "F.Cu")
		(net "MEMWEN")
	)
	(segment
		(start 15.944088 -140.561314)
		(end 14.769338 -141.736064)
		(width 0.127)
		(layer "F.Cu")
		(net "MEMWEN")
	)
	(segment
		(start 15.953486 -140.561314)
		(end 15.944088 -140.561314)
		(width 0.127)
		(layer "F.Cu")
		(net "MEMWEN")
	)
	(segment
		(start 17.634458 -140.561568)
		(end 17.291558 -140.218668)
		(width 0.127)
		(layer "F.Cu")
		(net "MEMWEN")
	)
	(segment
		(start 9.331198 -141.008862)
		(end 10.347198 -141.008862)
		(width 0.127)
		(layer "F.Cu")
		(net "MEMWEN")
	)
	(segment
		(start 11.71067 -142.347696)
		(end 11.45667 -142.347696)
		(width 0.127)
		(layer "F.Cu")
		(net "MEMWEN")
	)
	(segment
		(start 11.45667 -142.347696)
		(end 11.32967 -142.220696)
		(width 0.127)
		(layer "F.Cu")
		(net "MEMWEN")
	)
	(segment
		(start 17.634458 -140.561822)
		(end 17.634458 -140.561568)
		(width 0.127)
		(layer "F.Cu")
		(net "MEMWEN")
	)
	(segment
		(start 12.47267 -142.347696)
		(end 12.34567 -142.220696)
		(width 0.127)
		(layer "F.Cu")
		(net "MEMWEN")
	)
	(segment
		(start 14.769338 -141.736064)
		(end 12.98067 -141.736064)
		(width 0.127)
		(layer "F.Cu")
		(net "MEMWEN")
	)
	(segment
		(start 12.21867 -141.736064)
		(end 11.96467 -141.736064)
		(width 0.127)
		(layer "F.Cu")
		(net "MEMWEN")
	)
	(segment
		(start 12.98067 -141.736064)
		(end 12.85367 -141.863064)
		(width 0.127)
		(layer "F.Cu")
		(net "MEMWEN")
	)
	(segment
		(start 16.296132 -140.218668)
		(end 15.953486 -140.561314)
		(width 0.127)
		(layer "F.Cu")
		(net "MEMWEN")
	)
	(segment
		(start 12.34567 -142.220696)
		(end 12.34567 -141.863064)
		(width 0.127)
		(layer "F.Cu")
		(net "MEMWEN")
	)
	(segment
		(start 41.299892 -144.200118)
		(end 40.900096 -144.599914)
		(width 0.127)
		(layer "F.Cu")
		(net "MEMWEN")
	)
	(segment
		(start 11.20267 -141.736064)
		(end 11.0744 -141.736064)
		(width 0.127)
		(layer "F.Cu")
		(net "MEMWEN")
	)
	(segment
		(start 11.83767 -141.863064)
		(end 11.83767 -142.220696)
		(width 0.127)
		(layer "F.Cu")
		(net "MEMWEN")
	)
	(segment
		(start 17.234662 -140.961618)
		(end 17.634458 -140.561822)
		(width 0.127)
		(layer "F.Cu")
		(net "MEMWEN")
	)
	(segment
		(start 12.72667 -142.347696)
		(end 12.47267 -142.347696)
		(width 0.127)
		(layer "F.Cu")
		(net "MEMWEN")
	)
	(segment
		(start 40.900096 -144.599914)
		(end 40.899842 -144.599914)
		(width 0.127)
		(layer "F.Cu")
		(net "MEMWEN")
	)
	(via
		(at 41.299892 -144.200118)
		(size 0.4572)
		(drill 0.2032)
		(layers "F.Cu" "B.Cu")
		(net "MEMWEN")
	)
	(via
		(at 17.234662 -140.961618)
		(size 0.508)
		(drill 0.254)
		(layers "F.Cu" "B.Cu")
		(net "MEMWEN")
	)
	(segment
		(start 20.878038 -141.09446)
		(end 20.789138 -141.00556)
		(width 0.0889)
		(layer "In5.Cu")
		(net "MEMWEN")
	)
	(segment
		(start 40.81653 -143.933164)
		(end 40.79748 -143.91386)
		(width 0.127)
		(layer "In5.Cu")
		(net "MEMWEN")
	)
	(segment
		(start 20.077938 -140.840968)
		(end 19.989038 -140.752068)
		(width 0.0889)
		(layer "In5.Cu")
		(net "MEMWEN")
	)
	(segment
		(start 20.166838 -141.09446)
		(end 20.077938 -141.00556)
		(width 0.0889)
		(layer "In5.Cu")
		(net "MEMWEN")
	)
	(segment
		(start 27.722576 -141.252448)
		(end 27.074368 -140.60424)
		(width 0.127)
		(layer "In5.Cu")
		(net "MEMWEN")
	)
	(segment
		(start 19.989038 -140.752068)
		(end 18.647664 -140.752068)
		(width 0.0889)
		(layer "In5.Cu")
		(net "MEMWEN")
	)
	(segment
		(start 38.50513 -143.552164)
		(end 37.838634 -142.885668)
		(width 0.127)
		(layer "In5.Cu")
		(net "MEMWEN")
	)
	(segment
		(start 33.02635 -142.885414)
		(end 32.35452 -142.885414)
		(width 0.127)
		(layer "In5.Cu")
		(net "MEMWEN")
	)
	(segment
		(start 18.647664 -140.752068)
		(end 18.457164 -140.561568)
		(width 0.0889)
		(layer "In5.Cu")
		(net "MEMWEN")
	)
	(segment
		(start 20.433538 -140.840968)
		(end 20.433538 -141.00556)
		(width 0.0889)
		(layer "In5.Cu")
		(net "MEMWEN")
	)
	(segment
		(start 28.119578 -142.65275)
		(end 28.119578 -142.472918)
		(width 0.127)
		(layer "In5.Cu")
		(net "MEMWEN")
	)
	(segment
		(start 37.838634 -142.885668)
		(end 33.02635 -142.885668)
		(width 0.127)
		(layer "In5.Cu")
		(net "MEMWEN")
	)
	(segment
		(start 20.700238 -140.752068)
		(end 20.522438 -140.752068)
		(width 0.0889)
		(layer "In5.Cu")
		(net "MEMWEN")
	)
	(segment
		(start 21.144738 -140.840968)
		(end 21.144738 -141.00556)
		(width 0.0889)
		(layer "In5.Cu")
		(net "MEMWEN")
	)
	(segment
		(start 20.789138 -140.840968)
		(end 20.700238 -140.752068)
		(width 0.0889)
		(layer "In5.Cu")
		(net "MEMWEN")
	)
	(segment
		(start 17.634712 -140.561568)
		(end 17.234662 -140.961618)
		(width 0.0889)
		(layer "In5.Cu")
		(net "MEMWEN")
	)
	(segment
		(start 27.400758 -141.93393)
		(end 27.400758 -141.754098)
		(width 0.127)
		(layer "In5.Cu")
		(net "MEMWEN")
	)
	(segment
		(start 22.362414 -140.56106)
		(end 21.861018 -140.56106)
		(width 0.0889)
		(layer "In5.Cu")
		(net "MEMWEN")
	)
	(segment
		(start 28.441396 -142.1511)
		(end 28.441396 -141.971268)
		(width 0.127)
		(layer "In5.Cu")
		(net "MEMWEN")
	)
	(segment
		(start 27.400758 -141.754098)
		(end 27.722576 -141.43228)
		(width 0.127)
		(layer "In5.Cu")
		(net "MEMWEN")
	)
	(segment
		(start 20.344638 -141.09446)
		(end 20.166838 -141.09446)
		(width 0.0889)
		(layer "In5.Cu")
		(net "MEMWEN")
	)
	(segment
		(start 26.51633 -140.60424)
		(end 26.403808 -140.716762)
		(width 0.127)
		(layer "In5.Cu")
		(net "MEMWEN")
	)
	(segment
		(start 32.35452 -142.885414)
		(end 32.154114 -143.08582)
		(width 0.127)
		(layer "In5.Cu")
		(net "MEMWEN")
	)
	(segment
		(start 20.522438 -140.752068)
		(end 20.433538 -140.840968)
		(width 0.0889)
		(layer "In5.Cu")
		(net "MEMWEN")
	)
	(segment
		(start 27.580336 -142.113508)
		(end 27.400758 -141.93393)
		(width 0.127)
		(layer "In5.Cu")
		(net "MEMWEN")
	)
	(segment
		(start 21.233638 -140.752068)
		(end 21.144738 -140.840968)
		(width 0.0889)
		(layer "In5.Cu")
		(net "MEMWEN")
	)
	(segment
		(start 28.800806 -142.51051)
		(end 28.478988 -142.832328)
		(width 0.127)
		(layer "In5.Cu")
		(net "MEMWEN")
	)
	(segment
		(start 28.299156 -142.832328)
		(end 28.119578 -142.65275)
		(width 0.127)
		(layer "In5.Cu")
		(net "MEMWEN")
	)
	(segment
		(start 28.261818 -141.79169)
		(end 28.081986 -141.79169)
		(width 0.127)
		(layer "In5.Cu")
		(net "MEMWEN")
	)
	(segment
		(start 20.789138 -141.00556)
		(end 20.789138 -140.840968)
		(width 0.0889)
		(layer "In5.Cu")
		(net "MEMWEN")
	)
	(segment
		(start 40.53713 -143.806164)
		(end 39.118286 -143.806164)
		(width 0.127)
		(layer "In5.Cu")
		(net "MEMWEN")
	)
	(segment
		(start 28.119578 -142.472918)
		(end 28.441396 -142.1511)
		(width 0.127)
		(layer "In5.Cu")
		(net "MEMWEN")
	)
	(segment
		(start 22.518116 -140.716762)
		(end 22.362414 -140.56106)
		(width 0.127)
		(layer "In5.Cu")
		(net "MEMWEN")
	)
	(segment
		(start 28.980638 -142.51051)
		(end 28.800806 -142.51051)
		(width 0.127)
		(layer "In5.Cu")
		(net "MEMWEN")
	)
	(segment
		(start 21.055838 -141.09446)
		(end 20.878038 -141.09446)
		(width 0.0889)
		(layer "In5.Cu")
		(net "MEMWEN")
	)
	(segment
		(start 21.861018 -140.56106)
		(end 21.67001 -140.752068)
		(width 0.0889)
		(layer "In5.Cu")
		(net "MEMWEN")
	)
	(segment
		(start 18.457164 -140.561568)
		(end 17.634712 -140.561568)
		(width 0.0889)
		(layer "In5.Cu")
		(net "MEMWEN")
	)
	(segment
		(start 27.722576 -141.43228)
		(end 27.722576 -141.252448)
		(width 0.127)
		(layer "In5.Cu")
		(net "MEMWEN")
	)
	(segment
		(start 29.555948 -143.08582)
		(end 28.980638 -142.51051)
		(width 0.127)
		(layer "In5.Cu")
		(net "MEMWEN")
	)
	(segment
		(start 33.02635 -142.885668)
		(end 33.02635 -142.885414)
		(width 0.127)
		(layer "In5.Cu")
		(net "MEMWEN")
	)
	(segment
		(start 27.074368 -140.60424)
		(end 26.51633 -140.60424)
		(width 0.127)
		(layer "In5.Cu")
		(net "MEMWEN")
	)
	(segment
		(start 40.96893 -144.085564)
		(end 40.81653 -143.933164)
		(width 0.127)
		(layer "In5.Cu")
		(net "MEMWEN")
	)
	(segment
		(start 32.154114 -143.08582)
		(end 29.555948 -143.08582)
		(width 0.127)
		(layer "In5.Cu")
		(net "MEMWEN")
	)
	(segment
		(start 21.67001 -140.752068)
		(end 21.233638 -140.752068)
		(width 0.0889)
		(layer "In5.Cu")
		(net "MEMWEN")
	)
	(segment
		(start 26.403808 -140.716762)
		(end 22.518116 -140.716762)
		(width 0.127)
		(layer "In5.Cu")
		(net "MEMWEN")
	)
	(segment
		(start 27.760168 -142.113508)
		(end 27.580336 -142.113508)
		(width 0.127)
		(layer "In5.Cu")
		(net "MEMWEN")
	)
	(segment
		(start 21.144738 -141.00556)
		(end 21.055838 -141.09446)
		(width 0.0889)
		(layer "In5.Cu")
		(net "MEMWEN")
	)
	(segment
		(start 20.077938 -141.00556)
		(end 20.077938 -140.840968)
		(width 0.0889)
		(layer "In5.Cu")
		(net "MEMWEN")
	)
	(segment
		(start 28.478988 -142.832328)
		(end 28.299156 -142.832328)
		(width 0.127)
		(layer "In5.Cu")
		(net "MEMWEN")
	)
	(segment
		(start 28.441396 -141.971268)
		(end 28.261818 -141.79169)
		(width 0.127)
		(layer "In5.Cu")
		(net "MEMWEN")
	)
	(segment
		(start 28.081986 -141.79169)
		(end 27.760168 -142.113508)
		(width 0.127)
		(layer "In5.Cu")
		(net "MEMWEN")
	)
	(segment
		(start 41.299892 -144.200118)
		(end 41.245536 -144.200118)
		(width 0.127)
		(layer "In5.Cu")
		(net "MEMWEN")
	)
	(segment
		(start 20.433538 -141.00556)
		(end 20.344638 -141.09446)
		(width 0.0889)
		(layer "In5.Cu")
		(net "MEMWEN")
	)
	(arc
		(start 39.118286 -143.806164)
		(mid 38.78644 -143.740156)
		(end 38.50513 -143.552164)
		(width 0.127)
		(layer "In5.Cu")
		(net "MEMWEN")
	)
	(arc
		(start 40.79748 -143.91386)
		(mid 40.678002 -143.834154)
		(end 40.53713 -143.806164)
		(width 0.127)
		(layer "In5.Cu")
		(net "MEMWEN")
	)
	(arc
		(start 41.245536 -144.200118)
		(mid 41.095846 -144.170343)
		(end 40.96893 -144.085564)
		(width 0.127)
		(layer "In5.Cu")
		(net "MEMWEN")
	)
	(segment
		(start 41.700196 -144.599914)
		(end 41.699942 -144.599914)
		(width 0.127)
		(layer "F.Cu")
		(net "MEMRASN")
	)
	(segment
		(start 42.099992 -144.200118)
		(end 41.700196 -144.599914)
		(width 0.127)
		(layer "F.Cu")
		(net "MEMRASN")
	)
	(segment
		(start 22.43455 -140.561568)
		(end 22.343872 -140.47089)
		(width 0.127)
		(layer "F.Cu")
		(net "MEMRASN")
	)
	(segment
		(start 22.343872 -140.47089)
		(end 22.343872 -140.470382)
		(width 0.127)
		(layer "F.Cu")
		(net "MEMRASN")
	)
	(segment
		(start 22.343872 -140.470382)
		(end 22.0345 -140.16101)
		(width 0.127)
		(layer "F.Cu")
		(net "MEMRASN")
	)
	(via
		(at 22.0345 -140.16101)
		(size 0.508)
		(drill 0.254)
		(layers "F.Cu" "B.Cu")
		(net "MEMRASN")
	)
	(via
		(at 42.099992 -144.200118)
		(size 0.4572)
		(drill 0.2032)
		(layers "F.Cu" "B.Cu")
		(net "MEMRASN")
	)
	(segment
		(start 23.337266 -140.12926)
		(end 25.3619 -140.12926)
		(width 0.127)
		(layer "B.Cu")
		(net "MEMRASN")
	)
	(segment
		(start 25.779476 -141.14018)
		(end 24.898604 -142.021052)
		(width 0.127)
		(layer "B.Cu")
		(net "MEMRASN")
	)
	(segment
		(start 24.898604 -142.021052)
		(end 24.898604 -142.282164)
		(width 0.127)
		(layer "B.Cu")
		(net "MEMRASN")
	)
	(segment
		(start 23.154132 -141.280642)
		(end 23.154132 -140.312394)
		(width 0.127)
		(layer "B.Cu")
		(net "MEMRASN")
	)
	(segment
		(start 25.3619 -139.62126)
		(end 22.57425 -139.62126)
		(width 0.127)
		(layer "B.Cu")
		(net "MEMRASN")
	)
	(segment
		(start 24.898604 -142.282164)
		(end 24.155654 -142.282164)
		(width 0.127)
		(layer "B.Cu")
		(net "MEMRASN")
	)
	(segment
		(start 25.779476 -141.03096)
		(end 25.779476 -141.14018)
		(width 0.127)
		(layer "B.Cu")
		(net "MEMRASN")
	)
	(segment
		(start 25.4889 -139.74826)
		(end 25.3619 -139.62126)
		(width 0.127)
		(layer "B.Cu")
		(net "MEMRASN")
	)
	(segment
		(start 24.155654 -142.282164)
		(end 23.154132 -141.280642)
		(width 0.127)
		(layer "B.Cu")
		(net "MEMRASN")
	)
	(segment
		(start 23.154132 -140.312394)
		(end 23.337266 -140.12926)
		(width 0.127)
		(layer "B.Cu")
		(net "MEMRASN")
	)
	(segment
		(start 25.4889 -140.00226)
		(end 25.4889 -139.74826)
		(width 0.127)
		(layer "B.Cu")
		(net "MEMRASN")
	)
	(segment
		(start 22.57425 -139.62126)
		(end 22.0345 -140.16101)
		(width 0.127)
		(layer "B.Cu")
		(net "MEMRASN")
	)
	(segment
		(start 25.3619 -140.12926)
		(end 25.4889 -140.00226)
		(width 0.127)
		(layer "B.Cu")
		(net "MEMRASN")
	)
	(segment
		(start 25.59431 -140.676376)
		(end 24.426164 -140.676376)
		(width 0.127)
		(layer "In2.Cu")
		(net "MEMRASN")
	)
	(segment
		(start 26.960322 -141.862556)
		(end 26.78049 -141.862556)
		(width 0.127)
		(layer "In2.Cu")
		(net "MEMRASN")
	)
	(segment
		(start 41.706292 -143.806418)
		(end 39.863522 -143.806418)
		(width 0.127)
		(layer "In2.Cu")
		(net "MEMRASN")
	)
	(segment
		(start 36.21532 -144.02562)
		(end 36.21532 -143.77162)
		(width 0.127)
		(layer "In2.Cu")
		(net "MEMRASN")
	)
	(segment
		(start 27.10688 -141.715998)
		(end 26.960322 -141.862556)
		(width 0.127)
		(layer "In2.Cu")
		(net "MEMRASN")
	)
	(segment
		(start 24.426164 -140.676376)
		(end 24.385778 -140.716762)
		(width 0.127)
		(layer "In2.Cu")
		(net "MEMRASN")
	)
	(segment
		(start 23.29307 -140.16101)
		(end 22.0345 -140.16101)
		(width 0.127)
		(layer "In2.Cu")
		(net "MEMRASN")
	)
	(segment
		(start 27.46629 -141.895576)
		(end 27.286712 -141.715998)
		(width 0.127)
		(layer "In2.Cu")
		(net "MEMRASN")
	)
	(segment
		(start 23.848822 -140.716762)
		(end 23.29307 -140.16101)
		(width 0.127)
		(layer "In2.Cu")
		(net "MEMRASN")
	)
	(segment
		(start 42.099992 -144.200118)
		(end 41.706292 -143.806418)
		(width 0.127)
		(layer "In2.Cu")
		(net "MEMRASN")
	)
	(segment
		(start 24.385778 -140.716762)
		(end 23.848822 -140.716762)
		(width 0.127)
		(layer "In2.Cu")
		(net "MEMRASN")
	)
	(segment
		(start 27.286712 -141.715998)
		(end 27.10688 -141.715998)
		(width 0.127)
		(layer "In2.Cu")
		(net "MEMRASN")
	)
	(segment
		(start 39.51732 -144.15262)
		(end 36.34232 -144.15262)
		(width 0.127)
		(layer "In2.Cu")
		(net "MEMRASN")
	)
	(segment
		(start 27.756612 -142.838678)
		(end 27.319732 -142.401798)
		(width 0.127)
		(layer "In2.Cu")
		(net "MEMRASN")
	)
	(segment
		(start 39.10076 -143.13662)
		(end 29.775912 -143.13662)
		(width 0.127)
		(layer "In2.Cu")
		(net "MEMRASN")
	)
	(segment
		(start 39.10076 -143.64462)
		(end 39.22776 -143.51762)
		(width 0.127)
		(layer "In2.Cu")
		(net "MEMRASN")
	)
	(segment
		(start 26.78049 -141.862556)
		(end 25.59431 -140.676376)
		(width 0.127)
		(layer "In2.Cu")
		(net "MEMRASN")
	)
	(segment
		(start 39.22776 -143.26362)
		(end 39.10076 -143.13662)
		(width 0.127)
		(layer "In2.Cu")
		(net "MEMRASN")
	)
	(segment
		(start 36.34232 -143.64462)
		(end 39.10076 -143.64462)
		(width 0.127)
		(layer "In2.Cu")
		(net "MEMRASN")
	)
	(segment
		(start 36.21532 -143.77162)
		(end 36.34232 -143.64462)
		(width 0.127)
		(layer "In2.Cu")
		(net "MEMRASN")
	)
	(segment
		(start 39.863522 -143.806418)
		(end 39.51732 -144.15262)
		(width 0.127)
		(layer "In2.Cu")
		(net "MEMRASN")
	)
	(segment
		(start 29.47797 -142.838678)
		(end 27.756612 -142.838678)
		(width 0.127)
		(layer "In2.Cu")
		(net "MEMRASN")
	)
	(segment
		(start 27.319732 -142.401798)
		(end 27.319732 -142.221966)
		(width 0.127)
		(layer "In2.Cu")
		(net "MEMRASN")
	)
	(segment
		(start 29.775912 -143.13662)
		(end 29.47797 -142.838678)
		(width 0.127)
		(layer "In2.Cu")
		(net "MEMRASN")
	)
	(segment
		(start 36.34232 -144.15262)
		(end 36.21532 -144.02562)
		(width 0.127)
		(layer "In2.Cu")
		(net "MEMRASN")
	)
	(segment
		(start 27.319732 -142.221966)
		(end 27.46629 -142.075408)
		(width 0.127)
		(layer "In2.Cu")
		(net "MEMRASN")
	)
	(segment
		(start 39.22776 -143.51762)
		(end 39.22776 -143.26362)
		(width 0.127)
		(layer "In2.Cu")
		(net "MEMRASN")
	)
	(segment
		(start 27.46629 -142.075408)
		(end 27.46629 -141.895576)
		(width 0.127)
		(layer "In2.Cu")
		(net "MEMRASN")
	)
	(segment
		(start 18.434558 -141.361668)
		(end 18.034508 -140.961618)
		(width 0.127)
		(layer "F.Cu")
		(net "MEMODT")
	)
	(segment
		(start 42.500042 -145.400014)
		(end 42.099992 -144.999964)
		(width 0.127)
		(layer "F.Cu")
		(net "MEMODT")
	)
	(via
		(at 42.099992 -144.999964)
		(size 0.4572)
		(drill 0.2032)
		(layers "F.Cu" "B.Cu")
		(net "MEMODT")
	)
	(via
		(at 18.034508 -140.961618)
		(size 0.508)
		(drill 0.254)
		(layers "F.Cu" "B.Cu")
		(net "MEMODT")
	)
	(segment
		(start 14.86027 -143.161766)
		(end 14.935708 -143.086328)
		(width 0.127)
		(layer "B.Cu")
		(net "MEMODT")
	)
	(segment
		(start 17.615408 -140.542518)
		(end 18.034508 -140.961618)
		(width 0.127)
		(layer "B.Cu")
		(net "MEMODT")
	)
	(segment
		(start 11.662156 -142.4686)
		(end 11.66749 -142.463266)
		(width 0.127)
		(layer "B.Cu")
		(net "MEMODT")
	)
	(segment
		(start 16.536924 -141.06652)
		(end 17.060926 -140.542518)
		(width 0.127)
		(layer "B.Cu")
		(net "MEMODT")
	)
	(segment
		(start 11.66749 -142.463266)
		(end 11.66749 -142.926816)
		(width 0.127)
		(layer "B.Cu")
		(net "MEMODT")
	)
	(segment
		(start 17.060926 -140.542518)
		(end 17.615408 -140.542518)
		(width 0.127)
		(layer "B.Cu")
		(net "MEMODT")
	)
	(segment
		(start 11.66749 -142.926816)
		(end 11.90244 -143.161766)
		(width 0.127)
		(layer "B.Cu")
		(net "MEMODT")
	)
	(segment
		(start 15.11554 -143.086328)
		(end 15.583154 -143.553942)
		(width 0.127)
		(layer "B.Cu")
		(net "MEMODT")
	)
	(segment
		(start 10.6299 -142.4686)
		(end 11.662156 -142.4686)
		(width 0.127)
		(layer "B.Cu")
		(net "MEMODT")
	)
	(segment
		(start 15.62989 -142.061184)
		(end 16.536924 -141.15415)
		(width 0.127)
		(layer "B.Cu")
		(net "MEMODT")
	)
	(segment
		(start 15.942564 -143.374364)
		(end 15.942564 -143.194532)
		(width 0.127)
		(layer "B.Cu")
		(net "MEMODT")
	)
	(segment
		(start 14.935708 -143.086328)
		(end 15.11554 -143.086328)
		(width 0.127)
		(layer "B.Cu")
		(net "MEMODT")
	)
	(segment
		(start 15.762986 -143.553942)
		(end 15.942564 -143.374364)
		(width 0.127)
		(layer "B.Cu")
		(net "MEMODT")
	)
	(segment
		(start 15.583154 -143.553942)
		(end 15.762986 -143.553942)
		(width 0.127)
		(layer "B.Cu")
		(net "MEMODT")
	)
	(segment
		(start 15.47495 -142.726918)
		(end 15.47495 -142.547086)
		(width 0.127)
		(layer "B.Cu")
		(net "MEMODT")
	)
	(segment
		(start 16.536924 -141.15415)
		(end 16.536924 -141.06652)
		(width 0.127)
		(layer "B.Cu")
		(net "MEMODT")
	)
	(segment
		(start 15.942564 -143.194532)
		(end 15.47495 -142.726918)
		(width 0.127)
		(layer "B.Cu")
		(net "MEMODT")
	)
	(segment
		(start 15.47495 -142.547086)
		(end 15.62989 -142.392146)
		(width 0.127)
		(layer "B.Cu")
		(net "MEMODT")
	)
	(segment
		(start 15.62989 -142.392146)
		(end 15.62989 -142.061184)
		(width 0.127)
		(layer "B.Cu")
		(net "MEMODT")
	)
	(segment
		(start 11.90244 -143.161766)
		(end 14.86027 -143.161766)
		(width 0.127)
		(layer "B.Cu")
		(net "MEMODT")
	)
	(segment
		(start 18.707354 -141.27226)
		(end 18.707354 -141.04874)
		(width 0.0889)
		(layer "In5.Cu")
		(net "MEMODT")
	)
	(segment
		(start 19.774154 -141.04874)
		(end 19.774154 -141.27226)
		(width 0.0889)
		(layer "In5.Cu")
		(net "MEMODT")
	)
	(segment
		(start 18.618454 -141.36116)
		(end 18.707354 -141.27226)
		(width 0.0889)
		(layer "In5.Cu")
		(net "MEMODT")
	)
	(segment
		(start 19.062954 -141.71168)
		(end 19.167094 -141.81582)
		(width 0.0889)
		(layer "In5.Cu")
		(net "MEMODT")
	)
	(segment
		(start 19.418554 -141.04874)
		(end 19.507454 -140.95984)
		(width 0.0889)
		(layer "In5.Cu")
		(net "MEMODT")
	)
	(segment
		(start 20.036536 -141.534642)
		(end 20.036536 -141.86154)
		(width 0.0889)
		(layer "In5.Cu")
		(net "MEMODT")
	)
	(segment
		(start 19.314414 -141.81582)
		(end 19.418554 -141.71168)
		(width 0.0889)
		(layer "In5.Cu")
		(net "MEMODT")
	)
	(segment
		(start 19.418554 -141.71168)
		(end 19.418554 -141.04874)
		(width 0.0889)
		(layer "In5.Cu")
		(net "MEMODT")
	)
	(segment
		(start 32.65551 -143.393668)
		(end 37.737034 -143.393668)
		(width 0.127)
		(layer "In5.Cu")
		(net "MEMODT")
	)
	(segment
		(start 20.392136 -141.45006)
		(end 20.481036 -141.36116)
		(width 0.0889)
		(layer "In5.Cu")
		(net "MEMODT")
	)
	(segment
		(start 29.128212 -143.610076)
		(end 32.439102 -143.610076)
		(width 0.127)
		(layer "In5.Cu")
		(net "MEMODT")
	)
	(segment
		(start 19.507454 -140.95984)
		(end 19.685254 -140.95984)
		(width 0.0889)
		(layer "In5.Cu")
		(net "MEMODT")
	)
	(segment
		(start 22.490938 -141.36116)
		(end 22.753066 -141.099032)
		(width 0.127)
		(layer "In5.Cu")
		(net "MEMODT")
	)
	(segment
		(start 18.034508 -141.216888)
		(end 18.17878 -141.36116)
		(width 0.0889)
		(layer "In5.Cu")
		(net "MEMODT")
	)
	(segment
		(start 19.167094 -141.81582)
		(end 19.314414 -141.81582)
		(width 0.0889)
		(layer "In5.Cu")
		(net "MEMODT")
	)
	(segment
		(start 42.09923 -144.999964)
		(end 42.099992 -144.999964)
		(width 0.127)
		(layer "In5.Cu")
		(net "MEMODT")
	)
	(segment
		(start 19.062954 -141.04874)
		(end 19.062954 -141.71168)
		(width 0.0889)
		(layer "In5.Cu")
		(net "MEMODT")
	)
	(segment
		(start 24.584406 -141.450822)
		(end 26.109676 -141.450822)
		(width 0.127)
		(layer "In5.Cu")
		(net "MEMODT")
	)
	(segment
		(start 19.685254 -140.95984)
		(end 19.774154 -141.04874)
		(width 0.0889)
		(layer "In5.Cu")
		(net "MEMODT")
	)
	(segment
		(start 32.439102 -143.610076)
		(end 32.65551 -143.393668)
		(width 0.127)
		(layer "In5.Cu")
		(net "MEMODT")
	)
	(segment
		(start 37.737034 -143.393668)
		(end 38.45433 -144.110964)
		(width 0.127)
		(layer "In5.Cu")
		(net "MEMODT")
	)
	(segment
		(start 24.232616 -141.099032)
		(end 24.584406 -141.450822)
		(width 0.127)
		(layer "In5.Cu")
		(net "MEMODT")
	)
	(segment
		(start 18.796254 -140.95984)
		(end 18.974054 -140.95984)
		(width 0.0889)
		(layer "In5.Cu")
		(net "MEMODT")
	)
	(segment
		(start 18.17878 -141.36116)
		(end 18.618454 -141.36116)
		(width 0.0889)
		(layer "In5.Cu")
		(net "MEMODT")
	)
	(segment
		(start 20.036536 -141.86154)
		(end 20.140676 -141.96568)
		(width 0.0889)
		(layer "In5.Cu")
		(net "MEMODT")
	)
	(segment
		(start 41.54043 -144.682464)
		(end 41.687242 -144.829276)
		(width 0.127)
		(layer "In5.Cu")
		(net "MEMODT")
	)
	(segment
		(start 18.974054 -140.95984)
		(end 19.062954 -141.04874)
		(width 0.0889)
		(layer "In5.Cu")
		(net "MEMODT")
	)
	(segment
		(start 28.049474 -143.39062)
		(end 28.908756 -143.39062)
		(width 0.127)
		(layer "In5.Cu")
		(net "MEMODT")
	)
	(segment
		(start 39.619428 -144.593564)
		(end 39.632128 -144.606264)
		(width 0.127)
		(layer "In5.Cu")
		(net "MEMODT")
	)
	(segment
		(start 18.707354 -141.04874)
		(end 18.796254 -140.95984)
		(width 0.0889)
		(layer "In5.Cu")
		(net "MEMODT")
	)
	(segment
		(start 20.287996 -141.96568)
		(end 20.392136 -141.86154)
		(width 0.0889)
		(layer "In5.Cu")
		(net "MEMODT")
	)
	(segment
		(start 18.034508 -140.961618)
		(end 18.034508 -141.216888)
		(width 0.0889)
		(layer "In5.Cu")
		(net "MEMODT")
	)
	(segment
		(start 26.109676 -141.450822)
		(end 28.049474 -143.39062)
		(width 0.127)
		(layer "In5.Cu")
		(net "MEMODT")
	)
	(segment
		(start 20.481036 -141.36116)
		(end 22.490938 -141.36116)
		(width 0.0889)
		(layer "In5.Cu")
		(net "MEMODT")
	)
	(segment
		(start 19.774154 -141.27226)
		(end 20.036536 -141.534642)
		(width 0.0889)
		(layer "In5.Cu")
		(net "MEMODT")
	)
	(segment
		(start 20.140676 -141.96568)
		(end 20.287996 -141.96568)
		(width 0.0889)
		(layer "In5.Cu")
		(net "MEMODT")
	)
	(segment
		(start 28.908756 -143.39062)
		(end 29.128212 -143.610076)
		(width 0.127)
		(layer "In5.Cu")
		(net "MEMODT")
	)
	(segment
		(start 20.392136 -141.86154)
		(end 20.392136 -141.45006)
		(width 0.0889)
		(layer "In5.Cu")
		(net "MEMODT")
	)
	(segment
		(start 39.632128 -144.606264)
		(end 41.3131 -144.606264)
		(width 0.127)
		(layer "In5.Cu")
		(net "MEMODT")
	)
	(segment
		(start 22.753066 -141.099032)
		(end 24.232616 -141.099032)
		(width 0.127)
		(layer "In5.Cu")
		(net "MEMODT")
	)
	(arc
		(start 38.45433 -144.110964)
		(mid 38.988882 -144.46814)
		(end 39.619428 -144.593564)
		(width 0.127)
		(layer "In5.Cu")
		(net "MEMODT")
	)
	(arc
		(start 41.687242 -144.829276)
		(mid 41.876264 -144.955576)
		(end 42.09923 -144.999964)
		(width 0.127)
		(layer "In5.Cu")
		(net "MEMODT")
	)
	(arc
		(start 41.3131 -144.606264)
		(mid 41.43298 -144.625821)
		(end 41.54043 -144.682464)
		(width 0.127)
		(layer "In5.Cu")
		(net "MEMODT")
	)
	(segment
		(start 40.900096 -147.80006)
		(end 40.899842 -147.80006)
		(width 0.127)
		(layer "F.Cu")
		(net "MEMDQ_9")
	)
	(segment
		(start 24.279098 -147.75942)
		(end 24.52878 -147.75942)
		(width 0.127)
		(layer "F.Cu")
		(net "MEMDQ_9")
	)
	(segment
		(start 22.43455 -147.761452)
		(end 22.77745 -148.104352)
		(width 0.127)
		(layer "F.Cu")
		(net "MEMDQ_9")
	)
	(segment
		(start 41.299892 -148.199856)
		(end 40.900096 -147.80006)
		(width 0.127)
		(layer "F.Cu")
		(net "MEMDQ_9")
	)
	(segment
		(start 23.934166 -148.104352)
		(end 24.279098 -147.75942)
		(width 0.127)
		(layer "F.Cu")
		(net "MEMDQ_9")
	)
	(segment
		(start 22.77745 -148.104352)
		(end 23.934166 -148.104352)
		(width 0.127)
		(layer "F.Cu")
		(net "MEMDQ_9")
	)
	(via
		(at 24.52878 -147.75942)
		(size 0.508)
		(drill 0.254)
		(layers "F.Cu" "B.Cu")
		(net "MEMDQ_9")
	)
	(via
		(at 41.299892 -148.199856)
		(size 0.4572)
		(drill 0.2032)
		(layers "F.Cu" "B.Cu")
		(net "MEMDQ_9")
	)
	(segment
		(start 38.116764 -150.77948)
		(end 38.243764 -150.65248)
		(width 0.127)
		(layer "In2.Cu")
		(net "MEMDQ_9")
	)
	(segment
		(start 31.23438 -150.0886)
		(end 31.10738 -150.2156)
		(width 0.127)
		(layer "In2.Cu")
		(net "MEMDQ_9")
	)
	(segment
		(start 41.1734 -148.073364)
		(end 41.299892 -148.199856)
		(width 0.127)
		(layer "In2.Cu")
		(net "MEMDQ_9")
	)
	(segment
		(start 38.243764 -150.65248)
		(end 38.243764 -148.423376)
		(width 0.127)
		(layer "In2.Cu")
		(net "MEMDQ_9")
	)
	(segment
		(start 37.365432 -148.327872)
		(end 37.481764 -148.444204)
		(width 0.127)
		(layer "In2.Cu")
		(net "MEMDQ_9")
	)
	(segment
		(start 34.7472 -150.42896)
		(end 34.7472 -149.519386)
		(width 0.127)
		(layer "In2.Cu")
		(net "MEMDQ_9")
	)
	(segment
		(start 34.7472 -149.519386)
		(end 35.716464 -148.550122)
		(width 0.127)
		(layer "In2.Cu")
		(net "MEMDQ_9")
	)
	(segment
		(start 36.425378 -148.327872)
		(end 37.365432 -148.327872)
		(width 0.127)
		(layer "In2.Cu")
		(net "MEMDQ_9")
	)
	(segment
		(start 31.23438 -150.8506)
		(end 34.32556 -150.8506)
		(width 0.127)
		(layer "In2.Cu")
		(net "MEMDQ_9")
	)
	(segment
		(start 37.608764 -150.77948)
		(end 38.116764 -150.77948)
		(width 0.127)
		(layer "In2.Cu")
		(net "MEMDQ_9")
	)
	(segment
		(start 31.10738 -150.2156)
		(end 31.10738 -150.7236)
		(width 0.127)
		(layer "In2.Cu")
		(net "MEMDQ_9")
	)
	(segment
		(start 24.52878 -147.75942)
		(end 26.09596 -149.3266)
		(width 0.127)
		(layer "In2.Cu")
		(net "MEMDQ_9")
	)
	(segment
		(start 36.203128 -148.550122)
		(end 36.425378 -148.327872)
		(width 0.127)
		(layer "In2.Cu")
		(net "MEMDQ_9")
	)
	(segment
		(start 32.42564 -149.4536)
		(end 32.42564 -149.9616)
		(width 0.127)
		(layer "In2.Cu")
		(net "MEMDQ_9")
	)
	(segment
		(start 32.29864 -149.3266)
		(end 32.42564 -149.4536)
		(width 0.127)
		(layer "In2.Cu")
		(net "MEMDQ_9")
	)
	(segment
		(start 37.481764 -148.444204)
		(end 37.481764 -150.65248)
		(width 0.127)
		(layer "In2.Cu")
		(net "MEMDQ_9")
	)
	(segment
		(start 38.593776 -148.073364)
		(end 41.1734 -148.073364)
		(width 0.127)
		(layer "In2.Cu")
		(net "MEMDQ_9")
	)
	(segment
		(start 34.32556 -150.8506)
		(end 34.7472 -150.42896)
		(width 0.127)
		(layer "In2.Cu")
		(net "MEMDQ_9")
	)
	(segment
		(start 26.09596 -149.3266)
		(end 32.29864 -149.3266)
		(width 0.127)
		(layer "In2.Cu")
		(net "MEMDQ_9")
	)
	(segment
		(start 32.29864 -150.0886)
		(end 31.23438 -150.0886)
		(width 0.127)
		(layer "In2.Cu")
		(net "MEMDQ_9")
	)
	(segment
		(start 38.243764 -148.423376)
		(end 38.593776 -148.073364)
		(width 0.127)
		(layer "In2.Cu")
		(net "MEMDQ_9")
	)
	(segment
		(start 37.481764 -150.65248)
		(end 37.608764 -150.77948)
		(width 0.127)
		(layer "In2.Cu")
		(net "MEMDQ_9")
	)
	(segment
		(start 31.10738 -150.7236)
		(end 31.23438 -150.8506)
		(width 0.127)
		(layer "In2.Cu")
		(net "MEMDQ_9")
	)
	(segment
		(start 35.716464 -148.550122)
		(end 36.203128 -148.550122)
		(width 0.127)
		(layer "In2.Cu")
		(net "MEMDQ_9")
	)
	(segment
		(start 32.42564 -149.9616)
		(end 32.29864 -150.0886)
		(width 0.127)
		(layer "In2.Cu")
		(net "MEMDQ_9")
	)
	(segment
		(start 36.529264 -148.4503)
		(end 36.547044 -148.4503)
		(width 0.127)
		(layer "F.Cu")
		(net "MEMDQ_8")
	)
	(segment
		(start 20.238466 -150.36546)
		(end 22.58822 -150.36546)
		(width 0.127)
		(layer "F.Cu")
		(net "MEMDQ_8")
	)
	(segment
		(start 20.00504 -148.717)
		(end 20.00504 -150.132034)
		(width 0.127)
		(layer "F.Cu")
		(net "MEMDQ_8")
	)
	(segment
		(start 18.434558 -148.561552)
		(end 18.463006 -148.59)
		(width 0.127)
		(layer "F.Cu")
		(net "MEMDQ_8")
	)
	(segment
		(start 36.2839 -148.713444)
		(end 36.2839 -148.695664)
		(width 0.127)
		(layer "F.Cu")
		(net "MEMDQ_8")
	)
	(segment
		(start 35.539172 -149.458172)
		(end 36.2839 -148.713444)
		(width 0.127)
		(layer "F.Cu")
		(net "MEMDQ_8")
	)
	(segment
		(start 18.463006 -148.59)
		(end 19.87804 -148.59)
		(width 0.127)
		(layer "F.Cu")
		(net "MEMDQ_8")
	)
	(segment
		(start 25.064466 -150.09368)
		(end 27.83459 -150.09368)
		(width 0.127)
		(layer "F.Cu")
		(net "MEMDQ_8")
	)
	(segment
		(start 20.00504 -150.132034)
		(end 20.238466 -150.36546)
		(width 0.127)
		(layer "F.Cu")
		(net "MEMDQ_8")
	)
	(segment
		(start 24.612854 -150.22068)
		(end 24.937466 -150.22068)
		(width 0.127)
		(layer "F.Cu")
		(net "MEMDQ_8")
	)
	(segment
		(start 22.944074 -151.88946)
		(end 24.612854 -150.22068)
		(width 0.127)
		(layer "F.Cu")
		(net "MEMDQ_8")
	)
	(segment
		(start 20.54098 -151.76246)
		(end 20.66798 -151.88946)
		(width 0.127)
		(layer "F.Cu")
		(net "MEMDQ_8")
	)
	(segment
		(start 39.287196 -148.231098)
		(end 39.31793 -148.200364)
		(width 0.127)
		(layer "F.Cu")
		(net "MEMDQ_8")
	)
	(segment
		(start 24.937466 -150.22068)
		(end 25.064466 -150.09368)
		(width 0.127)
		(layer "F.Cu")
		(net "MEMDQ_8")
	)
	(segment
		(start 22.71522 -151.00046)
		(end 22.58822 -151.12746)
		(width 0.127)
		(layer "F.Cu")
		(net "MEMDQ_8")
	)
	(segment
		(start 22.71522 -150.49246)
		(end 22.71522 -151.00046)
		(width 0.127)
		(layer "F.Cu")
		(net "MEMDQ_8")
	)
	(segment
		(start 22.58822 -150.36546)
		(end 22.71522 -150.49246)
		(width 0.127)
		(layer "F.Cu")
		(net "MEMDQ_8")
	)
	(segment
		(start 19.87804 -148.59)
		(end 20.00504 -148.717)
		(width 0.127)
		(layer "F.Cu")
		(net "MEMDQ_8")
	)
	(segment
		(start 36.766246 -148.231098)
		(end 39.287196 -148.231098)
		(width 0.127)
		(layer "F.Cu")
		(net "MEMDQ_8")
	)
	(segment
		(start 20.54098 -151.25446)
		(end 20.54098 -151.76246)
		(width 0.127)
		(layer "F.Cu")
		(net "MEMDQ_8")
	)
	(segment
		(start 20.66798 -151.12746)
		(end 20.54098 -151.25446)
		(width 0.127)
		(layer "F.Cu")
		(net "MEMDQ_8")
	)
	(segment
		(start 36.2839 -148.695664)
		(end 36.529264 -148.4503)
		(width 0.127)
		(layer "F.Cu")
		(net "MEMDQ_8")
	)
	(segment
		(start 22.58822 -151.12746)
		(end 20.66798 -151.12746)
		(width 0.127)
		(layer "F.Cu")
		(net "MEMDQ_8")
	)
	(segment
		(start 39.969694 -147.930362)
		(end 40.099996 -147.80006)
		(width 0.127)
		(layer "F.Cu")
		(net "MEMDQ_8")
	)
	(segment
		(start 27.83459 -150.09368)
		(end 28.470098 -149.458172)
		(width 0.127)
		(layer "F.Cu")
		(net "MEMDQ_8")
	)
	(segment
		(start 20.66798 -151.88946)
		(end 22.944074 -151.88946)
		(width 0.127)
		(layer "F.Cu")
		(net "MEMDQ_8")
	)
	(segment
		(start 28.470098 -149.458172)
		(end 35.539172 -149.458172)
		(width 0.127)
		(layer "F.Cu")
		(net "MEMDQ_8")
	)
	(segment
		(start 36.547044 -148.4503)
		(end 36.766246 -148.231098)
		(width 0.127)
		(layer "F.Cu")
		(net "MEMDQ_8")
	)
	(arc
		(start 39.31793 -148.200364)
		(mid 39.670675 -148.130199)
		(end 39.969694 -147.930362)
		(width 0.127)
		(layer "F.Cu")
		(net "MEMDQ_8")
	)
	(segment
		(start 21.234654 -142.56131)
		(end 21.2344 -142.56131)
		(width 0.127)
		(layer "F.Cu")
		(net "MEMDQ_7")
	)
	(segment
		(start 42.500042 -146.99996)
		(end 42.099992 -147.40001)
		(width 0.127)
		(layer "F.Cu")
		(net "MEMDQ_7")
	)
	(segment
		(start 21.63445 -142.161514)
		(end 21.234654 -142.56131)
		(width 0.127)
		(layer "F.Cu")
		(net "MEMDQ_7")
	)
	(via
		(at 21.2344 -142.56131)
		(size 0.508)
		(drill 0.254)
		(layers "F.Cu" "B.Cu")
		(net "MEMDQ_7")
	)
	(via
		(at 42.099992 -147.40001)
		(size 0.4572)
		(drill 0.2032)
		(layers "F.Cu" "B.Cu")
		(net "MEMDQ_7")
	)
	(segment
		(start 36.3728 -144.663668)
		(end 36.129468 -144.907)
		(width 0.127)
		(layer "In5.Cu")
		(net "MEMDQ_7")
	)
	(segment
		(start 43.942 -145.39468)
		(end 41.20134 -145.39468)
		(width 0.127)
		(layer "In5.Cu")
		(net "MEMDQ_7")
	)
	(segment
		(start 29.784294 -145.977864)
		(end 29.530294 -145.723864)
		(width 0.127)
		(layer "In5.Cu")
		(net "MEMDQ_7")
	)
	(segment
		(start 23.164038 -142.96136)
		(end 21.63445 -142.96136)
		(width 0.0889)
		(layer "In5.Cu")
		(net "MEMDQ_7")
	)
	(segment
		(start 39.17315 -145.680938)
		(end 38.15588 -144.663668)
		(width 0.127)
		(layer "In5.Cu")
		(net "MEMDQ_7")
	)
	(segment
		(start 36.129468 -144.907)
		(end 35.031426 -144.907)
		(width 0.127)
		(layer "In5.Cu")
		(net "MEMDQ_7")
	)
	(segment
		(start 43.909996 -146.996912)
		(end 44.09313 -146.813778)
		(width 0.127)
		(layer "In5.Cu")
		(net "MEMDQ_7")
	)
	(segment
		(start 42.363898 -146.996912)
		(end 43.909996 -146.996912)
		(width 0.127)
		(layer "In5.Cu")
		(net "MEMDQ_7")
	)
	(segment
		(start 25.583642 -142.721076)
		(end 23.404322 -142.721076)
		(width 0.127)
		(layer "In5.Cu")
		(net "MEMDQ_7")
	)
	(segment
		(start 44.09313 -146.813778)
		(end 44.09313 -145.54581)
		(width 0.127)
		(layer "In5.Cu")
		(net "MEMDQ_7")
	)
	(segment
		(start 28.983178 -145.542)
		(end 28.360624 -144.919446)
		(width 0.127)
		(layer "In5.Cu")
		(net "MEMDQ_7")
	)
	(segment
		(start 44.09313 -145.54581)
		(end 43.942 -145.39468)
		(width 0.127)
		(layer "In5.Cu")
		(net "MEMDQ_7")
	)
	(segment
		(start 41.20134 -145.39468)
		(end 40.915082 -145.680938)
		(width 0.127)
		(layer "In5.Cu")
		(net "MEMDQ_7")
	)
	(segment
		(start 40.915082 -145.680938)
		(end 39.17315 -145.680938)
		(width 0.127)
		(layer "In5.Cu")
		(net "MEMDQ_7")
	)
	(segment
		(start 35.031426 -144.907)
		(end 35.015424 -144.923002)
		(width 0.127)
		(layer "In5.Cu")
		(net "MEMDQ_7")
	)
	(segment
		(start 21.63445 -142.96136)
		(end 21.2344 -142.56131)
		(width 0.0889)
		(layer "In5.Cu")
		(net "MEMDQ_7")
	)
	(segment
		(start 29.53004 -145.723864)
		(end 29.348176 -145.542)
		(width 0.127)
		(layer "In5.Cu")
		(net "MEMDQ_7")
	)
	(segment
		(start 33.903666 -145.977864)
		(end 29.784294 -145.977864)
		(width 0.127)
		(layer "In5.Cu")
		(net "MEMDQ_7")
	)
	(segment
		(start 27.782012 -144.919446)
		(end 25.583642 -142.721076)
		(width 0.127)
		(layer "In5.Cu")
		(net "MEMDQ_7")
	)
	(segment
		(start 23.404322 -142.721076)
		(end 23.164038 -142.96136)
		(width 0.127)
		(layer "In5.Cu")
		(net "MEMDQ_7")
	)
	(segment
		(start 34.958528 -144.923002)
		(end 33.903666 -145.977864)
		(width 0.127)
		(layer "In5.Cu")
		(net "MEMDQ_7")
	)
	(segment
		(start 29.348176 -145.542)
		(end 28.983178 -145.542)
		(width 0.127)
		(layer "In5.Cu")
		(net "MEMDQ_7")
	)
	(segment
		(start 28.360624 -144.919446)
		(end 27.782012 -144.919446)
		(width 0.127)
		(layer "In5.Cu")
		(net "MEMDQ_7")
	)
	(segment
		(start 42.099992 -147.40001)
		(end 42.099992 -147.260818)
		(width 0.127)
		(layer "In5.Cu")
		(net "MEMDQ_7")
	)
	(segment
		(start 35.015424 -144.923002)
		(end 34.958528 -144.923002)
		(width 0.127)
		(layer "In5.Cu")
		(net "MEMDQ_7")
	)
	(segment
		(start 29.530294 -145.723864)
		(end 29.53004 -145.723864)
		(width 0.127)
		(layer "In5.Cu")
		(net "MEMDQ_7")
	)
	(segment
		(start 38.15588 -144.663668)
		(end 36.3728 -144.663668)
		(width 0.127)
		(layer "In5.Cu")
		(net "MEMDQ_7")
	)
	(segment
		(start 42.099992 -147.260818)
		(end 42.363898 -146.996912)
		(width 0.127)
		(layer "In5.Cu")
		(net "MEMDQ_7")
	)
	(segment
		(start 18.434558 -142.161514)
		(end 18.434558 -142.429484)
		(width 0.127)
		(layer "F.Cu")
		(net "MEMDQ_6")
	)
	(segment
		(start 18.434558 -142.429484)
		(end 19.066764 -143.06169)
		(width 0.127)
		(layer "F.Cu")
		(net "MEMDQ_6")
	)
	(segment
		(start 41.699942 -146.99996)
		(end 41.299892 -146.59991)
		(width 0.127)
		(layer "F.Cu")
		(net "MEMDQ_6")
	)
	(via
		(at 41.299892 -146.59991)
		(size 0.4572)
		(drill 0.2032)
		(layers "F.Cu" "B.Cu")
		(net "MEMDQ_6")
	)
	(via
		(at 19.066764 -143.06169)
		(size 0.508)
		(drill 0.254)
		(layers "F.Cu" "B.Cu")
		(net "MEMDQ_6")
	)
	(segment
		(start 19.066764 -142.586202)
		(end 19.17319 -142.479776)
		(width 0.0889)
		(layer "In5.Cu")
		(net "MEMDQ_6")
	)
	(segment
		(start 41.476422 -145.73377)
		(end 41.72204 -145.979388)
		(width 0.127)
		(layer "In5.Cu")
		(net "MEMDQ_6")
	)
	(segment
		(start 20.138644 -142.591282)
		(end 20.138644 -144.23009)
		(width 0.0889)
		(layer "In5.Cu")
		(net "MEMDQ_6")
	)
	(segment
		(start 23.23846 -143.76146)
		(end 23.516844 -143.483076)
		(width 0.127)
		(layer "In5.Cu")
		(net "MEMDQ_6")
	)
	(segment
		(start 41.72204 -145.979388)
		(end 41.72204 -146.44878)
		(width 0.127)
		(layer "In5.Cu")
		(net "MEMDQ_6")
	)
	(segment
		(start 20.494244 -144.23009)
		(end 20.494244 -143.85036)
		(width 0.0889)
		(layer "In5.Cu")
		(net "MEMDQ_6")
	)
	(segment
		(start 20.583144 -143.76146)
		(end 23.23846 -143.76146)
		(width 0.0889)
		(layer "In5.Cu")
		(net "MEMDQ_6")
	)
	(segment
		(start 28.044902 -145.681446)
		(end 28.667456 -146.304)
		(width 0.127)
		(layer "In5.Cu")
		(net "MEMDQ_6")
	)
	(segment
		(start 34.276284 -146.739864)
		(end 35.347148 -145.669)
		(width 0.127)
		(layer "In5.Cu")
		(net "MEMDQ_6")
	)
	(segment
		(start 23.516844 -143.483076)
		(end 24.9301 -143.483076)
		(width 0.127)
		(layer "In5.Cu")
		(net "MEMDQ_6")
	)
	(segment
		(start 20.027138 -142.479776)
		(end 20.138644 -142.591282)
		(width 0.0889)
		(layer "In5.Cu")
		(net "MEMDQ_6")
	)
	(segment
		(start 20.494244 -143.85036)
		(end 20.583144 -143.76146)
		(width 0.0889)
		(layer "In5.Cu")
		(net "MEMDQ_6")
	)
	(segment
		(start 19.066764 -143.06169)
		(end 19.066764 -142.586202)
		(width 0.0889)
		(layer "In5.Cu")
		(net "MEMDQ_6")
	)
	(segment
		(start 41.57091 -146.59991)
		(end 41.299892 -146.59991)
		(width 0.127)
		(layer "In5.Cu")
		(net "MEMDQ_6")
	)
	(segment
		(start 41.05148 -145.934938)
		(end 41.252648 -145.73377)
		(width 0.127)
		(layer "In5.Cu")
		(net "MEMDQ_6")
	)
	(segment
		(start 41.72204 -146.44878)
		(end 41.57091 -146.59991)
		(width 0.127)
		(layer "In5.Cu")
		(net "MEMDQ_6")
	)
	(segment
		(start 24.9301 -143.483076)
		(end 27.12847 -145.681446)
		(width 0.127)
		(layer "In5.Cu")
		(net "MEMDQ_6")
	)
	(segment
		(start 29.468572 -146.739864)
		(end 34.276284 -146.739864)
		(width 0.127)
		(layer "In5.Cu")
		(net "MEMDQ_6")
	)
	(segment
		(start 20.138644 -144.23009)
		(end 20.242784 -144.33423)
		(width 0.0889)
		(layer "In5.Cu")
		(net "MEMDQ_6")
	)
	(segment
		(start 27.12847 -145.681446)
		(end 28.044902 -145.681446)
		(width 0.127)
		(layer "In5.Cu")
		(net "MEMDQ_6")
	)
	(segment
		(start 39.069264 -145.934938)
		(end 41.05148 -145.934938)
		(width 0.127)
		(layer "In5.Cu")
		(net "MEMDQ_6")
	)
	(segment
		(start 36.26358 -145.669)
		(end 36.768278 -145.164302)
		(width 0.127)
		(layer "In5.Cu")
		(net "MEMDQ_6")
	)
	(segment
		(start 41.252648 -145.73377)
		(end 41.476422 -145.73377)
		(width 0.127)
		(layer "In5.Cu")
		(net "MEMDQ_6")
	)
	(segment
		(start 29.111448 -146.38274)
		(end 29.468572 -146.739864)
		(width 0.127)
		(layer "In5.Cu")
		(net "MEMDQ_6")
	)
	(segment
		(start 36.768278 -145.164302)
		(end 38.298628 -145.164302)
		(width 0.127)
		(layer "In5.Cu")
		(net "MEMDQ_6")
	)
	(segment
		(start 20.242784 -144.33423)
		(end 20.390104 -144.33423)
		(width 0.0889)
		(layer "In5.Cu")
		(net "MEMDQ_6")
	)
	(segment
		(start 35.347148 -145.669)
		(end 36.26358 -145.669)
		(width 0.127)
		(layer "In5.Cu")
		(net "MEMDQ_6")
	)
	(segment
		(start 19.17319 -142.479776)
		(end 20.027138 -142.479776)
		(width 0.0889)
		(layer "In5.Cu")
		(net "MEMDQ_6")
	)
	(segment
		(start 28.667456 -146.304)
		(end 29.032454 -146.304)
		(width 0.127)
		(layer "In5.Cu")
		(net "MEMDQ_6")
	)
	(segment
		(start 20.390104 -144.33423)
		(end 20.494244 -144.23009)
		(width 0.0889)
		(layer "In5.Cu")
		(net "MEMDQ_6")
	)
	(segment
		(start 38.298628 -145.164302)
		(end 39.069264 -145.934938)
		(width 0.127)
		(layer "In5.Cu")
		(net "MEMDQ_6")
	)
	(segment
		(start 29.032454 -146.304)
		(end 29.111448 -146.38274)
		(width 0.127)
		(layer "In5.Cu")
		(net "MEMDQ_6")
	)
	(segment
		(start 22.43455 -142.961614)
		(end 22.434296 -142.961614)
		(width 0.127)
		(layer "F.Cu")
		(net "MEMDQ_5")
	)
	(segment
		(start 22.434296 -142.961614)
		(end 22.0345 -143.36141)
		(width 0.127)
		(layer "F.Cu")
		(net "MEMDQ_5")
	)
	(segment
		(start 40.500046 -147.40001)
		(end 40.899842 -147.000214)
		(width 0.127)
		(layer "F.Cu")
		(net "MEMDQ_5")
	)
	(segment
		(start 40.899842 -147.000214)
		(end 40.899842 -146.99996)
		(width 0.127)
		(layer "F.Cu")
		(net "MEMDQ_5")
	)
	(via
		(at 40.500046 -147.40001)
		(size 0.4572)
		(drill 0.2032)
		(layers "F.Cu" "B.Cu")
		(net "MEMDQ_5")
	)
	(via
		(at 22.0345 -143.36141)
		(size 0.508)
		(drill 0.254)
		(layers "F.Cu" "B.Cu")
		(net "MEMDQ_5")
	)
	(segment
		(start 41.64584 -146.03476)
		(end 41.64584 -145.52676)
		(width 0.127)
		(layer "In2.Cu")
		(net "MEMDQ_5")
	)
	(segment
		(start 38.59276 -146.16176)
		(end 41.51884 -146.16176)
		(width 0.127)
		(layer "In2.Cu")
		(net "MEMDQ_5")
	)
	(segment
		(start 36.23564 -145.591022)
		(end 36.03244 -145.794222)
		(width 0.127)
		(layer "In2.Cu")
		(net "MEMDQ_5")
	)
	(segment
		(start 35.385756 -145.591022)
		(end 35.385756 -145.114518)
		(width 0.127)
		(layer "In2.Cu")
		(net "MEMDQ_5")
	)
	(segment
		(start 35.385756 -145.114518)
		(end 35.258756 -144.987518)
		(width 0.127)
		(layer "In2.Cu")
		(net "MEMDQ_5")
	)
	(segment
		(start 33.242504 -146.7612)
		(end 28.764992 -146.7612)
		(width 0.127)
		(layer "In2.Cu")
		(net "MEMDQ_5")
	)
	(segment
		(start 40.01643 -147.12823)
		(end 39.887144 -146.998944)
		(width 0.127)
		(layer "In2.Cu")
		(net "MEMDQ_5")
	)
	(segment
		(start 40.138604 -147.25015)
		(end 40.01643 -147.12823)
		(width 0.127)
		(layer "In2.Cu")
		(net "MEMDQ_5")
	)
	(segment
		(start 23.00351 -143.758158)
		(end 23.000208 -143.76146)
		(width 0.0889)
		(layer "In2.Cu")
		(net "MEMDQ_5")
	)
	(segment
		(start 22.43455 -143.76146)
		(end 22.0345 -143.36141)
		(width 0.0889)
		(layer "In2.Cu")
		(net "MEMDQ_5")
	)
	(segment
		(start 34.750756 -144.987518)
		(end 34.623756 -145.114518)
		(width 0.127)
		(layer "In2.Cu")
		(net "MEMDQ_5")
	)
	(segment
		(start 38.94582 -145.14576)
		(end 36.39566 -145.14576)
		(width 0.127)
		(layer "In2.Cu")
		(net "MEMDQ_5")
	)
	(segment
		(start 36.23564 -145.30578)
		(end 36.23564 -145.591022)
		(width 0.127)
		(layer "In2.Cu")
		(net "MEMDQ_5")
	)
	(segment
		(start 41.64584 -145.52676)
		(end 41.51884 -145.39976)
		(width 0.127)
		(layer "In2.Cu")
		(net "MEMDQ_5")
	)
	(segment
		(start 23.463758 -143.758158)
		(end 23.00351 -143.758158)
		(width 0.0889)
		(layer "In2.Cu")
		(net "MEMDQ_5")
	)
	(segment
		(start 35.258756 -144.987518)
		(end 34.750756 -144.987518)
		(width 0.127)
		(layer "In2.Cu")
		(net "MEMDQ_5")
	)
	(segment
		(start 41.51884 -145.39976)
		(end 39.19982 -145.39976)
		(width 0.127)
		(layer "In2.Cu")
		(net "MEMDQ_5")
	)
	(segment
		(start 39.887144 -146.998944)
		(end 38.59276 -146.998944)
		(width 0.127)
		(layer "In2.Cu")
		(net "MEMDQ_5")
	)
	(segment
		(start 41.51884 -146.16176)
		(end 41.64584 -146.03476)
		(width 0.127)
		(layer "In2.Cu")
		(net "MEMDQ_5")
	)
	(segment
		(start 34.623756 -145.379948)
		(end 33.242504 -146.7612)
		(width 0.127)
		(layer "In2.Cu")
		(net "MEMDQ_5")
	)
	(segment
		(start 23.000208 -143.76146)
		(end 22.43455 -143.76146)
		(width 0.0889)
		(layer "In2.Cu")
		(net "MEMDQ_5")
	)
	(segment
		(start 28.042362 -146.03857)
		(end 26.601674 -146.03857)
		(width 0.127)
		(layer "In2.Cu")
		(net "MEMDQ_5")
	)
	(segment
		(start 28.764992 -146.7612)
		(end 28.042362 -146.03857)
		(width 0.127)
		(layer "In2.Cu")
		(net "MEMDQ_5")
	)
	(segment
		(start 38.46576 -146.871944)
		(end 38.46576 -146.28876)
		(width 0.127)
		(layer "In2.Cu")
		(net "MEMDQ_5")
	)
	(segment
		(start 36.03244 -145.794222)
		(end 35.588956 -145.794222)
		(width 0.127)
		(layer "In2.Cu")
		(net "MEMDQ_5")
	)
	(segment
		(start 38.46576 -146.28876)
		(end 38.59276 -146.16176)
		(width 0.127)
		(layer "In2.Cu")
		(net "MEMDQ_5")
	)
	(segment
		(start 38.59276 -146.998944)
		(end 38.46576 -146.871944)
		(width 0.127)
		(layer "In2.Cu")
		(net "MEMDQ_5")
	)
	(segment
		(start 36.39566 -145.14576)
		(end 36.23564 -145.30578)
		(width 0.127)
		(layer "In2.Cu")
		(net "MEMDQ_5")
	)
	(segment
		(start 34.623756 -145.114518)
		(end 34.623756 -145.379948)
		(width 0.127)
		(layer "In2.Cu")
		(net "MEMDQ_5")
	)
	(segment
		(start 39.19982 -145.39976)
		(end 38.94582 -145.14576)
		(width 0.127)
		(layer "In2.Cu")
		(net "MEMDQ_5")
	)
	(segment
		(start 26.601674 -146.03857)
		(end 24.321262 -143.758158)
		(width 0.127)
		(layer "In2.Cu")
		(net "MEMDQ_5")
	)
	(segment
		(start 24.321262 -143.758158)
		(end 23.463758 -143.758158)
		(width 0.127)
		(layer "In2.Cu")
		(net "MEMDQ_5")
	)
	(segment
		(start 35.588956 -145.794222)
		(end 35.385756 -145.591022)
		(width 0.127)
		(layer "In2.Cu")
		(net "MEMDQ_5")
	)
	(arc
		(start 40.500046 -147.40001)
		(mid 40.304433 -147.361007)
		(end 40.138604 -147.25015)
		(width 0.127)
		(layer "In2.Cu")
		(net "MEMDQ_5")
	)
	(segment
		(start 43.299888 -147.000214)
		(end 43.299888 -146.99996)
		(width 0.127)
		(layer "F.Cu")
		(net "MEMDQ_4")
	)
	(segment
		(start 42.900092 -147.40001)
		(end 43.299888 -147.000214)
		(width 0.127)
		(layer "F.Cu")
		(net "MEMDQ_4")
	)
	(segment
		(start 17.634458 -142.961868)
		(end 17.234662 -143.361664)
		(width 0.127)
		(layer "F.Cu")
		(net "MEMDQ_4")
	)
	(segment
		(start 17.634458 -142.961614)
		(end 17.634458 -142.961868)
		(width 0.127)
		(layer "F.Cu")
		(net "MEMDQ_4")
	)
	(via
		(at 17.234662 -143.361664)
		(size 0.508)
		(drill 0.254)
		(layers "F.Cu" "B.Cu")
		(net "MEMDQ_4")
	)
	(via
		(at 42.900092 -147.40001)
		(size 0.4572)
		(drill 0.2032)
		(layers "F.Cu" "B.Cu")
		(net "MEMDQ_4")
	)
	(segment
		(start 28.250642 -148.7551)
		(end 26.7335 -148.7551)
		(width 0.127)
		(layer "In5.Cu")
		(net "MEMDQ_4")
	)
	(segment
		(start 18.499582 -144.811242)
		(end 18.2499 -144.56156)
		(width 0.0889)
		(layer "In5.Cu")
		(net "MEMDQ_4")
	)
	(segment
		(start 38.707822 -148.185378)
		(end 36.226242 -148.185378)
		(width 0.127)
		(layer "In5.Cu")
		(net "MEMDQ_4")
	)
	(segment
		(start 28.678124 -149.182582)
		(end 28.250642 -148.7551)
		(width 0.127)
		(layer "In5.Cu")
		(net "MEMDQ_4")
	)
	(segment
		(start 18.641314 -144.952974)
		(end 18.499582 -144.811242)
		(width 0.127)
		(layer "In5.Cu")
		(net "MEMDQ_4")
	)
	(segment
		(start 19.276568 -144.952974)
		(end 18.641314 -144.952974)
		(width 0.127)
		(layer "In5.Cu")
		(net "MEMDQ_4")
	)
	(segment
		(start 17.868646 -144.56156)
		(end 17.234662 -143.927576)
		(width 0.0889)
		(layer "In5.Cu")
		(net "MEMDQ_4")
	)
	(segment
		(start 17.234662 -143.927576)
		(end 17.234662 -143.361664)
		(width 0.0889)
		(layer "In5.Cu")
		(net "MEMDQ_4")
	)
	(segment
		(start 24.282146 -146.303746)
		(end 24.282146 -145.492978)
		(width 0.127)
		(layer "In5.Cu")
		(net "MEMDQ_4")
	)
	(segment
		(start 23.826978 -145.03781)
		(end 19.361404 -145.03781)
		(width 0.127)
		(layer "In5.Cu")
		(net "MEMDQ_4")
	)
	(segment
		(start 19.361404 -145.03781)
		(end 19.276568 -144.952974)
		(width 0.127)
		(layer "In5.Cu")
		(net "MEMDQ_4")
	)
	(segment
		(start 36.226242 -148.185378)
		(end 35.229038 -149.182582)
		(width 0.127)
		(layer "In5.Cu")
		(net "MEMDQ_4")
	)
	(segment
		(start 24.282146 -145.492978)
		(end 23.826978 -145.03781)
		(width 0.127)
		(layer "In5.Cu")
		(net "MEMDQ_4")
	)
	(segment
		(start 42.900092 -147.40001)
		(end 42.505884 -147.794218)
		(width 0.127)
		(layer "In5.Cu")
		(net "MEMDQ_4")
	)
	(segment
		(start 39.098982 -147.794218)
		(end 38.707822 -148.185378)
		(width 0.127)
		(layer "In5.Cu")
		(net "MEMDQ_4")
	)
	(segment
		(start 18.2499 -144.56156)
		(end 17.868646 -144.56156)
		(width 0.0889)
		(layer "In5.Cu")
		(net "MEMDQ_4")
	)
	(segment
		(start 26.7335 -148.7551)
		(end 24.282146 -146.303746)
		(width 0.127)
		(layer "In5.Cu")
		(net "MEMDQ_4")
	)
	(segment
		(start 42.505884 -147.794218)
		(end 39.098982 -147.794218)
		(width 0.127)
		(layer "In5.Cu")
		(net "MEMDQ_4")
	)
	(segment
		(start 35.229038 -149.182582)
		(end 28.678124 -149.182582)
		(width 0.127)
		(layer "In5.Cu")
		(net "MEMDQ_4")
	)
	(segment
		(start 21.634196 -142.961614)
		(end 21.2344 -143.36141)
		(width 0.127)
		(layer "F.Cu")
		(net "MEMDQ_3")
	)
	(segment
		(start 21.63445 -142.961614)
		(end 21.634196 -142.961614)
		(width 0.127)
		(layer "F.Cu")
		(net "MEMDQ_3")
	)
	(segment
		(start 40.099996 -146.19986)
		(end 39.699946 -146.59991)
		(width 0.127)
		(layer "F.Cu")
		(net "MEMDQ_3")
	)
	(via
		(at 21.2344 -143.36141)
		(size 0.508)
		(drill 0.254)
		(layers "F.Cu" "B.Cu")
		(net "MEMDQ_3")
	)
	(via
		(at 39.699946 -146.59991)
		(size 0.4572)
		(drill 0.2032)
		(layers "F.Cu" "B.Cu")
		(net "MEMDQ_3")
	)
	(segment
		(start 42.506392 -146.746468)
		(end 42.25544 -146.99742)
		(width 0.127)
		(layer "In2.Cu")
		(net "MEMDQ_3")
	)
	(segment
		(start 40.14089 -146.87423)
		(end 39.98087 -146.71421)
		(width 0.127)
		(layer "In2.Cu")
		(net "MEMDQ_3")
	)
	(segment
		(start 42.378884 -144.606264)
		(end 42.506392 -144.733772)
		(width 0.127)
		(layer "In2.Cu")
		(net "MEMDQ_3")
	)
	(segment
		(start 33.90265 -144.117822)
		(end 34.104072 -143.9164)
		(width 0.127)
		(layer "In2.Cu")
		(net "MEMDQ_3")
	)
	(segment
		(start 33.90265 -144.82699)
		(end 33.90265 -144.117822)
		(width 0.127)
		(layer "In2.Cu")
		(net "MEMDQ_3")
	)
	(segment
		(start 42.25544 -146.99742)
		(end 40.438324 -146.99742)
		(width 0.127)
		(layer "In2.Cu")
		(net "MEMDQ_3")
	)
	(segment
		(start 36.142676 -144.78)
		(end 38.52672 -144.78)
		(width 0.127)
		(layer "In2.Cu")
		(net "MEMDQ_3")
	)
	(segment
		(start 39.705026 -146.59991)
		(end 39.699946 -146.59991)
		(width 0.127)
		(layer "In2.Cu")
		(net "MEMDQ_3")
	)
	(segment
		(start 28.358084 -145.27657)
		(end 29.080714 -145.9992)
		(width 0.127)
		(layer "In2.Cu")
		(net "MEMDQ_3")
	)
	(segment
		(start 32.73044 -145.9992)
		(end 33.90265 -144.82699)
		(width 0.127)
		(layer "In2.Cu")
		(net "MEMDQ_3")
	)
	(segment
		(start 35.54222 -144.0434)
		(end 35.54222 -144.179544)
		(width 0.127)
		(layer "In2.Cu")
		(net "MEMDQ_3")
	)
	(segment
		(start 24.61387 -142.96517)
		(end 26.92527 -145.27657)
		(width 0.127)
		(layer "In2.Cu")
		(net "MEMDQ_3")
	)
	(segment
		(start 38.52672 -144.78)
		(end 38.700456 -144.606264)
		(width 0.127)
		(layer "In2.Cu")
		(net "MEMDQ_3")
	)
	(segment
		(start 35.54222 -144.179544)
		(end 36.142676 -144.78)
		(width 0.127)
		(layer "In2.Cu")
		(net "MEMDQ_3")
	)
	(segment
		(start 38.700456 -144.606264)
		(end 42.378884 -144.606264)
		(width 0.127)
		(layer "In2.Cu")
		(net "MEMDQ_3")
	)
	(segment
		(start 34.104072 -143.9164)
		(end 35.41522 -143.9164)
		(width 0.127)
		(layer "In2.Cu")
		(net "MEMDQ_3")
	)
	(segment
		(start 21.2344 -143.36141)
		(end 21.63445 -142.96136)
		(width 0.0889)
		(layer "In2.Cu")
		(net "MEMDQ_3")
	)
	(segment
		(start 26.92527 -145.27657)
		(end 28.358084 -145.27657)
		(width 0.127)
		(layer "In2.Cu")
		(net "MEMDQ_3")
	)
	(segment
		(start 21.63445 -142.96136)
		(end 23.183088 -142.96136)
		(width 0.0889)
		(layer "In2.Cu")
		(net "MEMDQ_3")
	)
	(segment
		(start 35.41522 -143.9164)
		(end 35.54222 -144.0434)
		(width 0.127)
		(layer "In2.Cu")
		(net "MEMDQ_3")
	)
	(segment
		(start 29.080714 -145.9992)
		(end 32.73044 -145.9992)
		(width 0.127)
		(layer "In2.Cu")
		(net "MEMDQ_3")
	)
	(segment
		(start 23.183088 -142.96136)
		(end 23.186898 -142.96517)
		(width 0.0889)
		(layer "In2.Cu")
		(net "MEMDQ_3")
	)
	(segment
		(start 23.186898 -142.96517)
		(end 24.61387 -142.96517)
		(width 0.127)
		(layer "In2.Cu")
		(net "MEMDQ_3")
	)
	(segment
		(start 42.506392 -144.733772)
		(end 42.506392 -146.746468)
		(width 0.127)
		(layer "In2.Cu")
		(net "MEMDQ_3")
	)
	(arc
		(start 39.98087 -146.71421)
		(mid 39.854312 -146.629646)
		(end 39.705026 -146.59991)
		(width 0.127)
		(layer "In2.Cu")
		(net "MEMDQ_3")
	)
	(arc
		(start 40.438324 -146.99742)
		(mid 40.277358 -146.965402)
		(end 40.14089 -146.87423)
		(width 0.127)
		(layer "In2.Cu")
		(net "MEMDQ_3")
	)
	(segment
		(start 40.500046 -146.59991)
		(end 40.899842 -146.200114)
		(width 0.127)
		(layer "F.Cu")
		(net "MEMDQ_2")
	)
	(segment
		(start 40.899842 -146.200114)
		(end 40.899842 -146.19986)
		(width 0.127)
		(layer "F.Cu")
		(net "MEMDQ_2")
	)
	(segment
		(start 18.434558 -142.961614)
		(end 18.034508 -142.561564)
		(width 0.127)
		(layer "F.Cu")
		(net "MEMDQ_2")
	)
	(via
		(at 40.500046 -146.59991)
		(size 0.4572)
		(drill 0.2032)
		(layers "F.Cu" "B.Cu")
		(net "MEMDQ_2")
	)
	(via
		(at 18.034508 -142.561564)
		(size 0.508)
		(drill 0.254)
		(layers "F.Cu" "B.Cu")
		(net "MEMDQ_2")
	)
	(segment
		(start 37.08654 -145.43532)
		(end 37.9222 -145.43532)
		(width 0.127)
		(layer "In5.Cu")
		(net "MEMDQ_2")
	)
	(segment
		(start 40.500046 -146.329146)
		(end 40.500046 -146.59991)
		(width 0.127)
		(layer "In5.Cu")
		(net "MEMDQ_2")
	)
	(segment
		(start 23.56104 -143.98752)
		(end 23.6982 -143.85036)
		(width 0.127)
		(layer "In5.Cu")
		(net "MEMDQ_2")
	)
	(segment
		(start 24.36114 -144.40916)
		(end 24.534876 -144.582896)
		(width 0.127)
		(layer "In5.Cu")
		(net "MEMDQ_2")
	)
	(segment
		(start 18.7071 -142.35176)
		(end 18.7071 -142.68958)
		(width 0.127)
		(layer "In5.Cu")
		(net "MEMDQ_2")
	)
	(segment
		(start 23.56104 -144.36217)
		(end 23.56104 -143.98752)
		(width 0.127)
		(layer "In5.Cu")
		(net "MEMDQ_2")
	)
	(segment
		(start 34.676842 -147.501864)
		(end 35.699446 -146.47926)
		(width 0.127)
		(layer "In5.Cu")
		(net "MEMDQ_2")
	)
	(segment
		(start 23.3426 -144.58061)
		(end 23.56104 -144.36217)
		(width 0.127)
		(layer "In5.Cu")
		(net "MEMDQ_2")
	)
	(segment
		(start 24.534876 -144.582896)
		(end 24.952198 -144.582896)
		(width 0.127)
		(layer "In5.Cu")
		(net "MEMDQ_2")
	)
	(segment
		(start 24.23414 -143.85036)
		(end 24.36114 -143.97736)
		(width 0.127)
		(layer "In5.Cu")
		(net "MEMDQ_2")
	)
	(segment
		(start 37.9222 -145.43532)
		(end 38.20922 -145.72234)
		(width 0.127)
		(layer "In5.Cu")
		(net "MEMDQ_2")
	)
	(segment
		(start 24.36114 -143.97736)
		(end 24.36114 -144.40916)
		(width 0.127)
		(layer "In5.Cu")
		(net "MEMDQ_2")
	)
	(segment
		(start 19.550888 -144.58061)
		(end 23.3426 -144.58061)
		(width 0.127)
		(layer "In5.Cu")
		(net "MEMDQ_2")
	)
	(segment
		(start 26.037794 -145.90395)
		(end 27.364944 -147.2311)
		(width 0.127)
		(layer "In5.Cu")
		(net "MEMDQ_2")
	)
	(segment
		(start 29.15285 -147.501864)
		(end 34.676842 -147.501864)
		(width 0.127)
		(layer "In5.Cu")
		(net "MEMDQ_2")
	)
	(segment
		(start 18.542 -143.50492)
		(end 18.66392 -143.62684)
		(width 0.127)
		(layer "In5.Cu")
		(net "MEMDQ_2")
	)
	(segment
		(start 18.542 -142.85468)
		(end 18.542 -143.50492)
		(width 0.127)
		(layer "In5.Cu")
		(net "MEMDQ_2")
	)
	(segment
		(start 18.034508 -142.561564)
		(end 18.034508 -142.330932)
		(width 0.127)
		(layer "In5.Cu")
		(net "MEMDQ_2")
	)
	(segment
		(start 27.364944 -147.2311)
		(end 28.882086 -147.2311)
		(width 0.127)
		(layer "In5.Cu")
		(net "MEMDQ_2")
	)
	(segment
		(start 18.034508 -142.330932)
		(end 18.14322 -142.22222)
		(width 0.127)
		(layer "In5.Cu")
		(net "MEMDQ_2")
	)
	(segment
		(start 18.66392 -143.62684)
		(end 19.0246 -143.62684)
		(width 0.127)
		(layer "In5.Cu")
		(net "MEMDQ_2")
	)
	(segment
		(start 26.037794 -145.668492)
		(end 26.037794 -145.90395)
		(width 0.127)
		(layer "In5.Cu")
		(net "MEMDQ_2")
	)
	(segment
		(start 36.95446 -145.5674)
		(end 37.08654 -145.43532)
		(width 0.127)
		(layer "In5.Cu")
		(net "MEMDQ_2")
	)
	(segment
		(start 36.95446 -146.35988)
		(end 36.95446 -145.5674)
		(width 0.127)
		(layer "In5.Cu")
		(net "MEMDQ_2")
	)
	(segment
		(start 28.882086 -147.2311)
		(end 29.15285 -147.501864)
		(width 0.127)
		(layer "In5.Cu")
		(net "MEMDQ_2")
	)
	(segment
		(start 38.20922 -146.066764)
		(end 38.33622 -146.193764)
		(width 0.127)
		(layer "In5.Cu")
		(net "MEMDQ_2")
	)
	(segment
		(start 19.0246 -143.62684)
		(end 19.440398 -144.042638)
		(width 0.127)
		(layer "In5.Cu")
		(net "MEMDQ_2")
	)
	(segment
		(start 36.83508 -146.47926)
		(end 36.95446 -146.35988)
		(width 0.127)
		(layer "In5.Cu")
		(net "MEMDQ_2")
	)
	(segment
		(start 18.14322 -142.22222)
		(end 18.57756 -142.22222)
		(width 0.127)
		(layer "In5.Cu")
		(net "MEMDQ_2")
	)
	(segment
		(start 35.699446 -146.47926)
		(end 36.83508 -146.47926)
		(width 0.127)
		(layer "In5.Cu")
		(net "MEMDQ_2")
	)
	(segment
		(start 38.20922 -145.72234)
		(end 38.20922 -146.066764)
		(width 0.127)
		(layer "In5.Cu")
		(net "MEMDQ_2")
	)
	(segment
		(start 19.440398 -144.042638)
		(end 19.440398 -144.47012)
		(width 0.127)
		(layer "In5.Cu")
		(net "MEMDQ_2")
	)
	(segment
		(start 18.57756 -142.22222)
		(end 18.7071 -142.35176)
		(width 0.127)
		(layer "In5.Cu")
		(net "MEMDQ_2")
	)
	(segment
		(start 40.364664 -146.193764)
		(end 40.500046 -146.329146)
		(width 0.127)
		(layer "In5.Cu")
		(net "MEMDQ_2")
	)
	(segment
		(start 38.33622 -146.193764)
		(end 40.364664 -146.193764)
		(width 0.127)
		(layer "In5.Cu")
		(net "MEMDQ_2")
	)
	(segment
		(start 23.6982 -143.85036)
		(end 24.23414 -143.85036)
		(width 0.127)
		(layer "In5.Cu")
		(net "MEMDQ_2")
	)
	(segment
		(start 18.7071 -142.68958)
		(end 18.542 -142.85468)
		(width 0.127)
		(layer "In5.Cu")
		(net "MEMDQ_2")
	)
	(segment
		(start 19.440398 -144.47012)
		(end 19.550888 -144.58061)
		(width 0.127)
		(layer "In5.Cu")
		(net "MEMDQ_2")
	)
	(segment
		(start 24.952198 -144.582896)
		(end 26.037794 -145.668492)
		(width 0.127)
		(layer "In5.Cu")
		(net "MEMDQ_2")
	)
	(segment
		(start 43.299888 -148.60016)
		(end 43.299888 -148.599906)
		(width 0.127)
		(layer "F.Cu")
		(net "MEMDQ_15")
	)
	(segment
		(start 42.900092 -148.999956)
		(end 43.299888 -148.60016)
		(width 0.127)
		(layer "F.Cu")
		(net "MEMDQ_15")
	)
	(segment
		(start 21.63445 -146.161506)
		(end 22.0345 -146.561556)
		(width 0.127)
		(layer "F.Cu")
		(net "MEMDQ_15")
	)
	(via
		(at 22.0345 -146.561556)
		(size 0.508)
		(drill 0.254)
		(layers "F.Cu" "B.Cu")
		(net "MEMDQ_15")
	)
	(via
		(at 42.900092 -148.999956)
		(size 0.4572)
		(drill 0.2032)
		(layers "F.Cu" "B.Cu")
		(net "MEMDQ_15")
	)
	(segment
		(start 23.48992 -150.87346)
		(end 23.65756 -151.0411)
		(width 0.127)
		(layer "In5.Cu")
		(net "MEMDQ_15")
	)
	(segment
		(start 22.0345 -146.80438)
		(end 21.87956 -146.95932)
		(width 0.127)
		(layer "In5.Cu")
		(net "MEMDQ_15")
	)
	(segment
		(start 22.58568 -150.4188)
		(end 22.58568 -149.85492)
		(width 0.127)
		(layer "In5.Cu")
		(net "MEMDQ_15")
	)
	(segment
		(start 21.43252 -149.72792)
		(end 21.69668 -149.72792)
		(width 0.127)
		(layer "In5.Cu")
		(net "MEMDQ_15")
	)
	(segment
		(start 21.82368 -150.4188)
		(end 21.95068 -150.5458)
		(width 0.127)
		(layer "In5.Cu")
		(net "MEMDQ_15")
	)
	(segment
		(start 42.500296 -149.399752)
		(end 42.900092 -148.999956)
		(width 0.127)
		(layer "In5.Cu")
		(net "MEMDQ_15")
	)
	(segment
		(start 21.87956 -146.95932)
		(end 21.87956 -147.53336)
		(width 0.127)
		(layer "In5.Cu")
		(net "MEMDQ_15")
	)
	(segment
		(start 40.064436 -149.399752)
		(end 42.500296 -149.399752)
		(width 0.127)
		(layer "In5.Cu")
		(net "MEMDQ_15")
	)
	(segment
		(start 21.95068 -150.5458)
		(end 22.45868 -150.5458)
		(width 0.127)
		(layer "In5.Cu")
		(net "MEMDQ_15")
	)
	(segment
		(start 22.58568 -149.85492)
		(end 22.71268 -149.72792)
		(width 0.127)
		(layer "In5.Cu")
		(net "MEMDQ_15")
	)
	(segment
		(start 22.0345 -146.561556)
		(end 22.0345 -146.80438)
		(width 0.127)
		(layer "In5.Cu")
		(net "MEMDQ_15")
	)
	(segment
		(start 37.191188 -152.273)
		(end 40.064436 -149.399752)
		(width 0.127)
		(layer "In5.Cu")
		(net "MEMDQ_15")
	)
	(segment
		(start 21.82368 -149.85492)
		(end 21.82368 -150.4188)
		(width 0.127)
		(layer "In5.Cu")
		(net "MEMDQ_15")
	)
	(segment
		(start 21.15058 -149.44598)
		(end 21.43252 -149.72792)
		(width 0.127)
		(layer "In5.Cu")
		(net "MEMDQ_15")
	)
	(segment
		(start 23.30704 -149.72792)
		(end 23.48992 -149.9108)
		(width 0.127)
		(layer "In5.Cu")
		(net "MEMDQ_15")
	)
	(segment
		(start 21.87956 -147.53336)
		(end 21.15058 -148.26234)
		(width 0.127)
		(layer "In5.Cu")
		(net "MEMDQ_15")
	)
	(segment
		(start 21.15058 -148.26234)
		(end 21.15058 -149.44598)
		(width 0.127)
		(layer "In5.Cu")
		(net "MEMDQ_15")
	)
	(segment
		(start 21.69668 -149.72792)
		(end 21.82368 -149.85492)
		(width 0.127)
		(layer "In5.Cu")
		(net "MEMDQ_15")
	)
	(segment
		(start 22.71268 -149.72792)
		(end 23.30704 -149.72792)
		(width 0.127)
		(layer "In5.Cu")
		(net "MEMDQ_15")
	)
	(segment
		(start 28.535376 -152.273)
		(end 37.191188 -152.273)
		(width 0.127)
		(layer "In5.Cu")
		(net "MEMDQ_15")
	)
	(segment
		(start 23.48992 -149.9108)
		(end 23.48992 -150.87346)
		(width 0.127)
		(layer "In5.Cu")
		(net "MEMDQ_15")
	)
	(segment
		(start 22.45868 -150.5458)
		(end 22.58568 -150.4188)
		(width 0.127)
		(layer "In5.Cu")
		(net "MEMDQ_15")
	)
	(segment
		(start 23.65756 -151.0411)
		(end 27.303476 -151.0411)
		(width 0.127)
		(layer "In5.Cu")
		(net "MEMDQ_15")
	)
	(segment
		(start 27.303476 -151.0411)
		(end 28.535376 -152.273)
		(width 0.127)
		(layer "In5.Cu")
		(net "MEMDQ_15")
	)
	(segment
		(start 42.500042 -148.599906)
		(end 42.099992 -148.999956)
		(width 0.127)
		(layer "F.Cu")
		(net "MEMDQ_14")
	)
	(segment
		(start 18.834354 -146.561302)
		(end 18.834608 -146.561302)
		(width 0.127)
		(layer "F.Cu")
		(net "MEMDQ_14")
	)
	(segment
		(start 18.434558 -146.161506)
		(end 18.834354 -146.561302)
		(width 0.127)
		(layer "F.Cu")
		(net "MEMDQ_14")
	)
	(via
		(at 18.834608 -146.561302)
		(size 0.508)
		(drill 0.254)
		(layers "F.Cu" "B.Cu")
		(net "MEMDQ_14")
	)
	(via
		(at 42.099992 -148.999956)
		(size 0.4572)
		(drill 0.2032)
		(layers "F.Cu" "B.Cu")
		(net "MEMDQ_14")
	)
	(segment
		(start 40.64 -148.47316)
		(end 40.773604 -148.606764)
		(width 0.127)
		(layer "In2.Cu")
		(net "MEMDQ_14")
	)
	(segment
		(start 37.99332 -151.3078)
		(end 38.9763 -150.32482)
		(width 0.127)
		(layer "In2.Cu")
		(net "MEMDQ_14")
	)
	(segment
		(start 30.4038 -152.82672)
		(end 36.075112 -152.82672)
		(width 0.127)
		(layer "In2.Cu")
		(net "MEMDQ_14")
	)
	(segment
		(start 38.9763 -150.32482)
		(end 38.9763 -149.098)
		(width 0.127)
		(layer "In2.Cu")
		(net "MEMDQ_14")
	)
	(segment
		(start 36.075112 -152.82672)
		(end 37.594032 -151.3078)
		(width 0.127)
		(layer "In2.Cu")
		(net "MEMDQ_14")
	)
	(segment
		(start 40.773604 -148.606764)
		(end 41.176956 -148.606764)
		(width 0.127)
		(layer "In2.Cu")
		(net "MEMDQ_14")
	)
	(segment
		(start 38.9763 -149.098)
		(end 39.60114 -148.47316)
		(width 0.127)
		(layer "In2.Cu")
		(net "MEMDQ_14")
	)
	(segment
		(start 39.60114 -148.47316)
		(end 40.64 -148.47316)
		(width 0.127)
		(layer "In2.Cu")
		(net "MEMDQ_14")
	)
	(segment
		(start 29.77896 -152.20188)
		(end 30.4038 -152.82672)
		(width 0.127)
		(layer "In2.Cu")
		(net "MEMDQ_14")
	)
	(segment
		(start 19.31416 -147.14982)
		(end 19.31416 -150.441914)
		(width 0.127)
		(layer "In2.Cu")
		(net "MEMDQ_14")
	)
	(segment
		(start 37.594032 -151.3078)
		(end 37.99332 -151.3078)
		(width 0.127)
		(layer "In2.Cu")
		(net "MEMDQ_14")
	)
	(segment
		(start 18.834608 -146.561302)
		(end 18.834608 -146.670268)
		(width 0.127)
		(layer "In2.Cu")
		(net "MEMDQ_14")
	)
	(segment
		(start 18.834608 -146.670268)
		(end 19.31416 -147.14982)
		(width 0.127)
		(layer "In2.Cu")
		(net "MEMDQ_14")
	)
	(segment
		(start 21.074126 -152.20188)
		(end 29.77896 -152.20188)
		(width 0.127)
		(layer "In2.Cu")
		(net "MEMDQ_14")
	)
	(segment
		(start 19.31416 -150.441914)
		(end 21.074126 -152.20188)
		(width 0.127)
		(layer "In2.Cu")
		(net "MEMDQ_14")
	)
	(arc
		(start 41.176956 -148.606764)
		(mid 41.289562 -148.600394)
		(end 41.40073 -148.581364)
		(width 0.127)
		(layer "In2.Cu")
		(net "MEMDQ_14")
	)
	(arc
		(start 41.40073 -148.581364)
		(mid 41.834647 -148.649898)
		(end 42.099992 -148.999956)
		(width 0.127)
		(layer "In2.Cu")
		(net "MEMDQ_14")
	)
	(segment
		(start 41.699942 -148.599906)
		(end 41.299892 -148.999956)
		(width 0.127)
		(layer "F.Cu")
		(net "MEMDQ_13")
	)
	(segment
		(start 22.834346 -146.56181)
		(end 22.834346 -146.561556)
		(width 0.127)
		(layer "F.Cu")
		(net "MEMDQ_13")
	)
	(segment
		(start 22.43455 -146.961606)
		(end 22.834346 -146.56181)
		(width 0.127)
		(layer "F.Cu")
		(net "MEMDQ_13")
	)
	(via
		(at 22.834346 -146.561556)
		(size 0.508)
		(drill 0.254)
		(layers "F.Cu" "B.Cu")
		(net "MEMDQ_13")
	)
	(via
		(at 41.299892 -148.999956)
		(size 0.4572)
		(drill 0.2032)
		(layers "F.Cu" "B.Cu")
		(net "MEMDQ_13")
	)
	(segment
		(start 32.150558 -151.30272)
		(end 32.277558 -151.42972)
		(width 0.127)
		(layer "In5.Cu")
		(net "MEMDQ_13")
	)
	(segment
		(start 33.801558 -151.42972)
		(end 34.309558 -151.42972)
		(width 0.127)
		(layer "In5.Cu")
		(net "MEMDQ_13")
	)
	(segment
		(start 24.4602 -149.15642)
		(end 24.4602 -149.336252)
		(width 0.127)
		(layer "In5.Cu")
		(net "MEMDQ_13")
	)
	(segment
		(start 32.912558 -151.30272)
		(end 32.912558 -150.833582)
		(width 0.127)
		(layer "In5.Cu")
		(net "MEMDQ_13")
	)
	(segment
		(start 28.975558 -150.706582)
		(end 29.102558 -150.833582)
		(width 0.127)
		(layer "In5.Cu")
		(net "MEMDQ_13")
	)
	(segment
		(start 25.17902 -149.87524)
		(end 25.58288 -150.2791)
		(width 0.127)
		(layer "In5.Cu")
		(net "MEMDQ_13")
	)
	(segment
		(start 34.436558 -151.30272)
		(end 34.436558 -150.833582)
		(width 0.127)
		(layer "In5.Cu")
		(net "MEMDQ_13")
	)
	(segment
		(start 30.626558 -151.30272)
		(end 30.753558 -151.42972)
		(width 0.127)
		(layer "In5.Cu")
		(net "MEMDQ_13")
	)
	(segment
		(start 33.674558 -151.30272)
		(end 33.801558 -151.42972)
		(width 0.127)
		(layer "In5.Cu")
		(net "MEMDQ_13")
	)
	(segment
		(start 30.626558 -150.833582)
		(end 30.626558 -151.30272)
		(width 0.127)
		(layer "In5.Cu")
		(net "MEMDQ_13")
	)
	(segment
		(start 31.388558 -150.833582)
		(end 31.515558 -150.706582)
		(width 0.127)
		(layer "In5.Cu")
		(net "MEMDQ_13")
	)
	(segment
		(start 32.785558 -151.42972)
		(end 32.912558 -151.30272)
		(width 0.127)
		(layer "In5.Cu")
		(net "MEMDQ_13")
	)
	(segment
		(start 35.325558 -151.42972)
		(end 37.314378 -151.42972)
		(width 0.127)
		(layer "In5.Cu")
		(net "MEMDQ_13")
	)
	(segment
		(start 34.436558 -150.833582)
		(end 34.563558 -150.706582)
		(width 0.127)
		(layer "In5.Cu")
		(net "MEMDQ_13")
	)
	(segment
		(start 39.306246 -149.437852)
		(end 39.306246 -148.836634)
		(width 0.127)
		(layer "In5.Cu")
		(net "MEMDQ_13")
	)
	(segment
		(start 31.515558 -150.706582)
		(end 32.023558 -150.706582)
		(width 0.127)
		(layer "In5.Cu")
		(net "MEMDQ_13")
	)
	(segment
		(start 29.102558 -151.30272)
		(end 29.229558 -151.42972)
		(width 0.127)
		(layer "In5.Cu")
		(net "MEMDQ_13")
	)
	(segment
		(start 33.039558 -150.706582)
		(end 33.547558 -150.706582)
		(width 0.127)
		(layer "In5.Cu")
		(net "MEMDQ_13")
	)
	(segment
		(start 30.753558 -151.42972)
		(end 31.261558 -151.42972)
		(width 0.127)
		(layer "In5.Cu")
		(net "MEMDQ_13")
	)
	(segment
		(start 40.788336 -148.606256)
		(end 41.182036 -148.999956)
		(width 0.127)
		(layer "In5.Cu")
		(net "MEMDQ_13")
	)
	(segment
		(start 29.864558 -151.30272)
		(end 29.864558 -150.833582)
		(width 0.127)
		(layer "In5.Cu")
		(net "MEMDQ_13")
	)
	(segment
		(start 24.999188 -149.87524)
		(end 25.17902 -149.87524)
		(width 0.127)
		(layer "In5.Cu")
		(net "MEMDQ_13")
	)
	(segment
		(start 29.737558 -151.42972)
		(end 29.864558 -151.30272)
		(width 0.127)
		(layer "In5.Cu")
		(net "MEMDQ_13")
	)
	(segment
		(start 41.182036 -148.999956)
		(end 41.299892 -148.999956)
		(width 0.127)
		(layer "In5.Cu")
		(net "MEMDQ_13")
	)
	(segment
		(start 32.023558 -150.706582)
		(end 32.150558 -150.833582)
		(width 0.127)
		(layer "In5.Cu")
		(net "MEMDQ_13")
	)
	(segment
		(start 30.499558 -150.706582)
		(end 30.626558 -150.833582)
		(width 0.127)
		(layer "In5.Cu")
		(net "MEMDQ_13")
	)
	(segment
		(start 29.991558 -150.706582)
		(end 30.499558 -150.706582)
		(width 0.127)
		(layer "In5.Cu")
		(net "MEMDQ_13")
	)
	(segment
		(start 29.229558 -151.42972)
		(end 29.737558 -151.42972)
		(width 0.127)
		(layer "In5.Cu")
		(net "MEMDQ_13")
	)
	(segment
		(start 22.69744 -148.38172)
		(end 23.00732 -148.6916)
		(width 0.127)
		(layer "In5.Cu")
		(net "MEMDQ_13")
	)
	(segment
		(start 27.619198 -150.2791)
		(end 28.04668 -150.706582)
		(width 0.127)
		(layer "In5.Cu")
		(net "MEMDQ_13")
	)
	(segment
		(start 22.834346 -146.561556)
		(end 22.69744 -146.698462)
		(width 0.127)
		(layer "In5.Cu")
		(net "MEMDQ_13")
	)
	(segment
		(start 29.864558 -150.833582)
		(end 29.991558 -150.706582)
		(width 0.127)
		(layer "In5.Cu")
		(net "MEMDQ_13")
	)
	(segment
		(start 34.309558 -151.42972)
		(end 34.436558 -151.30272)
		(width 0.127)
		(layer "In5.Cu")
		(net "MEMDQ_13")
	)
	(segment
		(start 24.4602 -149.336252)
		(end 24.079962 -149.71649)
		(width 0.127)
		(layer "In5.Cu")
		(net "MEMDQ_13")
	)
	(segment
		(start 24.079962 -149.71649)
		(end 24.079962 -149.935692)
		(width 0.127)
		(layer "In5.Cu")
		(net "MEMDQ_13")
	)
	(segment
		(start 39.536624 -148.606256)
		(end 40.788336 -148.606256)
		(width 0.127)
		(layer "In5.Cu")
		(net "MEMDQ_13")
	)
	(segment
		(start 22.69744 -146.698462)
		(end 22.69744 -148.38172)
		(width 0.127)
		(layer "In5.Cu")
		(net "MEMDQ_13")
	)
	(segment
		(start 25.58288 -150.2791)
		(end 27.619198 -150.2791)
		(width 0.127)
		(layer "In5.Cu")
		(net "MEMDQ_13")
	)
	(segment
		(start 35.071558 -150.706582)
		(end 35.198558 -150.833582)
		(width 0.127)
		(layer "In5.Cu")
		(net "MEMDQ_13")
	)
	(segment
		(start 32.150558 -150.833582)
		(end 32.150558 -151.30272)
		(width 0.127)
		(layer "In5.Cu")
		(net "MEMDQ_13")
	)
	(segment
		(start 39.306246 -148.836634)
		(end 39.536624 -148.606256)
		(width 0.127)
		(layer "In5.Cu")
		(net "MEMDQ_13")
	)
	(segment
		(start 31.388558 -151.30272)
		(end 31.388558 -150.833582)
		(width 0.127)
		(layer "In5.Cu")
		(net "MEMDQ_13")
	)
	(segment
		(start 23.99538 -148.6916)
		(end 24.4602 -149.15642)
		(width 0.127)
		(layer "In5.Cu")
		(net "MEMDQ_13")
	)
	(segment
		(start 23.00732 -148.6916)
		(end 23.99538 -148.6916)
		(width 0.127)
		(layer "In5.Cu")
		(net "MEMDQ_13")
	)
	(segment
		(start 35.198558 -150.833582)
		(end 35.198558 -151.30272)
		(width 0.127)
		(layer "In5.Cu")
		(net "MEMDQ_13")
	)
	(segment
		(start 33.674558 -150.833582)
		(end 33.674558 -151.30272)
		(width 0.127)
		(layer "In5.Cu")
		(net "MEMDQ_13")
	)
	(segment
		(start 37.314378 -151.42972)
		(end 39.306246 -149.437852)
		(width 0.127)
		(layer "In5.Cu")
		(net "MEMDQ_13")
	)
	(segment
		(start 32.277558 -151.42972)
		(end 32.785558 -151.42972)
		(width 0.127)
		(layer "In5.Cu")
		(net "MEMDQ_13")
	)
	(segment
		(start 33.547558 -150.706582)
		(end 33.674558 -150.833582)
		(width 0.127)
		(layer "In5.Cu")
		(net "MEMDQ_13")
	)
	(segment
		(start 28.04668 -150.706582)
		(end 28.975558 -150.706582)
		(width 0.127)
		(layer "In5.Cu")
		(net "MEMDQ_13")
	)
	(segment
		(start 34.563558 -150.706582)
		(end 35.071558 -150.706582)
		(width 0.127)
		(layer "In5.Cu")
		(net "MEMDQ_13")
	)
	(segment
		(start 35.198558 -151.30272)
		(end 35.325558 -151.42972)
		(width 0.127)
		(layer "In5.Cu")
		(net "MEMDQ_13")
	)
	(segment
		(start 31.261558 -151.42972)
		(end 31.388558 -151.30272)
		(width 0.127)
		(layer "In5.Cu")
		(net "MEMDQ_13")
	)
	(segment
		(start 24.079962 -149.935692)
		(end 24.386286 -150.242016)
		(width 0.127)
		(layer "In5.Cu")
		(net "MEMDQ_13")
	)
	(segment
		(start 32.912558 -150.833582)
		(end 33.039558 -150.706582)
		(width 0.127)
		(layer "In5.Cu")
		(net "MEMDQ_13")
	)
	(segment
		(start 24.632412 -150.242016)
		(end 24.999188 -149.87524)
		(width 0.127)
		(layer "In5.Cu")
		(net "MEMDQ_13")
	)
	(segment
		(start 24.386286 -150.242016)
		(end 24.632412 -150.242016)
		(width 0.127)
		(layer "In5.Cu")
		(net "MEMDQ_13")
	)
	(segment
		(start 29.102558 -150.833582)
		(end 29.102558 -151.30272)
		(width 0.127)
		(layer "In5.Cu")
		(net "MEMDQ_13")
	)
	(segment
		(start 25.61844 -150.85568)
		(end 28.150312 -150.85568)
		(width 0.127)
		(layer "F.Cu")
		(net "MEMDQ_12")
	)
	(segment
		(start 38.7985 -150.1521)
		(end 39.1414 -149.8092)
		(width 0.127)
		(layer "F.Cu")
		(net "MEMDQ_12")
	)
	(segment
		(start 17.634458 -146.961606)
		(end 17.634458 -147.276312)
		(width 0.127)
		(layer "F.Cu")
		(net "MEMDQ_12")
	)
	(segment
		(start 18.87728 -150.130764)
		(end 18.87728 -150.638764)
		(width 0.127)
		(layer "F.Cu")
		(net "MEMDQ_12")
	)
	(segment
		(start 18.87728 -150.638764)
		(end 18.75028 -150.765764)
		(width 0.127)
		(layer "F.Cu")
		(net "MEMDQ_12")
	)
	(segment
		(start 36.529264 -150.5585)
		(end 37.018722 -150.5585)
		(width 0.127)
		(layer "F.Cu")
		(net "MEMDQ_12")
	)
	(segment
		(start 17.634458 -147.276312)
		(end 17.977358 -147.619212)
		(width 0.127)
		(layer "F.Cu")
		(net "MEMDQ_12")
	)
	(segment
		(start 18.104358 -150.765764)
		(end 17.977358 -150.892764)
		(width 0.127)
		(layer "F.Cu")
		(net "MEMDQ_12")
	)
	(segment
		(start 28.150312 -150.85568)
		(end 28.78582 -150.220172)
		(width 0.127)
		(layer "F.Cu")
		(net "MEMDQ_12")
	)
	(segment
		(start 23.77948 -152.69464)
		(end 25.61844 -150.85568)
		(width 0.127)
		(layer "F.Cu")
		(net "MEMDQ_12")
	)
	(segment
		(start 37.018722 -150.5585)
		(end 37.425122 -150.1521)
		(width 0.127)
		(layer "F.Cu")
		(net "MEMDQ_12")
	)
	(segment
		(start 39.690802 -149.8092)
		(end 40.099996 -149.400006)
		(width 0.127)
		(layer "F.Cu")
		(net "MEMDQ_12")
	)
	(segment
		(start 17.977358 -151.586438)
		(end 19.61388 -153.22296)
		(width 0.127)
		(layer "F.Cu")
		(net "MEMDQ_12")
	)
	(segment
		(start 18.75028 -150.003764)
		(end 18.87728 -150.130764)
		(width 0.127)
		(layer "F.Cu")
		(net "MEMDQ_12")
	)
	(segment
		(start 28.78582 -150.220172)
		(end 36.190936 -150.220172)
		(width 0.127)
		(layer "F.Cu")
		(net "MEMDQ_12")
	)
	(segment
		(start 18.104358 -150.003764)
		(end 18.75028 -150.003764)
		(width 0.127)
		(layer "F.Cu")
		(net "MEMDQ_12")
	)
	(segment
		(start 37.425122 -150.1521)
		(end 38.7985 -150.1521)
		(width 0.127)
		(layer "F.Cu")
		(net "MEMDQ_12")
	)
	(segment
		(start 17.977358 -149.876764)
		(end 18.104358 -150.003764)
		(width 0.127)
		(layer "F.Cu")
		(net "MEMDQ_12")
	)
	(segment
		(start 20.57654 -153.22296)
		(end 21.10486 -152.69464)
		(width 0.127)
		(layer "F.Cu")
		(net "MEMDQ_12")
	)
	(segment
		(start 19.61388 -153.22296)
		(end 20.57654 -153.22296)
		(width 0.127)
		(layer "F.Cu")
		(net "MEMDQ_12")
	)
	(segment
		(start 39.1414 -149.8092)
		(end 39.690802 -149.8092)
		(width 0.127)
		(layer "F.Cu")
		(net "MEMDQ_12")
	)
	(segment
		(start 18.75028 -150.765764)
		(end 18.104358 -150.765764)
		(width 0.127)
		(layer "F.Cu")
		(net "MEMDQ_12")
	)
	(segment
		(start 36.190936 -150.220172)
		(end 36.529264 -150.5585)
		(width 0.127)
		(layer "F.Cu")
		(net "MEMDQ_12")
	)
	(segment
		(start 21.10486 -152.69464)
		(end 23.77948 -152.69464)
		(width 0.127)
		(layer "F.Cu")
		(net "MEMDQ_12")
	)
	(segment
		(start 17.977358 -150.892764)
		(end 17.977358 -151.586438)
		(width 0.127)
		(layer "F.Cu")
		(net "MEMDQ_12")
	)
	(segment
		(start 17.977358 -147.619212)
		(end 17.977358 -149.876764)
		(width 0.127)
		(layer "F.Cu")
		(net "MEMDQ_12")
	)
	(segment
		(start 21.63445 -146.96186)
		(end 21.234654 -147.361656)
		(width 0.127)
		(layer "F.Cu")
		(net "MEMDQ_11")
	)
	(segment
		(start 21.63445 -146.961606)
		(end 21.63445 -146.96186)
		(width 0.127)
		(layer "F.Cu")
		(net "MEMDQ_11")
	)
	(segment
		(start 41.699942 -147.80006)
		(end 41.299892 -147.40001)
		(width 0.127)
		(layer "F.Cu")
		(net "MEMDQ_11")
	)
	(via
		(at 41.299892 -147.40001)
		(size 0.4572)
		(drill 0.2032)
		(layers "F.Cu" "B.Cu")
		(net "MEMDQ_11")
	)
	(via
		(at 21.234654 -147.361656)
		(size 0.508)
		(drill 0.254)
		(layers "F.Cu" "B.Cu")
		(net "MEMDQ_11")
	)
	(segment
		(start 33.833308 -149.58314)
		(end 33.960308 -149.45614)
		(width 0.127)
		(layer "In2.Cu")
		(net "MEMDQ_11")
	)
	(segment
		(start 33.960308 -148.6916)
		(end 34.087308 -148.5646)
		(width 0.127)
		(layer "In2.Cu")
		(net "MEMDQ_11")
	)
	(segment
		(start 34.486596 -148.5646)
		(end 35.279584 -147.771612)
		(width 0.127)
		(layer "In2.Cu")
		(net "MEMDQ_11")
	)
	(segment
		(start 35.829748 -147.620736)
		(end 37.194236 -147.620736)
		(width 0.127)
		(layer "In2.Cu")
		(net "MEMDQ_11")
	)
	(segment
		(start 38.2524 -147.9296)
		(end 38.464236 -147.717764)
		(width 0.127)
		(layer "In2.Cu")
		(net "MEMDQ_11")
	)
	(segment
		(start 20.252944 -146.79168)
		(end 20.049744 -146.99488)
		(width 0.127)
		(layer "In2.Cu")
		(net "MEMDQ_11")
	)
	(segment
		(start 34.087308 -148.5646)
		(end 34.486596 -148.5646)
		(width 0.127)
		(layer "In2.Cu")
		(net "MEMDQ_11")
	)
	(segment
		(start 21.914866 -147.647914)
		(end 22.321012 -147.647914)
		(width 0.127)
		(layer "In2.Cu")
		(net "MEMDQ_11")
	)
	(segment
		(start 37.194236 -147.620736)
		(end 37.5031 -147.9296)
		(width 0.127)
		(layer "In2.Cu")
		(net "MEMDQ_11")
	)
	(segment
		(start 20.049744 -146.99488)
		(end 20.049744 -149.121114)
		(width 0.127)
		(layer "In2.Cu")
		(net "MEMDQ_11")
	)
	(segment
		(start 26.416 -148.5646)
		(end 33.071308 -148.5646)
		(width 0.127)
		(layer "In2.Cu")
		(net "MEMDQ_11")
	)
	(segment
		(start 21.087334 -149.121114)
		(end 21.087334 -148.475446)
		(width 0.127)
		(layer "In2.Cu")
		(net "MEMDQ_11")
	)
	(segment
		(start 20.049744 -149.121114)
		(end 20.252944 -149.324314)
		(width 0.127)
		(layer "In2.Cu")
		(net "MEMDQ_11")
	)
	(segment
		(start 33.960308 -149.45614)
		(end 33.960308 -148.6916)
		(width 0.127)
		(layer "In2.Cu")
		(net "MEMDQ_11")
	)
	(segment
		(start 33.198308 -149.45614)
		(end 33.325308 -149.58314)
		(width 0.127)
		(layer "In2.Cu")
		(net "MEMDQ_11")
	)
	(segment
		(start 33.325308 -149.58314)
		(end 33.833308 -149.58314)
		(width 0.127)
		(layer "In2.Cu")
		(net "MEMDQ_11")
	)
	(segment
		(start 38.464236 -147.717764)
		(end 39.41953 -147.717764)
		(width 0.127)
		(layer "In2.Cu")
		(net "MEMDQ_11")
	)
	(segment
		(start 24.499824 -147.153376)
		(end 25.004776 -147.153376)
		(width 0.127)
		(layer "In2.Cu")
		(net "MEMDQ_11")
	)
	(segment
		(start 21.234654 -146.99488)
		(end 21.031454 -146.79168)
		(width 0.127)
		(layer "In2.Cu")
		(net "MEMDQ_11")
	)
	(segment
		(start 35.279584 -147.771612)
		(end 35.678872 -147.771612)
		(width 0.127)
		(layer "In2.Cu")
		(net "MEMDQ_11")
	)
	(segment
		(start 39.664894 -147.819364)
		(end 40.68953 -147.819364)
		(width 0.127)
		(layer "In2.Cu")
		(net "MEMDQ_11")
	)
	(segment
		(start 21.087334 -148.475446)
		(end 21.914866 -147.647914)
		(width 0.127)
		(layer "In2.Cu")
		(net "MEMDQ_11")
	)
	(segment
		(start 20.252944 -149.324314)
		(end 20.884134 -149.324314)
		(width 0.127)
		(layer "In2.Cu")
		(net "MEMDQ_11")
	)
	(segment
		(start 22.453854 -147.780756)
		(end 23.872444 -147.780756)
		(width 0.127)
		(layer "In2.Cu")
		(net "MEMDQ_11")
	)
	(segment
		(start 35.678872 -147.771612)
		(end 35.829748 -147.620736)
		(width 0.127)
		(layer "In2.Cu")
		(net "MEMDQ_11")
	)
	(segment
		(start 22.321012 -147.647914)
		(end 22.453854 -147.780756)
		(width 0.127)
		(layer "In2.Cu")
		(net "MEMDQ_11")
	)
	(segment
		(start 33.071308 -148.5646)
		(end 33.198308 -148.6916)
		(width 0.127)
		(layer "In2.Cu")
		(net "MEMDQ_11")
	)
	(segment
		(start 33.198308 -148.6916)
		(end 33.198308 -149.45614)
		(width 0.127)
		(layer "In2.Cu")
		(net "MEMDQ_11")
	)
	(segment
		(start 20.884134 -149.324314)
		(end 21.087334 -149.121114)
		(width 0.127)
		(layer "In2.Cu")
		(net "MEMDQ_11")
	)
	(segment
		(start 21.031454 -146.79168)
		(end 20.252944 -146.79168)
		(width 0.127)
		(layer "In2.Cu")
		(net "MEMDQ_11")
	)
	(segment
		(start 23.872444 -147.780756)
		(end 24.499824 -147.153376)
		(width 0.127)
		(layer "In2.Cu")
		(net "MEMDQ_11")
	)
	(segment
		(start 41.015412 -147.684236)
		(end 41.299892 -147.40001)
		(width 0.127)
		(layer "In2.Cu")
		(net "MEMDQ_11")
	)
	(segment
		(start 37.5031 -147.9296)
		(end 38.2524 -147.9296)
		(width 0.127)
		(layer "In2.Cu")
		(net "MEMDQ_11")
	)
	(segment
		(start 25.004776 -147.153376)
		(end 26.416 -148.5646)
		(width 0.127)
		(layer "In2.Cu")
		(net "MEMDQ_11")
	)
	(segment
		(start 21.234654 -147.361656)
		(end 21.234654 -146.99488)
		(width 0.127)
		(layer "In2.Cu")
		(net "MEMDQ_11")
	)
	(arc
		(start 40.68953 -147.819364)
		(mid 40.865897 -147.784189)
		(end 41.015412 -147.684236)
		(width 0.127)
		(layer "In2.Cu")
		(net "MEMDQ_11")
	)
	(arc
		(start 39.41953 -147.717764)
		(mid 39.532104 -147.792984)
		(end 39.664894 -147.819364)
		(width 0.127)
		(layer "In2.Cu")
		(net "MEMDQ_11")
	)
	(segment
		(start 40.899842 -148.60016)
		(end 40.899842 -148.599906)
		(width 0.127)
		(layer "F.Cu")
		(net "MEMDQ_10")
	)
	(segment
		(start 18.434812 -146.961606)
		(end 18.834608 -147.361402)
		(width 0.127)
		(layer "F.Cu")
		(net "MEMDQ_10")
	)
	(segment
		(start 18.434558 -146.961606)
		(end 18.434812 -146.961606)
		(width 0.127)
		(layer "F.Cu")
		(net "MEMDQ_10")
	)
	(segment
		(start 40.500046 -148.999956)
		(end 40.899842 -148.60016)
		(width 0.127)
		(layer "F.Cu")
		(net "MEMDQ_10")
	)
	(via
		(at 40.500046 -148.999956)
		(size 0.4572)
		(drill 0.2032)
		(layers "F.Cu" "B.Cu")
		(net "MEMDQ_10")
	)
	(via
		(at 18.834608 -147.361402)
		(size 0.508)
		(drill 0.254)
		(layers "F.Cu" "B.Cu")
		(net "MEMDQ_10")
	)
	(segment
		(start 40.02786 -149.8219)
		(end 38.88994 -150.95982)
		(width 0.127)
		(layer "In2.Cu")
		(net "MEMDQ_10")
	)
	(segment
		(start 38.88994 -150.95982)
		(end 38.88994 -151.43988)
		(width 0.127)
		(layer "In2.Cu")
		(net "MEMDQ_10")
	)
	(segment
		(start 17.96288 -151.396192)
		(end 17.96288 -148.06676)
		(width 0.127)
		(layer "In2.Cu")
		(net "MEMDQ_10")
	)
	(segment
		(start 37.953696 -152.13584)
		(end 36.477956 -153.61158)
		(width 0.127)
		(layer "In2.Cu")
		(net "MEMDQ_10")
	)
	(segment
		(start 17.96288 -148.06676)
		(end 18.668238 -147.361402)
		(width 0.127)
		(layer "In2.Cu")
		(net "MEMDQ_10")
	)
	(segment
		(start 38.88994 -151.43988)
		(end 38.19398 -152.13584)
		(width 0.127)
		(layer "In2.Cu")
		(net "MEMDQ_10")
	)
	(segment
		(start 18.668238 -147.361402)
		(end 18.834608 -147.361402)
		(width 0.127)
		(layer "In2.Cu")
		(net "MEMDQ_10")
	)
	(segment
		(start 19.766788 -153.2001)
		(end 17.96288 -151.396192)
		(width 0.127)
		(layer "In2.Cu")
		(net "MEMDQ_10")
	)
	(segment
		(start 38.19398 -152.13584)
		(end 37.953696 -152.13584)
		(width 0.127)
		(layer "In2.Cu")
		(net "MEMDQ_10")
	)
	(segment
		(start 40.500046 -148.999956)
		(end 40.02786 -149.472142)
		(width 0.127)
		(layer "In2.Cu")
		(net "MEMDQ_10")
	)
	(segment
		(start 36.477956 -153.61158)
		(end 29.72943 -153.61158)
		(width 0.127)
		(layer "In2.Cu")
		(net "MEMDQ_10")
	)
	(segment
		(start 29.72943 -153.61158)
		(end 29.31795 -153.2001)
		(width 0.127)
		(layer "In2.Cu")
		(net "MEMDQ_10")
	)
	(segment
		(start 40.02786 -149.472142)
		(end 40.02786 -149.8219)
		(width 0.127)
		(layer "In2.Cu")
		(net "MEMDQ_10")
	)
	(segment
		(start 29.31795 -153.2001)
		(end 19.766788 -153.2001)
		(width 0.127)
		(layer "In2.Cu")
		(net "MEMDQ_10")
	)
	(segment
		(start 21.8313 -145.01876)
		(end 23.45182 -145.01876)
		(width 0.127)
		(layer "F.Cu")
		(net "MEMDQ_1")
	)
	(segment
		(start 41.53789 -146.038062)
		(end 41.699942 -146.19986)
		(width 0.127)
		(layer "F.Cu")
		(net "MEMDQ_1")
	)
	(segment
		(start 24.4348 -146.43862)
		(end 24.3078 -146.56562)
		(width 0.127)
		(layer "F.Cu")
		(net "MEMDQ_1")
	)
	(segment
		(start 34.552128 -147.934172)
		(end 34.907728 -147.578572)
		(width 0.127)
		(layer "F.Cu")
		(net "MEMDQ_1")
	)
	(segment
		(start 24.3078 -146.56562)
		(end 24.3078 -147.08124)
		(width 0.127)
		(layer "F.Cu")
		(net "MEMDQ_1")
	)
	(segment
		(start 25.3365 -147.52066)
		(end 25.3365 -148.47316)
		(width 0.127)
		(layer "F.Cu")
		(net "MEMDQ_1")
	)
	(segment
		(start 24.39924 -144.96034)
		(end 24.39924 -145.43786)
		(width 0.127)
		(layer "F.Cu")
		(net "MEMDQ_1")
	)
	(segment
		(start 26.133298 -146.324828)
		(end 26.133044 -146.325082)
		(width 0.127)
		(layer "F.Cu")
		(net "MEMDQ_1")
	)
	(segment
		(start 26.01976 -146.43862)
		(end 24.4348 -146.43862)
		(width 0.127)
		(layer "F.Cu")
		(net "MEMDQ_1")
	)
	(segment
		(start 27.08529 -147.56765)
		(end 27.08529 -147.807172)
		(width 0.127)
		(layer "F.Cu")
		(net "MEMDQ_1")
	)
	(segment
		(start 21.63445 -144.56156)
		(end 21.63445 -144.82191)
		(width 0.127)
		(layer "F.Cu")
		(net "MEMDQ_1")
	)
	(segment
		(start 25.43302 -148.56968)
		(end 26.22677 -148.56968)
		(width 0.127)
		(layer "F.Cu")
		(net "MEMDQ_1")
	)
	(segment
		(start 26.006298 -145.639282)
		(end 26.133298 -145.766282)
		(width 0.127)
		(layer "F.Cu")
		(net "MEMDQ_1")
	)
	(segment
		(start 23.63724 -144.83334)
		(end 24.27224 -144.83334)
		(width 0.127)
		(layer "F.Cu")
		(net "MEMDQ_1")
	)
	(segment
		(start 21.63445 -144.82191)
		(end 21.8313 -145.01876)
		(width 0.127)
		(layer "F.Cu")
		(net "MEMDQ_1")
	)
	(segment
		(start 37.605208 -145.55216)
		(end 38.66134 -145.55216)
		(width 0.127)
		(layer "F.Cu")
		(net "MEMDQ_1")
	)
	(segment
		(start 37.07892 -146.078448)
		(end 37.605208 -145.55216)
		(width 0.127)
		(layer "F.Cu")
		(net "MEMDQ_1")
	)
	(segment
		(start 25.3365 -148.47316)
		(end 25.43302 -148.56968)
		(width 0.127)
		(layer "F.Cu")
		(net "MEMDQ_1")
	)
	(segment
		(start 26.32329 -148.47316)
		(end 26.32329 -147.59432)
		(width 0.127)
		(layer "F.Cu")
		(net "MEMDQ_1")
	)
	(segment
		(start 26.133298 -145.766282)
		(end 26.133298 -146.324828)
		(width 0.127)
		(layer "F.Cu")
		(net "MEMDQ_1")
	)
	(segment
		(start 23.45182 -145.01876)
		(end 23.63724 -144.83334)
		(width 0.127)
		(layer "F.Cu")
		(net "MEMDQ_1")
	)
	(segment
		(start 26.463752 -147.453858)
		(end 26.971498 -147.453858)
		(width 0.127)
		(layer "F.Cu")
		(net "MEMDQ_1")
	)
	(segment
		(start 37.07892 -146.32432)
		(end 37.07892 -146.078448)
		(width 0.127)
		(layer "F.Cu")
		(net "MEMDQ_1")
	)
	(segment
		(start 24.47036 -147.2438)
		(end 25.05964 -147.2438)
		(width 0.127)
		(layer "F.Cu")
		(net "MEMDQ_1")
	)
	(segment
		(start 37.143944 -146.97202)
		(end 37.270944 -146.84502)
		(width 0.127)
		(layer "F.Cu")
		(net "MEMDQ_1")
	)
	(segment
		(start 38.66134 -145.55216)
		(end 38.921944 -145.812764)
		(width 0.127)
		(layer "F.Cu")
		(net "MEMDQ_1")
	)
	(segment
		(start 25.05964 -147.2438)
		(end 25.3365 -147.52066)
		(width 0.127)
		(layer "F.Cu")
		(net "MEMDQ_1")
	)
	(segment
		(start 27.21229 -147.934172)
		(end 34.552128 -147.934172)
		(width 0.127)
		(layer "F.Cu")
		(net "MEMDQ_1")
	)
	(segment
		(start 24.3078 -147.08124)
		(end 24.47036 -147.2438)
		(width 0.127)
		(layer "F.Cu")
		(net "MEMDQ_1")
	)
	(segment
		(start 27.08529 -147.807172)
		(end 27.21229 -147.934172)
		(width 0.127)
		(layer "F.Cu")
		(net "MEMDQ_1")
	)
	(segment
		(start 24.600662 -145.639282)
		(end 26.006298 -145.639282)
		(width 0.127)
		(layer "F.Cu")
		(net "MEMDQ_1")
	)
	(segment
		(start 26.971498 -147.453858)
		(end 27.08529 -147.56765)
		(width 0.127)
		(layer "F.Cu")
		(net "MEMDQ_1")
	)
	(segment
		(start 35.034728 -146.97202)
		(end 37.143944 -146.97202)
		(width 0.127)
		(layer "F.Cu")
		(net "MEMDQ_1")
	)
	(segment
		(start 37.270944 -146.84502)
		(end 37.270944 -146.516344)
		(width 0.127)
		(layer "F.Cu")
		(net "MEMDQ_1")
	)
	(segment
		(start 38.921944 -145.812764)
		(end 40.99433 -145.812764)
		(width 0.127)
		(layer "F.Cu")
		(net "MEMDQ_1")
	)
	(segment
		(start 26.32329 -147.59432)
		(end 26.463752 -147.453858)
		(width 0.127)
		(layer "F.Cu")
		(net "MEMDQ_1")
	)
	(segment
		(start 26.22677 -148.56968)
		(end 26.32329 -148.47316)
		(width 0.127)
		(layer "F.Cu")
		(net "MEMDQ_1")
	)
	(segment
		(start 24.27224 -144.83334)
		(end 24.39924 -144.96034)
		(width 0.127)
		(layer "F.Cu")
		(net "MEMDQ_1")
	)
	(segment
		(start 34.907728 -147.09902)
		(end 35.034728 -146.97202)
		(width 0.127)
		(layer "F.Cu")
		(net "MEMDQ_1")
	)
	(segment
		(start 26.133044 -146.325082)
		(end 26.01976 -146.43862)
		(width 0.127)
		(layer "F.Cu")
		(net "MEMDQ_1")
	)
	(segment
		(start 24.39924 -145.43786)
		(end 24.600662 -145.639282)
		(width 0.127)
		(layer "F.Cu")
		(net "MEMDQ_1")
	)
	(segment
		(start 37.270944 -146.516344)
		(end 37.07892 -146.32432)
		(width 0.127)
		(layer "F.Cu")
		(net "MEMDQ_1")
	)
	(segment
		(start 34.907728 -147.578572)
		(end 34.907728 -147.09902)
		(width 0.127)
		(layer "F.Cu")
		(net "MEMDQ_1")
	)
	(arc
		(start 40.99433 -145.812764)
		(mid 41.288531 -145.87132)
		(end 41.53789 -146.038062)
		(width 0.127)
		(layer "F.Cu")
		(net "MEMDQ_1")
	)
	(segment
		(start 18.034508 -143.361664)
		(end 18.034508 -143.356584)
		(width 0.127)
		(layer "F.Cu")
		(net "MEMDQ_0")
	)
	(segment
		(start 17.634712 -143.76146)
		(end 18.034508 -143.361664)
		(width 0.127)
		(layer "F.Cu")
		(net "MEMDQ_0")
	)
	(segment
		(start 42.900092 -146.59991)
		(end 43.299888 -146.200114)
		(width 0.127)
		(layer "F.Cu")
		(net "MEMDQ_0")
	)
	(segment
		(start 17.634458 -143.76146)
		(end 17.634712 -143.76146)
		(width 0.127)
		(layer "F.Cu")
		(net "MEMDQ_0")
	)
	(segment
		(start 43.299888 -146.200114)
		(end 43.299888 -146.19986)
		(width 0.127)
		(layer "F.Cu")
		(net "MEMDQ_0")
	)
	(via
		(at 42.900092 -146.59991)
		(size 0.4572)
		(drill 0.2032)
		(layers "F.Cu" "B.Cu")
		(net "MEMDQ_0")
	)
	(via
		(at 18.034508 -143.356584)
		(size 0.508)
		(drill 0.254)
		(layers "F.Cu" "B.Cu")
		(net "MEMDQ_0")
	)
	(segment
		(start 25.041098 -145.984976)
		(end 25.041098 -145.928588)
		(width 0.127)
		(layer "In5.Cu")
		(net "MEMDQ_0")
	)
	(segment
		(start 43.08856 -146.411442)
		(end 43.08856 -146.07032)
		(width 0.127)
		(layer "In5.Cu")
		(net "MEMDQ_0")
	)
	(segment
		(start 28.837128 -148.263864)
		(end 28.566364 -147.9931)
		(width 0.127)
		(layer "In5.Cu")
		(net "MEMDQ_0")
	)
	(segment
		(start 39.536624 -146.99361)
		(end 38.832028 -147.698206)
		(width 0.127)
		(layer "In5.Cu")
		(net "MEMDQ_0")
	)
	(segment
		(start 42.90568 -145.88744)
		(end 42.5958 -145.88744)
		(width 0.127)
		(layer "In5.Cu")
		(net "MEMDQ_0")
	)
	(segment
		(start 38.832028 -147.698206)
		(end 37.160454 -147.698206)
		(width 0.127)
		(layer "In5.Cu")
		(net "MEMDQ_0")
	)
	(segment
		(start 35.887406 -147.446492)
		(end 35.070034 -148.263864)
		(width 0.127)
		(layer "In5.Cu")
		(net "MEMDQ_0")
	)
	(segment
		(start 25.041098 -145.928588)
		(end 23.92172 -144.80921)
		(width 0.127)
		(layer "In5.Cu")
		(net "MEMDQ_0")
	)
	(segment
		(start 19.456146 -144.80921)
		(end 19.350736 -144.7038)
		(width 0.127)
		(layer "In5.Cu")
		(net "MEMDQ_0")
	)
	(segment
		(start 18.034508 -143.513048)
		(end 18.034508 -143.356584)
		(width 0.0889)
		(layer "In5.Cu")
		(net "MEMDQ_0")
	)
	(segment
		(start 35.070034 -148.263864)
		(end 28.837128 -148.263864)
		(width 0.127)
		(layer "In5.Cu")
		(net "MEMDQ_0")
	)
	(segment
		(start 27.049222 -147.9931)
		(end 25.041098 -145.984976)
		(width 0.127)
		(layer "In5.Cu")
		(net "MEMDQ_0")
	)
	(segment
		(start 23.92172 -144.80921)
		(end 19.456146 -144.80921)
		(width 0.127)
		(layer "In5.Cu")
		(net "MEMDQ_0")
	)
	(segment
		(start 37.160454 -147.698206)
		(end 36.90874 -147.446492)
		(width 0.127)
		(layer "In5.Cu")
		(net "MEMDQ_0")
	)
	(segment
		(start 18.434558 -144.334992)
		(end 18.434558 -143.913098)
		(width 0.0889)
		(layer "In5.Cu")
		(net "MEMDQ_0")
	)
	(segment
		(start 18.434558 -143.913098)
		(end 18.034508 -143.513048)
		(width 0.0889)
		(layer "In5.Cu")
		(net "MEMDQ_0")
	)
	(segment
		(start 42.0624 -146.705574)
		(end 41.774364 -146.99361)
		(width 0.127)
		(layer "In5.Cu")
		(net "MEMDQ_0")
	)
	(segment
		(start 42.5958 -145.88744)
		(end 42.0624 -146.42084)
		(width 0.127)
		(layer "In5.Cu")
		(net "MEMDQ_0")
	)
	(segment
		(start 42.900092 -146.59991)
		(end 43.08856 -146.411442)
		(width 0.127)
		(layer "In5.Cu")
		(net "MEMDQ_0")
	)
	(segment
		(start 18.784316 -144.68475)
		(end 18.434558 -144.334992)
		(width 0.0889)
		(layer "In5.Cu")
		(net "MEMDQ_0")
	)
	(segment
		(start 42.0624 -146.42084)
		(end 42.0624 -146.705574)
		(width 0.127)
		(layer "In5.Cu")
		(net "MEMDQ_0")
	)
	(segment
		(start 36.90874 -147.446492)
		(end 35.887406 -147.446492)
		(width 0.127)
		(layer "In5.Cu")
		(net "MEMDQ_0")
	)
	(segment
		(start 41.774364 -146.99361)
		(end 39.536624 -146.99361)
		(width 0.127)
		(layer "In5.Cu")
		(net "MEMDQ_0")
	)
	(segment
		(start 18.803366 -144.7038)
		(end 18.784316 -144.68475)
		(width 0.127)
		(layer "In5.Cu")
		(net "MEMDQ_0")
	)
	(segment
		(start 28.566364 -147.9931)
		(end 27.049222 -147.9931)
		(width 0.127)
		(layer "In5.Cu")
		(net "MEMDQ_0")
	)
	(segment
		(start 43.08856 -146.07032)
		(end 42.90568 -145.88744)
		(width 0.127)
		(layer "In5.Cu")
		(net "MEMDQ_0")
	)
	(segment
		(start 19.350736 -144.7038)
		(end 18.803366 -144.7038)
		(width 0.127)
		(layer "In5.Cu")
		(net "MEMDQ_0")
	)
	(segment
		(start 38.7096 -148.771356)
		(end 38.955472 -148.771356)
		(width 0.12446)
		(layer "F.Cu")
		(net "MEMDQS_P1")
	)
	(segment
		(start 37.913056 -149.217888)
		(end 38.1127 -149.018244)
		(width 0.12446)
		(layer "F.Cu")
		(net "MEMDQS_P1")
	)
	(segment
		(start 37.267896 -149.3774)
		(end 37.5285 -149.3774)
		(width 0.12446)
		(layer "F.Cu")
		(net "MEMDQS_P1")
	)
	(segment
		(start 39.25062 -148.648928)
		(end 39.299896 -148.599906)
		(width 0.12446)
		(layer "F.Cu")
		(net "MEMDQS_P1")
	)
	(segment
		(start 36.798504 -149.141942)
		(end 36.868608 -149.212046)
		(width 0.12446)
		(layer "F.Cu")
		(net "MEMDQS_P1")
	)
	(segment
		(start 38.1127 -149.018244)
		(end 38.1127 -149.018498)
		(width 0.12446)
		(layer "F.Cu")
		(net "MEMDQS_P1")
	)
	(segment
		(start 22.0345 -148.161502)
		(end 21.63445 -147.761452)
		(width 0.12446)
		(layer "F.Cu")
		(net "MEMDQS_P1")
	)
	(via
		(at 36.798504 -149.141942)
		(size 0.508)
		(drill 0.254)
		(layers "F.Cu" "B.Cu")
		(net "MEMDQS_P1")
	)
	(via
		(at 22.0345 -148.161502)
		(size 0.508)
		(drill 0.254)
		(layers "F.Cu" "B.Cu")
		(net "MEMDQS_P1")
	)
	(arc
		(start 36.868608 -149.212046)
		(mid 37.051803 -149.334453)
		(end 37.267896 -149.3774)
		(width 0.12446)
		(layer "F.Cu")
		(net "MEMDQS_P1")
	)
	(arc
		(start 38.955472 -148.771356)
		(mid 39.115218 -148.739487)
		(end 39.25062 -148.648928)
		(width 0.12446)
		(layer "F.Cu")
		(net "MEMDQS_P1")
	)
	(arc
		(start 37.5285 -149.3774)
		(mid 37.736652 -149.335902)
		(end 37.913056 -149.217888)
		(width 0.12446)
		(layer "F.Cu")
		(net "MEMDQS_P1")
	)
	(arc
		(start 38.1127 -149.018498)
		(mid 38.386547 -148.835486)
		(end 38.7096 -148.771356)
		(width 0.12446)
		(layer "F.Cu")
		(net "MEMDQS_P1")
	)
	(segment
		(start 30.769052 -151.458168)
		(end 30.454346 -151.143462)
		(width 0.1016)
		(layer "In2.Cu")
		(net "MEMDQS_P1")
	)
	(segment
		(start 21.419058 -150.012654)
		(end 23.843234 -150.012654)
		(width 0.1016)
		(layer "In2.Cu")
		(net "MEMDQS_P1")
	)
	(segment
		(start 36.44138 -149.456902)
		(end 36.2712 -149.456902)
		(width 0.1016)
		(layer "In2.Cu")
		(net "MEMDQS_P1")
	)
	(segment
		(start 35.58286 -150.145242)
		(end 35.58286 -151.423878)
		(width 0.1016)
		(layer "In2.Cu")
		(net "MEMDQS_P1")
	)
	(segment
		(start 22.095968 -148.222716)
		(end 22.0345 -148.161502)
		(width 0.1016)
		(layer "In2.Cu")
		(net "MEMDQS_P1")
	)
	(segment
		(start 29.791914 -150.872444)
		(end 29.264356 -150.872444)
		(width 0.1016)
		(layer "In2.Cu")
		(net "MEMDQS_P1")
	)
	(segment
		(start 25.132792 -150.872444)
		(end 21.419058 -150.872444)
		(width 0.1016)
		(layer "In2.Cu")
		(net "MEMDQS_P1")
	)
	(segment
		(start 35.234118 -151.77262)
		(end 31.528512 -151.77262)
		(width 0.1016)
		(layer "In2.Cu")
		(net "MEMDQS_P1")
	)
	(segment
		(start 23.843234 -148.372068)
		(end 22.45614 -148.372068)
		(width 0.1016)
		(layer "In2.Cu")
		(net "MEMDQS_P1")
	)
	(arc
		(start 21.419058 -150.872444)
		(mid 20.98929 -150.442676)
		(end 21.419058 -150.012654)
		(width 0.1016)
		(layer "In2.Cu")
		(net "MEMDQS_P1")
	)
	(arc
		(start 30.454346 -151.143462)
		(mid 30.149775 -150.94283)
		(end 29.791914 -150.872444)
		(width 0.1016)
		(layer "In2.Cu")
		(net "MEMDQS_P1")
	)
	(arc
		(start 36.2712 -149.456902)
		(mid 35.78447 -149.658512)
		(end 35.58286 -150.145242)
		(width 0.1016)
		(layer "In2.Cu")
		(net "MEMDQS_P1")
	)
	(arc
		(start 23.843234 -150.012654)
		(mid 24.6634 -149.192488)
		(end 23.843234 -148.372068)
		(width 0.1016)
		(layer "In2.Cu")
		(net "MEMDQS_P1")
	)
	(arc
		(start 35.58286 -151.423878)
		(mid 35.480716 -151.670476)
		(end 35.234118 -151.77262)
		(width 0.1016)
		(layer "In2.Cu")
		(net "MEMDQS_P1")
	)
	(arc
		(start 36.798504 -149.141942)
		(mid 36.679473 -149.366929)
		(end 36.44138 -149.456902)
		(width 0.1016)
		(layer "In2.Cu")
		(net "MEMDQS_P1")
	)
	(arc
		(start 26.795984 -150.490936)
		(mid 26.564594 -150.19863)
		(end 26.208482 -150.088346)
		(width 0.1016)
		(layer "In2.Cu")
		(net "MEMDQS_P1")
	)
	(arc
		(start 28.902152 -150.60295)
		(mid 28.657498 -150.237819)
		(end 28.241244 -150.096728)
		(width 0.1016)
		(layer "In2.Cu")
		(net "MEMDQS_P1")
	)
	(arc
		(start 28.241244 -150.096728)
		(mid 27.852022 -150.215325)
		(end 27.595068 -150.530814)
		(width 0.1016)
		(layer "In2.Cu")
		(net "MEMDQS_P1")
	)
	(arc
		(start 29.264356 -150.872444)
		(mid 29.036515 -150.800552)
		(end 28.902152 -150.60295)
		(width 0.1016)
		(layer "In2.Cu")
		(net "MEMDQS_P1")
	)
	(arc
		(start 26.208482 -150.088346)
		(mid 25.755909 -150.246267)
		(end 25.499822 -150.651464)
		(width 0.1016)
		(layer "In2.Cu")
		(net "MEMDQS_P1")
	)
	(arc
		(start 27.595068 -150.530814)
		(mid 27.183028 -150.761881)
		(end 26.795984 -150.490936)
		(width 0.1016)
		(layer "In2.Cu")
		(net "MEMDQS_P1")
	)
	(arc
		(start 22.45614 -148.372068)
		(mid 22.261207 -148.3332)
		(end 22.095968 -148.222716)
		(width 0.1016)
		(layer "In2.Cu")
		(net "MEMDQS_P1")
	)
	(arc
		(start 31.528512 -151.77262)
		(mid 31.117515 -151.690903)
		(end 30.769052 -151.458168)
		(width 0.1016)
		(layer "In2.Cu")
		(net "MEMDQS_P1")
	)
	(arc
		(start 25.499822 -150.651464)
		(mid 25.347002 -150.812937)
		(end 25.132792 -150.872444)
		(width 0.1016)
		(layer "In2.Cu")
		(net "MEMDQS_P1")
	)
	(segment
		(start 18.434558 -143.76146)
		(end 18.034508 -144.16151)
		(width 0.12446)
		(layer "F.Cu")
		(net "MEMDQS_P0")
	)
	(segment
		(start 38.065456 -146.84502)
		(end 39.022528 -146.84502)
		(width 0.12446)
		(layer "F.Cu")
		(net "MEMDQS_P0")
	)
	(via
		(at 18.034508 -144.16151)
		(size 0.508)
		(drill 0.254)
		(layers "F.Cu" "B.Cu")
		(net "MEMDQS_P0")
	)
	(via
		(at 37.695886 -147.155662)
		(size 0.508)
		(drill 0.254)
		(layers "F.Cu" "B.Cu")
		(net "MEMDQS_P0")
	)
	(arc
		(start 39.022528 -146.84502)
		(mid 39.038294 -146.845402)
		(end 39.054024 -146.846544)
		(width 0.12446)
		(layer "F.Cu")
		(net "MEMDQS_P0")
	)
	(arc
		(start 39.054024 -146.846544)
		(mid 39.194949 -146.894412)
		(end 39.299896 -146.99996)
		(width 0.12446)
		(layer "F.Cu")
		(net "MEMDQS_P0")
	)
	(arc
		(start 37.695886 -147.155662)
		(mid 37.824064 -146.932995)
		(end 38.065456 -146.84502)
		(width 0.12446)
		(layer "F.Cu")
		(net "MEMDQS_P0")
	)
	(segment
		(start 20.97532 -145.128234)
		(end 23.81885 -145.128234)
		(width 0.1016)
		(layer "In2.Cu")
		(net "MEMDQS_P0")
	)
	(segment
		(start 20.506944 -142.804388)
		(end 20.506944 -144.659858)
		(width 0.1016)
		(layer "In2.Cu")
		(net "MEMDQS_P0")
	)
	(segment
		(start 19.816572 -145.477992)
		(end 19.816572 -142.804388)
		(width 0.1016)
		(layer "In2.Cu")
		(net "MEMDQS_P0")
	)
	(segment
		(start 18.983198 -146.112992)
		(end 19.181572 -146.112992)
		(width 0.1016)
		(layer "In2.Cu")
		(net "MEMDQS_P0")
	)
	(segment
		(start 33.982406 -147.512278)
		(end 34.295588 -147.199096)
		(width 0.1016)
		(layer "In2.Cu")
		(net "MEMDQS_P0")
	)
	(segment
		(start 27.100022 -147.8153)
		(end 33.250124 -147.8153)
		(width 0.1016)
		(layer "In2.Cu")
		(net "MEMDQS_P0")
	)
	(segment
		(start 18.174716 -144.500092)
		(end 18.174716 -145.286984)
		(width 0.1016)
		(layer "In2.Cu")
		(net "MEMDQS_P0")
	)
	(segment
		(start 18.416524 -145.871184)
		(end 18.42897 -145.88363)
		(width 0.1016)
		(layer "In2.Cu")
		(net "MEMDQS_P0")
	)
	(segment
		(start 35.103816 -146.864324)
		(end 37.221668 -146.864324)
		(width 0.1016)
		(layer "In2.Cu")
		(net "MEMDQS_P0")
	)
	(segment
		(start 24.228044 -145.297906)
		(end 26.495248 -147.564856)
		(width 0.1016)
		(layer "In2.Cu")
		(net "MEMDQS_P0")
	)
	(arc
		(start 20.506944 -144.659858)
		(mid 20.644128 -144.99105)
		(end 20.97532 -145.128234)
		(width 0.1016)
		(layer "In2.Cu")
		(net "MEMDQS_P0")
	)
	(arc
		(start 19.630644 -145.927572)
		(mid 19.768303 -145.721273)
		(end 19.816572 -145.477992)
		(width 0.1016)
		(layer "In2.Cu")
		(net "MEMDQS_P0")
	)
	(arc
		(start 18.42897 -145.88363)
		(mid 18.683281 -146.053399)
		(end 18.983198 -146.112992)
		(width 0.1016)
		(layer "In2.Cu")
		(net "MEMDQS_P0")
	)
	(arc
		(start 19.816572 -142.804388)
		(mid 20.161758 -142.459202)
		(end 20.506944 -142.804388)
		(width 0.1016)
		(layer "In2.Cu")
		(net "MEMDQS_P0")
	)
	(arc
		(start 34.295588 -147.199096)
		(mid 34.666406 -146.951323)
		(end 35.103816 -146.864324)
		(width 0.1016)
		(layer "In2.Cu")
		(net "MEMDQS_P0")
	)
	(arc
		(start 18.034508 -144.16151)
		(mid 18.138305 -144.316853)
		(end 18.174716 -144.500092)
		(width 0.1016)
		(layer "In2.Cu")
		(net "MEMDQS_P0")
	)
	(arc
		(start 18.174716 -145.286984)
		(mid 18.237509 -145.603137)
		(end 18.416524 -145.871184)
		(width 0.1016)
		(layer "In2.Cu")
		(net "MEMDQS_P0")
	)
	(arc
		(start 19.181572 -146.112992)
		(mid 19.424546 -146.06492)
		(end 19.630644 -145.927572)
		(width 0.1016)
		(layer "In2.Cu")
		(net "MEMDQS_P0")
	)
	(arc
		(start 33.250124 -147.8153)
		(mid 33.646411 -147.736643)
		(end 33.982406 -147.512278)
		(width 0.1016)
		(layer "In2.Cu")
		(net "MEMDQS_P0")
	)
	(arc
		(start 23.81885 -145.128234)
		(mid 24.040319 -145.172381)
		(end 24.228044 -145.297906)
		(width 0.1016)
		(layer "In2.Cu")
		(net "MEMDQS_P0")
	)
	(arc
		(start 37.221668 -146.864324)
		(mid 37.499949 -146.942976)
		(end 37.695886 -147.155662)
		(width 0.1016)
		(layer "In2.Cu")
		(net "MEMDQS_P0")
	)
	(arc
		(start 26.495248 -147.564856)
		(mid 26.772735 -147.750204)
		(end 27.100022 -147.8153)
		(width 0.1016)
		(layer "In2.Cu")
		(net "MEMDQS_P0")
	)
	(segment
		(start 22.0345 -148.961602)
		(end 21.63445 -148.561552)
		(width 0.12446)
		(layer "F.Cu")
		(net "MEMDQS_N1")
	)
	(segment
		(start 37.267896 -149.7838)
		(end 37.5285 -149.7838)
		(width 0.12446)
		(layer "F.Cu")
		(net "MEMDQS_N1")
	)
	(segment
		(start 36.798504 -150.076916)
		(end 36.96716 -149.908514)
		(width 0.12446)
		(layer "F.Cu")
		(net "MEMDQS_N1")
	)
	(segment
		(start 38.200584 -149.505416)
		(end 38.400228 -149.305772)
		(width 0.12446)
		(layer "F.Cu")
		(net "MEMDQS_N1")
	)
	(segment
		(start 39.164006 -149.264116)
		(end 39.299896 -149.400006)
		(width 0.12446)
		(layer "F.Cu")
		(net "MEMDQS_N1")
	)
	(segment
		(start 38.709346 -149.177756)
		(end 38.955472 -149.177756)
		(width 0.12446)
		(layer "F.Cu")
		(net "MEMDQS_N1")
	)
	(via
		(at 22.0345 -148.961602)
		(size 0.508)
		(drill 0.254)
		(layers "F.Cu" "B.Cu")
		(net "MEMDQS_N1")
	)
	(via
		(at 36.798504 -150.076916)
		(size 0.508)
		(drill 0.254)
		(layers "F.Cu" "B.Cu")
		(net "MEMDQS_N1")
	)
	(arc
		(start 38.400228 -149.305772)
		(mid 38.542053 -149.211008)
		(end 38.709346 -149.177756)
		(width 0.12446)
		(layer "F.Cu")
		(net "MEMDQS_N1")
	)
	(arc
		(start 38.955472 -149.177756)
		(mid 39.068323 -149.200203)
		(end 39.164006 -149.264116)
		(width 0.12446)
		(layer "F.Cu")
		(net "MEMDQS_N1")
	)
	(arc
		(start 37.5285 -149.7838)
		(mid 37.892228 -149.71145)
		(end 38.200584 -149.505416)
		(width 0.12446)
		(layer "F.Cu")
		(net "MEMDQS_N1")
	)
	(arc
		(start 36.96716 -149.908514)
		(mid 37.105124 -149.816237)
		(end 37.267896 -149.7838)
		(width 0.12446)
		(layer "F.Cu")
		(net "MEMDQS_N1")
	)
	(segment
		(start 35.88766 -151.423878)
		(end 35.88766 -150.145242)
		(width 0.1016)
		(layer "In2.Cu")
		(net "MEMDQS_N1")
	)
	(segment
		(start 29.272992 -151.177244)
		(end 29.791914 -151.177244)
		(width 0.1016)
		(layer "In2.Cu")
		(net "MEMDQS_N1")
	)
	(segment
		(start 30.239716 -151.360124)
		(end 30.553406 -151.673814)
		(width 0.1016)
		(layer "In2.Cu")
		(net "MEMDQS_N1")
	)
	(segment
		(start 21.419058 -151.177244)
		(end 25.132792 -151.177244)
		(width 0.1016)
		(layer "In2.Cu")
		(net "MEMDQS_N1")
	)
	(segment
		(start 36.2712 -149.761702)
		(end 36.441126 -149.761702)
		(width 0.1016)
		(layer "In2.Cu")
		(net "MEMDQS_N1")
	)
	(segment
		(start 22.45614 -148.676868)
		(end 23.843234 -148.676868)
		(width 0.1016)
		(layer "In2.Cu")
		(net "MEMDQS_N1")
	)
	(segment
		(start 23.843234 -149.707854)
		(end 21.419058 -149.707854)
		(width 0.1016)
		(layer "In2.Cu")
		(net "MEMDQS_N1")
	)
	(segment
		(start 26.515314 -150.6093)
		(end 26.51506 -150.6093)
		(width 0.1016)
		(layer "In2.Cu")
		(net "MEMDQS_N1")
	)
	(segment
		(start 22.0345 -148.961602)
		(end 22.22246 -148.773642)
		(width 0.1016)
		(layer "In2.Cu")
		(net "MEMDQS_N1")
	)
	(segment
		(start 25.76957 -150.794212)
		(end 25.769316 -150.793958)
		(width 0.1016)
		(layer "In2.Cu")
		(net "MEMDQS_N1")
	)
	(segment
		(start 31.528258 -152.07742)
		(end 35.234118 -152.07742)
		(width 0.1016)
		(layer "In2.Cu")
		(net "MEMDQS_N1")
	)
	(segment
		(start 28.607512 -150.682198)
		(end 28.607766 -150.682198)
		(width 0.1016)
		(layer "In2.Cu")
		(net "MEMDQS_N1")
	)
	(arc
		(start 30.553406 -151.673814)
		(mid 31.000715 -151.972506)
		(end 31.528258 -152.07742)
		(width 0.1016)
		(layer "In2.Cu")
		(net "MEMDQS_N1")
	)
	(arc
		(start 21.419058 -149.707854)
		(mid 20.684236 -150.442676)
		(end 21.419058 -151.177244)
		(width 0.1016)
		(layer "In2.Cu")
		(net "MEMDQS_N1")
	)
	(arc
		(start 26.51506 -150.6093)
		(mid 27.1678 -151.066432)
		(end 27.862784 -150.67661)
		(width 0.1016)
		(layer "In2.Cu")
		(net "MEMDQS_N1")
	)
	(arc
		(start 27.862784 -150.67661)
		(mid 27.872741 -150.656732)
		(end 27.881326 -150.636224)
		(width 0.1016)
		(layer "In2.Cu")
		(net "MEMDQS_N1")
	)
	(arc
		(start 29.791914 -151.177244)
		(mid 30.033736 -151.224786)
		(end 30.239716 -151.360124)
		(width 0.1016)
		(layer "In2.Cu")
		(net "MEMDQS_N1")
	)
	(arc
		(start 25.796748 -150.720298)
		(mid 25.945537 -150.484885)
		(end 26.208482 -150.393146)
		(width 0.1016)
		(layer "In2.Cu")
		(net "MEMDQS_N1")
	)
	(arc
		(start 25.132792 -151.177244)
		(mid 25.504371 -151.074163)
		(end 25.76957 -150.794212)
		(width 0.1016)
		(layer "In2.Cu")
		(net "MEMDQS_N1")
	)
	(arc
		(start 26.208482 -150.393146)
		(mid 26.39219 -150.450077)
		(end 26.511504 -150.600918)
		(width 0.1016)
		(layer "In2.Cu")
		(net "MEMDQS_N1")
	)
	(arc
		(start 35.88766 -150.145242)
		(mid 35.999996 -149.874038)
		(end 36.2712 -149.761702)
		(width 0.1016)
		(layer "In2.Cu")
		(net "MEMDQS_N1")
	)
	(arc
		(start 36.441126 -149.761702)
		(mid 36.679382 -149.851767)
		(end 36.798504 -150.076916)
		(width 0.1016)
		(layer "In2.Cu")
		(net "MEMDQS_N1")
	)
	(arc
		(start 27.881326 -150.636224)
		(mid 28.026425 -150.465436)
		(end 28.241244 -150.401528)
		(width 0.1016)
		(layer "In2.Cu")
		(net "MEMDQS_N1")
	)
	(arc
		(start 25.769316 -150.793958)
		(mid 25.785413 -150.758016)
		(end 25.796748 -150.720298)
		(width 0.1016)
		(layer "In2.Cu")
		(net "MEMDQS_N1")
	)
	(arc
		(start 22.22246 -148.773642)
		(mid 22.329673 -148.702004)
		(end 22.45614 -148.676868)
		(width 0.1016)
		(layer "In2.Cu")
		(net "MEMDQS_N1")
	)
	(arc
		(start 28.607766 -150.682198)
		(mid 28.854434 -151.045231)
		(end 29.272992 -151.177244)
		(width 0.1016)
		(layer "In2.Cu")
		(net "MEMDQS_N1")
	)
	(arc
		(start 35.234118 -152.07742)
		(mid 35.696242 -151.886002)
		(end 35.88766 -151.423878)
		(width 0.1016)
		(layer "In2.Cu")
		(net "MEMDQS_N1")
	)
	(arc
		(start 23.843234 -148.676868)
		(mid 24.358854 -149.192488)
		(end 23.843234 -149.707854)
		(width 0.1016)
		(layer "In2.Cu")
		(net "MEMDQS_N1")
	)
	(arc
		(start 28.241244 -150.401528)
		(mid 28.471942 -150.479772)
		(end 28.607512 -150.682198)
		(width 0.1016)
		(layer "In2.Cu")
		(net "MEMDQS_N1")
	)
	(arc
		(start 26.511504 -150.600918)
		(mid 26.513483 -150.605075)
		(end 26.515314 -150.6093)
		(width 0.1016)
		(layer "In2.Cu")
		(net "MEMDQS_N1")
	)
	(segment
		(start 18.434558 -144.56156)
		(end 18.834608 -144.16151)
		(width 0.12446)
		(layer "F.Cu")
		(net "MEMDQS_N0")
	)
	(segment
		(start 39.022274 -146.43862)
		(end 38.090602 -146.43862)
		(width 0.12446)
		(layer "F.Cu")
		(net "MEMDQS_N0")
	)
	(via
		(at 37.695886 -146.220688)
		(size 0.508)
		(drill 0.254)
		(layers "F.Cu" "B.Cu")
		(net "MEMDQS_N0")
	)
	(via
		(at 18.834608 -144.16151)
		(size 0.508)
		(drill 0.254)
		(layers "F.Cu" "B.Cu")
		(net "MEMDQS_N0")
	)
	(arc
		(start 39.299896 -146.19986)
		(mid 39.205391 -146.370785)
		(end 39.022274 -146.43862)
		(width 0.12446)
		(layer "F.Cu")
		(net "MEMDQS_N0")
	)
	(arc
		(start 38.090602 -146.43862)
		(mid 37.865169 -146.380512)
		(end 37.695886 -146.220688)
		(width 0.12446)
		(layer "F.Cu")
		(net "MEMDQS_N0")
	)
	(segment
		(start 18.644616 -145.667984)
		(end 18.63217 -145.655538)
		(width 0.1016)
		(layer "In2.Cu")
		(net "MEMDQS_N0")
	)
	(segment
		(start 18.734532 -144.16151)
		(end 18.834608 -144.16151)
		(width 0.1016)
		(layer "In2.Cu")
		(net "MEMDQS_N0")
	)
	(segment
		(start 22.530054 -144.823434)
		(end 22.225254 -144.823434)
		(width 0.1016)
		(layer "In2.Cu")
		(net "MEMDQS_N0")
	)
	(segment
		(start 34.079942 -146.98345)
		(end 33.76676 -147.296632)
		(width 0.1016)
		(layer "In2.Cu")
		(net "MEMDQS_N0")
	)
	(segment
		(start 37.221668 -146.559524)
		(end 35.103816 -146.559524)
		(width 0.1016)
		(layer "In2.Cu")
		(net "MEMDQS_N0")
	)
	(segment
		(start 23.236174 -144.622774)
		(end 22.931374 -144.622774)
		(width 0.1016)
		(layer "In2.Cu")
		(net "MEMDQS_N0")
	)
	(segment
		(start 21.823934 -144.622774)
		(end 21.519134 -144.622774)
		(width 0.1016)
		(layer "In2.Cu")
		(net "MEMDQS_N0")
	)
	(segment
		(start 24.687022 -145.325338)
		(end 24.44369 -145.08226)
		(width 0.1016)
		(layer "In2.Cu")
		(net "MEMDQS_N0")
	)
	(segment
		(start 19.414998 -145.711926)
		(end 19.414998 -145.711672)
		(width 0.1016)
		(layer "In2.Cu")
		(net "MEMDQS_N0")
	)
	(segment
		(start 26.710894 -147.34921)
		(end 24.687022 -145.325338)
		(width 0.1016)
		(layer "In2.Cu")
		(net "MEMDQS_N0")
	)
	(segment
		(start 19.181572 -145.808192)
		(end 18.983198 -145.808192)
		(width 0.1016)
		(layer "In2.Cu")
		(net "MEMDQS_N0")
	)
	(segment
		(start 21.117814 -144.823434)
		(end 20.97532 -144.823434)
		(width 0.1016)
		(layer "In2.Cu")
		(net "MEMDQS_N0")
	)
	(segment
		(start 18.479516 -145.286984)
		(end 18.479516 -144.416526)
		(width 0.1016)
		(layer "In2.Cu")
		(net "MEMDQS_N0")
	)
	(segment
		(start 23.819104 -144.823434)
		(end 23.637494 -144.823434)
		(width 0.1016)
		(layer "In2.Cu")
		(net "MEMDQS_N0")
	)
	(segment
		(start 19.511772 -142.804388)
		(end 19.511772 -145.478246)
		(width 0.1016)
		(layer "In2.Cu")
		(net "MEMDQS_N0")
	)
	(segment
		(start 33.250124 -147.5105)
		(end 27.100276 -147.5105)
		(width 0.1016)
		(layer "In2.Cu")
		(net "MEMDQS_N0")
	)
	(segment
		(start 20.811744 -144.659858)
		(end 20.811744 -142.804388)
		(width 0.1016)
		(layer "In2.Cu")
		(net "MEMDQS_N0")
	)
	(arc
		(start 20.811744 -142.804388)
		(mid 20.161758 -142.154402)
		(end 19.511772 -142.804388)
		(width 0.1016)
		(layer "In2.Cu")
		(net "MEMDQS_N0")
	)
	(arc
		(start 19.414998 -145.711672)
		(mid 19.307873 -145.783125)
		(end 19.181572 -145.808192)
		(width 0.1016)
		(layer "In2.Cu")
		(net "MEMDQS_N0")
	)
	(arc
		(start 18.63217 -145.655538)
		(mid 18.519185 -145.486444)
		(end 18.479516 -145.286984)
		(width 0.1016)
		(layer "In2.Cu")
		(net "MEMDQS_N0")
	)
	(arc
		(start 35.103816 -146.559524)
		(mid 34.549713 -146.669648)
		(end 34.079942 -146.98345)
		(width 0.1016)
		(layer "In2.Cu")
		(net "MEMDQS_N0")
	)
	(arc
		(start 20.97532 -144.823434)
		(mid 20.859654 -144.775524)
		(end 20.811744 -144.659858)
		(width 0.1016)
		(layer "In2.Cu")
		(net "MEMDQS_N0")
	)
	(arc
		(start 23.637494 -144.823434)
		(mid 23.525337 -144.79691)
		(end 23.436834 -144.723104)
		(width 0.1016)
		(layer "In2.Cu")
		(net "MEMDQS_N0")
	)
	(arc
		(start 33.76676 -147.296632)
		(mid 33.529725 -147.454984)
		(end 33.250124 -147.5105)
		(width 0.1016)
		(layer "In2.Cu")
		(net "MEMDQS_N0")
	)
	(arc
		(start 18.983198 -145.808192)
		(mid 18.799959 -145.771761)
		(end 18.644616 -145.667984)
		(width 0.1016)
		(layer "In2.Cu")
		(net "MEMDQS_N0")
	)
	(arc
		(start 22.730714 -144.723104)
		(mid 22.642188 -144.796864)
		(end 22.530054 -144.823434)
		(width 0.1016)
		(layer "In2.Cu")
		(net "MEMDQS_N0")
	)
	(arc
		(start 37.695886 -146.220688)
		(mid 37.513108 -146.466167)
		(end 37.221668 -146.559524)
		(width 0.1016)
		(layer "In2.Cu")
		(net "MEMDQS_N0")
	)
	(arc
		(start 27.100276 -147.5105)
		(mid 26.889543 -147.468583)
		(end 26.710894 -147.34921)
		(width 0.1016)
		(layer "In2.Cu")
		(net "MEMDQS_N0")
	)
	(arc
		(start 22.225254 -144.823434)
		(mid 22.113097 -144.79691)
		(end 22.024594 -144.723104)
		(width 0.1016)
		(layer "In2.Cu")
		(net "MEMDQS_N0")
	)
	(arc
		(start 21.318474 -144.723104)
		(mid 21.229948 -144.796864)
		(end 21.117814 -144.823434)
		(width 0.1016)
		(layer "In2.Cu")
		(net "MEMDQS_N0")
	)
	(arc
		(start 22.931374 -144.622774)
		(mid 22.819217 -144.649298)
		(end 22.730714 -144.723104)
		(width 0.1016)
		(layer "In2.Cu")
		(net "MEMDQS_N0")
	)
	(arc
		(start 19.511772 -145.478246)
		(mid 19.486633 -145.604719)
		(end 19.414998 -145.711926)
		(width 0.1016)
		(layer "In2.Cu")
		(net "MEMDQS_N0")
	)
	(arc
		(start 23.436834 -144.723104)
		(mid 23.348308 -144.649344)
		(end 23.236174 -144.622774)
		(width 0.1016)
		(layer "In2.Cu")
		(net "MEMDQS_N0")
	)
	(arc
		(start 21.519134 -144.622774)
		(mid 21.406977 -144.649298)
		(end 21.318474 -144.723104)
		(width 0.1016)
		(layer "In2.Cu")
		(net "MEMDQS_N0")
	)
	(arc
		(start 24.44369 -145.08226)
		(mid 24.157128 -144.890756)
		(end 23.819104 -144.823434)
		(width 0.1016)
		(layer "In2.Cu")
		(net "MEMDQS_N0")
	)
	(arc
		(start 18.479516 -144.416526)
		(mid 18.554208 -144.236202)
		(end 18.734532 -144.16151)
		(width 0.1016)
		(layer "In2.Cu")
		(net "MEMDQS_N0")
	)
	(arc
		(start 22.024594 -144.723104)
		(mid 21.936068 -144.649344)
		(end 21.823934 -144.622774)
		(width 0.1016)
		(layer "In2.Cu")
		(net "MEMDQS_N0")
	)
	(segment
		(start 20.243292 -143.342106)
		(end 20.388072 -143.486886)
		(width 0.127)
		(layer "F.Cu")
		(net "MEMDM_1")
	)
	(segment
		(start 20.894294 -149.635464)
		(end 24.31796 -149.635464)
		(width 0.127)
		(layer "F.Cu")
		(net "MEMDM_1")
	)
	(segment
		(start 19.699732 -143.342106)
		(end 20.243292 -143.342106)
		(width 0.127)
		(layer "F.Cu")
		(net "MEMDM_1")
	)
	(segment
		(start 19.252946 -145.85188)
		(end 19.554952 -145.549874)
		(width 0.127)
		(layer "F.Cu")
		(net "MEMDM_1")
	)
	(segment
		(start 35.875468 -148.044154)
		(end 35.900106 -148.044154)
		(width 0.127)
		(layer "F.Cu")
		(net "MEMDM_1")
	)
	(segment
		(start 17.999964 -145.727166)
		(end 18.6436 -145.727166)
		(width 0.127)
		(layer "F.Cu")
		(net "MEMDM_1")
	)
	(segment
		(start 19.554952 -145.549874)
		(end 19.554952 -143.486886)
		(width 0.127)
		(layer "F.Cu")
		(net "MEMDM_1")
	)
	(segment
		(start 18.6436 -145.727166)
		(end 18.768314 -145.85188)
		(width 0.127)
		(layer "F.Cu")
		(net "MEMDM_1")
	)
	(segment
		(start 35.22345 -148.696172)
		(end 35.875468 -148.044154)
		(width 0.127)
		(layer "F.Cu")
		(net "MEMDM_1")
	)
	(segment
		(start 24.621744 -149.33168)
		(end 26.983436 -149.33168)
		(width 0.127)
		(layer "F.Cu")
		(net "MEMDM_1")
	)
	(segment
		(start 26.983436 -149.33168)
		(end 27.618944 -148.696172)
		(width 0.127)
		(layer "F.Cu")
		(net "MEMDM_1")
	)
	(segment
		(start 20.388072 -143.486886)
		(end 20.388072 -149.129242)
		(width 0.127)
		(layer "F.Cu")
		(net "MEMDM_1")
	)
	(segment
		(start 19.554952 -143.486886)
		(end 19.699732 -143.342106)
		(width 0.127)
		(layer "F.Cu")
		(net "MEMDM_1")
	)
	(segment
		(start 27.618944 -148.696172)
		(end 35.22345 -148.696172)
		(width 0.127)
		(layer "F.Cu")
		(net "MEMDM_1")
	)
	(segment
		(start 17.634458 -145.36166)
		(end 17.999964 -145.727166)
		(width 0.127)
		(layer "F.Cu")
		(net "MEMDM_1")
	)
	(segment
		(start 36.16706 -147.7772)
		(end 39.277036 -147.7772)
		(width 0.127)
		(layer "F.Cu")
		(net "MEMDM_1")
	)
	(segment
		(start 35.900106 -148.044154)
		(end 36.16706 -147.7772)
		(width 0.127)
		(layer "F.Cu")
		(net "MEMDM_1")
	)
	(segment
		(start 39.277036 -147.7772)
		(end 39.299896 -147.80006)
		(width 0.127)
		(layer "F.Cu")
		(net "MEMDM_1")
	)
	(segment
		(start 24.31796 -149.635464)
		(end 24.621744 -149.33168)
		(width 0.127)
		(layer "F.Cu")
		(net "MEMDM_1")
	)
	(segment
		(start 20.388072 -149.129242)
		(end 20.894294 -149.635464)
		(width 0.127)
		(layer "F.Cu")
		(net "MEMDM_1")
	)
	(segment
		(start 18.768314 -145.85188)
		(end 19.252946 -145.85188)
		(width 0.127)
		(layer "F.Cu")
		(net "MEMDM_1")
	)
	(segment
		(start 43.299888 -147.80006)
		(end 42.900092 -148.199856)
		(width 0.127)
		(layer "F.Cu")
		(net "MEMDM_0")
	)
	(segment
		(start 21.63445 -145.36166)
		(end 21.2344 -145.76171)
		(width 0.127)
		(layer "F.Cu")
		(net "MEMDM_0")
	)
	(via
		(at 42.900092 -148.199856)
		(size 0.4572)
		(drill 0.2032)
		(layers "F.Cu" "B.Cu")
		(net "MEMDM_0")
	)
	(via
		(at 21.2344 -145.76171)
		(size 0.508)
		(drill 0.254)
		(layers "F.Cu" "B.Cu")
		(net "MEMDM_0")
	)
	(segment
		(start 20.919948 -146.076162)
		(end 21.2344 -145.76171)
		(width 0.127)
		(layer "In5.Cu")
		(net "MEMDM_0")
	)
	(segment
		(start 20.265136 -145.26641)
		(end 20.03298 -145.498566)
		(width 0.127)
		(layer "In5.Cu")
		(net "MEMDM_0")
	)
	(segment
		(start 37.165788 -150.65375)
		(end 36.295838 -150.65375)
		(width 0.127)
		(layer "In5.Cu")
		(net "MEMDM_0")
	)
	(segment
		(start 42.900092 -148.199856)
		(end 42.506392 -148.593556)
		(width 0.127)
		(layer "In5.Cu")
		(net "MEMDM_0")
	)
	(segment
		(start 24.5872 -148.410676)
		(end 24.053546 -147.877022)
		(width 0.127)
		(layer "In5.Cu")
		(net "MEMDM_0")
	)
	(segment
		(start 41.135046 -148.593556)
		(end 40.919146 -148.377656)
		(width 0.127)
		(layer "In5.Cu")
		(net "MEMDM_0")
	)
	(segment
		(start 39.441882 -148.377656)
		(end 37.165788 -150.65375)
		(width 0.127)
		(layer "In5.Cu")
		(net "MEMDM_0")
	)
	(segment
		(start 26.058622 -149.5171)
		(end 24.952198 -148.410676)
		(width 0.127)
		(layer "In5.Cu")
		(net "MEMDM_0")
	)
	(segment
		(start 36.295838 -150.65375)
		(end 35.58667 -149.944582)
		(width 0.127)
		(layer "In5.Cu")
		(net "MEMDM_0")
	)
	(segment
		(start 24.952198 -148.410676)
		(end 24.5872 -148.410676)
		(width 0.127)
		(layer "In5.Cu")
		(net "MEMDM_0")
	)
	(segment
		(start 20.209764 -146.076162)
		(end 20.919948 -146.076162)
		(width 0.127)
		(layer "In5.Cu")
		(net "MEMDM_0")
	)
	(segment
		(start 24.053546 -147.877022)
		(end 24.053546 -145.58772)
		(width 0.127)
		(layer "In5.Cu")
		(net "MEMDM_0")
	)
	(segment
		(start 23.732236 -145.26641)
		(end 20.265136 -145.26641)
		(width 0.127)
		(layer "In5.Cu")
		(net "MEMDM_0")
	)
	(segment
		(start 27.93492 -149.5171)
		(end 26.058622 -149.5171)
		(width 0.127)
		(layer "In5.Cu")
		(net "MEMDM_0")
	)
	(segment
		(start 42.506392 -148.593556)
		(end 41.135046 -148.593556)
		(width 0.127)
		(layer "In5.Cu")
		(net "MEMDM_0")
	)
	(segment
		(start 20.03298 -145.899378)
		(end 20.209764 -146.076162)
		(width 0.127)
		(layer "In5.Cu")
		(net "MEMDM_0")
	)
	(segment
		(start 35.58667 -149.944582)
		(end 28.362402 -149.944582)
		(width 0.127)
		(layer "In5.Cu")
		(net "MEMDM_0")
	)
	(segment
		(start 24.053546 -145.58772)
		(end 23.732236 -145.26641)
		(width 0.127)
		(layer "In5.Cu")
		(net "MEMDM_0")
	)
	(segment
		(start 28.362402 -149.944582)
		(end 27.93492 -149.5171)
		(width 0.127)
		(layer "In5.Cu")
		(net "MEMDM_0")
	)
	(segment
		(start 40.919146 -148.377656)
		(end 39.441882 -148.377656)
		(width 0.127)
		(layer "In5.Cu")
		(net "MEMDM_0")
	)
	(segment
		(start 20.03298 -145.498566)
		(end 20.03298 -145.899378)
		(width 0.127)
		(layer "In5.Cu")
		(net "MEMDM_0")
	)
	(segment
		(start 30.485334 -143.47698)
		(end 26.70302 -143.47698)
		(width 0.127)
		(layer "F.Cu")
		(net "MEMCSN")
	)
	(segment
		(start 26.57602 -144.07896)
		(end 26.70302 -144.20596)
		(width 0.127)
		(layer "F.Cu")
		(net "MEMCSN")
	)
	(segment
		(start 19.85137 -131.261358)
		(end 19.85137 -133.604)
		(width 0.127)
		(layer "F.Cu")
		(net "MEMCSN")
	)
	(segment
		(start 20.225004 -139.032742)
		(end 20.225004 -139.5603)
		(width 0.127)
		(layer "F.Cu")
		(net "MEMCSN")
	)
	(segment
		(start 26.70302 -144.20596)
		(end 29.79674 -144.20596)
		(width 0.127)
		(layer "F.Cu")
		(net "MEMCSN")
	)
	(segment
		(start 20.301204 -138.400028)
		(end 20.301204 -138.7475)
		(width 0.127)
		(layer "F.Cu")
		(net "MEMCSN")
	)
	(segment
		(start 31.120334 -144.08404)
		(end 30.993334 -144.21104)
		(width 0.127)
		(layer "F.Cu")
		(net "MEMCSN")
	)
	(segment
		(start 19.15287 -129.530094)
		(end 19.144742 -129.521966)
		(width 0.127)
		(layer "F.Cu")
		(net "MEMCSN")
	)
	(segment
		(start 20.2946 -134.04723)
		(end 20.2946 -138.393424)
		(width 0.127)
		(layer "F.Cu")
		(net "MEMCSN")
	)
	(segment
		(start 19.15287 -130.562858)
		(end 19.15287 -129.530094)
		(width 0.127)
		(layer "F.Cu")
		(net "MEMCSN")
	)
	(segment
		(start 30.993334 -144.21104)
		(end 30.739334 -144.21104)
		(width 0.127)
		(layer "F.Cu")
		(net "MEMCSN")
	)
	(segment
		(start 29.79674 -144.20596)
		(end 29.8196 -144.1831)
		(width 0.127)
		(layer "F.Cu")
		(net "MEMCSN")
	)
	(segment
		(start 39.80053 -144.491964)
		(end 39.67353 -144.364964)
		(width 0.1016)
		(layer "F.Cu")
		(net "MEMCSN")
	)
	(segment
		(start 20.225004 -139.5603)
		(end 20.825968 -140.161264)
		(width 0.127)
		(layer "F.Cu")
		(net "MEMCSN")
	)
	(segment
		(start 34.125408 -144.092168)
		(end 33.51022 -143.47698)
		(width 0.127)
		(layer "F.Cu")
		(net "MEMCSN")
	)
	(segment
		(start 33.51022 -143.47698)
		(end 31.247334 -143.47698)
		(width 0.127)
		(layer "F.Cu")
		(net "MEMCSN")
	)
	(segment
		(start 31.247334 -143.47698)
		(end 31.120334 -143.60398)
		(width 0.127)
		(layer "F.Cu")
		(net "MEMCSN")
	)
	(segment
		(start 37.2872 -144.212564)
		(end 36.971224 -144.52854)
		(width 0.127)
		(layer "F.Cu")
		(net "MEMCSN")
	)
	(segment
		(start 20.825968 -140.161264)
		(end 21.234146 -140.161264)
		(width 0.127)
		(layer "F.Cu")
		(net "MEMCSN")
	)
	(segment
		(start 26.70302 -143.47698)
		(end 26.57602 -143.60398)
		(width 0.127)
		(layer "F.Cu")
		(net "MEMCSN")
	)
	(segment
		(start 19.15287 -130.562858)
		(end 19.85137 -131.261358)
		(width 0.127)
		(layer "F.Cu")
		(net "MEMCSN")
	)
	(segment
		(start 21.2344 -140.161518)
		(end 21.63445 -140.561568)
		(width 0.127)
		(layer "F.Cu")
		(net "MEMCSN")
	)
	(segment
		(start 39.67353 -144.364964)
		(end 39.62908 -144.32026)
		(width 0.1016)
		(layer "F.Cu")
		(net "MEMCSN")
	)
	(segment
		(start 30.612334 -143.60398)
		(end 30.485334 -143.47698)
		(width 0.127)
		(layer "F.Cu")
		(net "MEMCSN")
	)
	(segment
		(start 34.549842 -144.52854)
		(end 34.125408 -144.104106)
		(width 0.127)
		(layer "F.Cu")
		(net "MEMCSN")
	)
	(segment
		(start 20.2946 -138.754104)
		(end 20.2946 -138.963146)
		(width 0.127)
		(layer "F.Cu")
		(net "MEMCSN")
	)
	(segment
		(start 19.85137 -133.604)
		(end 20.2946 -134.04723)
		(width 0.127)
		(layer "F.Cu")
		(net "MEMCSN")
	)
	(segment
		(start 39.36873 -144.212564)
		(end 37.2872 -144.212564)
		(width 0.127)
		(layer "F.Cu")
		(net "MEMCSN")
	)
	(segment
		(start 34.125408 -144.104106)
		(end 34.125408 -144.092168)
		(width 0.127)
		(layer "F.Cu")
		(net "MEMCSN")
	)
	(segment
		(start 26.57602 -143.60398)
		(end 26.57602 -144.07896)
		(width 0.127)
		(layer "F.Cu")
		(net "MEMCSN")
	)
	(segment
		(start 36.971224 -144.52854)
		(end 34.549842 -144.52854)
		(width 0.127)
		(layer "F.Cu")
		(net "MEMCSN")
	)
	(segment
		(start 21.234146 -140.161264)
		(end 21.2344 -140.161518)
		(width 0.127)
		(layer "F.Cu")
		(net "MEMCSN")
	)
	(segment
		(start 31.120334 -143.60398)
		(end 31.120334 -144.08404)
		(width 0.127)
		(layer "F.Cu")
		(net "MEMCSN")
	)
	(segment
		(start 20.2946 -138.963146)
		(end 20.225004 -139.032742)
		(width 0.127)
		(layer "F.Cu")
		(net "MEMCSN")
	)
	(segment
		(start 30.739334 -144.21104)
		(end 30.612334 -144.08404)
		(width 0.127)
		(layer "F.Cu")
		(net "MEMCSN")
	)
	(segment
		(start 20.301204 -138.7475)
		(end 20.2946 -138.754104)
		(width 0.127)
		(layer "F.Cu")
		(net "MEMCSN")
	)
	(segment
		(start 30.612334 -144.08404)
		(end 30.612334 -143.60398)
		(width 0.127)
		(layer "F.Cu")
		(net "MEMCSN")
	)
	(segment
		(start 20.2946 -138.393424)
		(end 20.301204 -138.400028)
		(width 0.127)
		(layer "F.Cu")
		(net "MEMCSN")
	)
	(segment
		(start 40.099996 -144.599914)
		(end 40.061134 -144.599914)
		(width 0.1016)
		(layer "F.Cu")
		(net "MEMCSN")
	)
	(via
		(at 29.8196 -144.1831)
		(size 0.508)
		(drill 0.254)
		(layers "F.Cu" "B.Cu")
		(net "MEMCSN")
	)
	(via
		(at 21.2344 -140.161518)
		(size 0.508)
		(drill 0.254)
		(layers "F.Cu" "B.Cu")
		(net "MEMCSN")
	)
	(arc
		(start 40.061134 -144.599914)
		(mid 39.920094 -144.571859)
		(end 39.80053 -144.491964)
		(width 0.1016)
		(layer "F.Cu")
		(net "MEMCSN")
	)
	(arc
		(start 39.62908 -144.32026)
		(mid 39.509602 -144.240554)
		(end 39.36873 -144.212564)
		(width 0.1016)
		(layer "F.Cu")
		(net "MEMCSN")
	)
	(segment
		(start 23.730712 -141.099032)
		(end 23.288498 -140.656818)
		(width 0.127)
		(layer "In2.Cu")
		(net "MEMCSN")
	)
	(segment
		(start 25.383744 -141.184376)
		(end 24.426164 -141.184376)
		(width 0.127)
		(layer "In2.Cu")
		(net "MEMCSN")
	)
	(segment
		(start 29.8196 -144.1831)
		(end 28.983178 -143.346678)
		(width 0.127)
		(layer "In2.Cu")
		(net "MEMCSN")
	)
	(segment
		(start 23.288498 -140.656818)
		(end 23.19274 -140.56106)
		(width 0.0889)
		(layer "In2.Cu")
		(net "MEMCSN")
	)
	(segment
		(start 24.34082 -141.099032)
		(end 23.730712 -141.099032)
		(width 0.127)
		(layer "In2.Cu")
		(net "MEMCSN")
	)
	(segment
		(start 27.546046 -143.346678)
		(end 25.383744 -141.184376)
		(width 0.127)
		(layer "In2.Cu")
		(net "MEMCSN")
	)
	(segment
		(start 23.19274 -140.56106)
		(end 21.633942 -140.56106)
		(width 0.0889)
		(layer "In2.Cu")
		(net "MEMCSN")
	)
	(segment
		(start 21.633942 -140.56106)
		(end 21.2344 -140.161518)
		(width 0.0889)
		(layer "In2.Cu")
		(net "MEMCSN")
	)
	(segment
		(start 28.983178 -143.346678)
		(end 27.546046 -143.346678)
		(width 0.127)
		(layer "In2.Cu")
		(net "MEMCSN")
	)
	(segment
		(start 24.426164 -141.184376)
		(end 24.34082 -141.099032)
		(width 0.127)
		(layer "In2.Cu")
		(net "MEMCSN")
	)
	(segment
		(start 36.115244 -146.002502)
		(end 34.69005 -146.002502)
		(width 0.12446)
		(layer "F.Cu")
		(net "MEMCK_P")
	)
	(segment
		(start 21.63445 -141.361668)
		(end 21.634958 -141.361668)
		(width 0.12446)
		(layer "F.Cu")
		(net "MEMCK_P")
	)
	(segment
		(start 32.670242 -146.970242)
		(end 29.651198 -146.970242)
		(width 0.12446)
		(layer "F.Cu")
		(net "MEMCK_P")
	)
	(segment
		(start 21.634958 -141.361668)
		(end 22.0345 -141.76121)
		(width 0.12446)
		(layer "F.Cu")
		(net "MEMCK_P")
	)
	(segment
		(start 33.79216 -146.374358)
		(end 33.568132 -146.598386)
		(width 0.12446)
		(layer "F.Cu")
		(net "MEMCK_P")
	)
	(segment
		(start 38.9636 -145.21815)
		(end 37.951664 -145.21815)
		(width 0.12446)
		(layer "F.Cu")
		(net "MEMCK_P")
	)
	(segment
		(start 37.053774 -145.590006)
		(end 37.013134 -145.630646)
		(width 0.12446)
		(layer "F.Cu")
		(net "MEMCK_P")
	)
	(segment
		(start 29.651452 -145.19148)
		(end 32.244538 -145.19148)
		(width 0.12446)
		(layer "F.Cu")
		(net "MEMCK_P")
	)
	(segment
		(start 32.332676 -145.15465)
		(end 32.339026 -145.1483)
		(width 0.12446)
		(layer "F.Cu")
		(net "MEMCK_P")
	)
	(segment
		(start 32.38246 -145.044414)
		(end 32.38246 -144.957546)
		(width 0.12446)
		(layer "F.Cu")
		(net "MEMCK_P")
	)
	(segment
		(start 32.339026 -145.1483)
		(end 32.33928 -145.1483)
		(width 0.12446)
		(layer "F.Cu")
		(net "MEMCK_P")
	)
	(via
		(at 32.092138 -144.667224)
		(size 0.508)
		(drill 0.254)
		(layers "F.Cu" "B.Cu")
		(net "MEMCK_P")
	)
	(via
		(at 22.0345 -141.76121)
		(size 0.508)
		(drill 0.254)
		(layers "F.Cu" "B.Cu")
		(net "MEMCK_P")
	)
	(arc
		(start 33.568132 -146.598386)
		(mid 33.156162 -146.873592)
		(end 32.670242 -146.970242)
		(width 0.12446)
		(layer "F.Cu")
		(net "MEMCK_P")
	)
	(arc
		(start 37.013134 -145.630646)
		(mid 36.601164 -145.905852)
		(end 36.115244 -146.002502)
		(width 0.12446)
		(layer "F.Cu")
		(net "MEMCK_P")
	)
	(arc
		(start 29.651198 -146.970242)
		(mid 29.0224 -146.709786)
		(end 28.761944 -146.080988)
		(width 0.12446)
		(layer "F.Cu")
		(net "MEMCK_P")
	)
	(arc
		(start 32.33928 -145.1483)
		(mid 32.371264 -145.100666)
		(end 32.38246 -145.044414)
		(width 0.12446)
		(layer "F.Cu")
		(net "MEMCK_P")
	)
	(arc
		(start 39.299896 -145.400014)
		(mid 39.154765 -145.266516)
		(end 38.9636 -145.21815)
		(width 0.12446)
		(layer "F.Cu")
		(net "MEMCK_P")
	)
	(arc
		(start 28.761944 -146.080988)
		(mid 29.022475 -145.452011)
		(end 29.651452 -145.19148)
		(width 0.12446)
		(layer "F.Cu")
		(net "MEMCK_P")
	)
	(arc
		(start 32.38246 -144.957546)
		(mid 32.297427 -144.752257)
		(end 32.092138 -144.667224)
		(width 0.12446)
		(layer "F.Cu")
		(net "MEMCK_P")
	)
	(arc
		(start 37.951664 -145.21815)
		(mid 37.465739 -145.314789)
		(end 37.053774 -145.590006)
		(width 0.12446)
		(layer "F.Cu")
		(net "MEMCK_P")
	)
	(arc
		(start 34.69005 -146.002502)
		(mid 34.204125 -146.099141)
		(end 33.79216 -146.374358)
		(width 0.12446)
		(layer "F.Cu")
		(net "MEMCK_P")
	)
	(arc
		(start 32.244538 -145.19148)
		(mid 32.292279 -145.181854)
		(end 32.332676 -145.15465)
		(width 0.12446)
		(layer "F.Cu")
		(net "MEMCK_P")
	)
	(segment
		(start 21.130768 -141.52372)
		(end 21.79701 -141.52372)
		(width 0.12446)
		(layer "B.Cu")
		(net "MEMCK_P")
	)
	(segment
		(start 20.821396 -141.833092)
		(end 21.130768 -141.52372)
		(width 0.12446)
		(layer "B.Cu")
		(net "MEMCK_P")
	)
	(segment
		(start 21.79701 -141.52372)
		(end 22.0345 -141.76121)
		(width 0.12446)
		(layer "B.Cu")
		(net "MEMCK_P")
	)
	(segment
		(start 23.255224 -141.633448)
		(end 23.255224 -141.497558)
		(width 0.1016)
		(layer "In2.Cu")
		(net "MEMCK_P")
	)
	(segment
		(start 22.28215 -141.51356)
		(end 22.0345 -141.76121)
		(width 0.1016)
		(layer "In2.Cu")
		(net "MEMCK_P")
	)
	(segment
		(start 32.325818 -144.071594)
		(end 31.583376 -144.071594)
		(width 0.1016)
		(layer "In2.Cu")
		(net "MEMCK_P")
	)
	(segment
		(start 28.605226 -144.52727)
		(end 27.669236 -144.52727)
		(width 0.1016)
		(layer "In2.Cu")
		(net "MEMCK_P")
	)
	(segment
		(start 29.160978 -144.999202)
		(end 28.748736 -144.58696)
		(width 0.1016)
		(layer "In2.Cu")
		(net "MEMCK_P")
	)
	(segment
		(start 30.551882 -145.2372)
		(end 29.73578 -145.2372)
		(width 0.1016)
		(layer "In2.Cu")
		(net "MEMCK_P")
	)
	(segment
		(start 22.696678 -141.29766)
		(end 22.480778 -141.51356)
		(width 0.1016)
		(layer "In2.Cu")
		(net "MEMCK_P")
	)
	(segment
		(start 31.242 -144.41297)
		(end 31.242 -144.532858)
		(width 0.1016)
		(layer "In2.Cu")
		(net "MEMCK_P")
	)
	(segment
		(start 23.055326 -141.29766)
		(end 22.696678 -141.29766)
		(width 0.1016)
		(layer "In2.Cu")
		(net "MEMCK_P")
	)
	(segment
		(start 32.455358 -144.304004)
		(end 32.455358 -144.201134)
		(width 0.1016)
		(layer "In2.Cu")
		(net "MEMCK_P")
	)
	(segment
		(start 24.959818 -142.238476)
		(end 23.887176 -142.238476)
		(width 0.1016)
		(layer "In2.Cu")
		(net "MEMCK_P")
	)
	(segment
		(start 27.094434 -144.289272)
		(end 25.103328 -142.298166)
		(width 0.1016)
		(layer "In2.Cu")
		(net "MEMCK_P")
	)
	(segment
		(start 22.480778 -141.51356)
		(end 22.28215 -141.51356)
		(width 0.1016)
		(layer "In2.Cu")
		(net "MEMCK_P")
	)
	(arc
		(start 27.669236 -144.52727)
		(mid 27.358151 -144.465467)
		(end 27.094434 -144.289272)
		(width 0.1016)
		(layer "In2.Cu")
		(net "MEMCK_P")
	)
	(arc
		(start 23.887176 -142.238476)
		(mid 23.625174 -142.185083)
		(end 23.405084 -142.033244)
		(width 0.1016)
		(layer "In2.Cu")
		(net "MEMCK_P")
	)
	(arc
		(start 32.455358 -144.201134)
		(mid 32.417417 -144.109535)
		(end 32.325818 -144.071594)
		(width 0.1016)
		(layer "In2.Cu")
		(net "MEMCK_P")
	)
	(arc
		(start 31.242 -144.532858)
		(mid 31.040722 -145.025937)
		(end 30.551882 -145.2372)
		(width 0.1016)
		(layer "In2.Cu")
		(net "MEMCK_P")
	)
	(arc
		(start 31.583376 -144.071594)
		(mid 31.341987 -144.171581)
		(end 31.242 -144.41297)
		(width 0.1016)
		(layer "In2.Cu")
		(net "MEMCK_P")
	)
	(arc
		(start 23.19655 -141.356334)
		(mid 23.131771 -141.312957)
		(end 23.055326 -141.29766)
		(width 0.1016)
		(layer "In2.Cu")
		(net "MEMCK_P")
	)
	(arc
		(start 28.748736 -144.58696)
		(mid 28.682922 -144.542828)
		(end 28.605226 -144.52727)
		(width 0.1016)
		(layer "In2.Cu")
		(net "MEMCK_P")
	)
	(arc
		(start 23.255224 -141.497558)
		(mid 23.239925 -141.421114)
		(end 23.19655 -141.356334)
		(width 0.1016)
		(layer "In2.Cu")
		(net "MEMCK_P")
	)
	(arc
		(start 29.73578 -145.2372)
		(mid 29.424695 -145.175397)
		(end 29.160978 -144.999202)
		(width 0.1016)
		(layer "In2.Cu")
		(net "MEMCK_P")
	)
	(arc
		(start 25.103328 -142.298166)
		(mid 25.037514 -142.254034)
		(end 24.959818 -142.238476)
		(width 0.1016)
		(layer "In2.Cu")
		(net "MEMCK_P")
	)
	(arc
		(start 23.405084 -142.033244)
		(mid 23.293869 -141.846952)
		(end 23.255224 -141.633448)
		(width 0.1016)
		(layer "In2.Cu")
		(net "MEMCK_P")
	)
	(arc
		(start 32.092138 -144.667224)
		(mid 32.348973 -144.560839)
		(end 32.455358 -144.304004)
		(width 0.1016)
		(layer "In2.Cu")
		(net "MEMCK_P")
	)
	(segment
		(start 33.504632 -146.08683)
		(end 33.280604 -146.310858)
		(width 0.12446)
		(layer "F.Cu")
		(net "MEMCK_N")
	)
	(segment
		(start 22.43455 -141.361668)
		(end 22.43455 -141.36116)
		(width 0.12446)
		(layer "F.Cu")
		(net "MEMCK_N")
	)
	(segment
		(start 32.670242 -146.563842)
		(end 29.651198 -146.563842)
		(width 0.12446)
		(layer "F.Cu")
		(net "MEMCK_N")
	)
	(segment
		(start 32.78886 -145.044668)
		(end 32.78886 -145.026126)
		(width 0.12446)
		(layer "F.Cu")
		(net "MEMCK_N")
	)
	(segment
		(start 32.620712 -145.44167)
		(end 32.626554 -145.435828)
		(width 0.12446)
		(layer "F.Cu")
		(net "MEMCK_N")
	)
	(segment
		(start 36.766246 -145.302478)
		(end 36.725606 -145.343118)
		(width 0.12446)
		(layer "F.Cu")
		(net "MEMCK_N")
	)
	(segment
		(start 22.43455 -141.36116)
		(end 22.0345 -140.96111)
		(width 0.12446)
		(layer "F.Cu")
		(net "MEMCK_N")
	)
	(segment
		(start 38.9636 -144.81175)
		(end 37.951664 -144.81175)
		(width 0.12446)
		(layer "F.Cu")
		(net "MEMCK_N")
	)
	(segment
		(start 36.115244 -145.596102)
		(end 34.69005 -145.596102)
		(width 0.12446)
		(layer "F.Cu")
		(net "MEMCK_N")
	)
	(segment
		(start 29.651452 -145.59788)
		(end 32.244538 -145.59788)
		(width 0.12446)
		(layer "F.Cu")
		(net "MEMCK_N")
	)
	(via
		(at 33.174178 -144.687544)
		(size 0.508)
		(drill 0.254)
		(layers "F.Cu" "B.Cu")
		(net "MEMCK_N")
	)
	(via
		(at 22.0345 -140.96111)
		(size 0.508)
		(drill 0.254)
		(layers "F.Cu" "B.Cu")
		(net "MEMCK_N")
	)
	(arc
		(start 33.280604 -146.310858)
		(mid 33.000583 -146.498055)
		(end 32.670242 -146.563842)
		(width 0.12446)
		(layer "F.Cu")
		(net "MEMCK_N")
	)
	(arc
		(start 36.725606 -145.343118)
		(mid 36.445585 -145.530315)
		(end 36.115244 -145.596102)
		(width 0.12446)
		(layer "F.Cu")
		(net "MEMCK_N")
	)
	(arc
		(start 34.69005 -145.596102)
		(mid 34.048549 -145.723593)
		(end 33.504632 -146.08683)
		(width 0.12446)
		(layer "F.Cu")
		(net "MEMCK_N")
	)
	(arc
		(start 29.651198 -146.563842)
		(mid 29.309769 -146.422417)
		(end 29.168344 -146.080988)
		(width 0.12446)
		(layer "F.Cu")
		(net "MEMCK_N")
	)
	(arc
		(start 32.78886 -145.026126)
		(mid 32.904915 -144.769673)
		(end 33.174178 -144.687544)
		(width 0.12446)
		(layer "F.Cu")
		(net "MEMCK_N")
	)
	(arc
		(start 32.244538 -145.59788)
		(mid 32.448201 -145.557279)
		(end 32.620712 -145.44167)
		(width 0.12446)
		(layer "F.Cu")
		(net "MEMCK_N")
	)
	(arc
		(start 32.626554 -145.435828)
		(mid 32.746606 -145.256392)
		(end 32.78886 -145.044668)
		(width 0.12446)
		(layer "F.Cu")
		(net "MEMCK_N")
	)
	(arc
		(start 37.951664 -144.81175)
		(mid 37.310163 -144.939241)
		(end 36.766246 -145.302478)
		(width 0.12446)
		(layer "F.Cu")
		(net "MEMCK_N")
	)
	(arc
		(start 39.299896 -144.599914)
		(mid 39.162325 -144.754371)
		(end 38.9636 -144.81175)
		(width 0.12446)
		(layer "F.Cu")
		(net "MEMCK_N")
	)
	(arc
		(start 29.168344 -146.080988)
		(mid 29.309843 -145.739379)
		(end 29.651452 -145.59788)
		(width 0.12446)
		(layer "F.Cu")
		(net "MEMCK_N")
	)
	(segment
		(start 21.87829 -141.11732)
		(end 22.0345 -140.96111)
		(width 0.12446)
		(layer "B.Cu")
		(net "MEMCK_N")
	)
	(segment
		(start 20.82165 -140.808202)
		(end 21.130768 -141.11732)
		(width 0.12446)
		(layer "B.Cu")
		(net "MEMCK_N")
	)
	(segment
		(start 21.130768 -141.11732)
		(end 21.87829 -141.11732)
		(width 0.12446)
		(layer "B.Cu")
		(net "MEMCK_N")
	)
	(segment
		(start 30.9372 -144.41297)
		(end 30.9372 -144.532858)
		(width 0.1016)
		(layer "In2.Cu")
		(net "MEMCK_N")
	)
	(segment
		(start 22.354286 -141.20876)
		(end 22.28215 -141.20876)
		(width 0.1016)
		(layer "In2.Cu")
		(net "MEMCK_N")
	)
	(segment
		(start 22.570186 -140.99286)
		(end 22.354286 -141.20876)
		(width 0.1016)
		(layer "In2.Cu")
		(net "MEMCK_N")
	)
	(segment
		(start 23.560024 -141.633448)
		(end 23.560024 -141.497558)
		(width 0.1016)
		(layer "In2.Cu")
		(net "MEMCK_N")
	)
	(segment
		(start 29.376624 -144.783556)
		(end 28.964382 -144.371314)
		(width 0.1016)
		(layer "In2.Cu")
		(net "MEMCK_N")
	)
	(segment
		(start 32.760158 -144.273524)
		(end 32.760158 -144.201134)
		(width 0.1016)
		(layer "In2.Cu")
		(net "MEMCK_N")
	)
	(segment
		(start 23.05558 -140.99286)
		(end 22.570186 -140.99286)
		(width 0.1016)
		(layer "In2.Cu")
		(net "MEMCK_N")
	)
	(segment
		(start 27.31008 -144.073626)
		(end 25.318974 -142.08252)
		(width 0.1016)
		(layer "In2.Cu")
		(net "MEMCK_N")
	)
	(segment
		(start 32.325818 -143.766794)
		(end 31.583376 -143.766794)
		(width 0.1016)
		(layer "In2.Cu")
		(net "MEMCK_N")
	)
	(segment
		(start 28.605226 -144.22247)
		(end 27.669236 -144.22247)
		(width 0.1016)
		(layer "In2.Cu")
		(net "MEMCK_N")
	)
	(segment
		(start 22.28215 -141.20876)
		(end 22.0345 -140.96111)
		(width 0.1016)
		(layer "In2.Cu")
		(net "MEMCK_N")
	)
	(segment
		(start 30.545786 -144.9324)
		(end 29.73578 -144.9324)
		(width 0.1016)
		(layer "In2.Cu")
		(net "MEMCK_N")
	)
	(segment
		(start 24.959818 -141.933676)
		(end 23.887176 -141.933676)
		(width 0.1016)
		(layer "In2.Cu")
		(net "MEMCK_N")
	)
	(arc
		(start 23.887176 -141.933676)
		(mid 23.748081 -141.906008)
		(end 23.630128 -141.82725)
		(width 0.1016)
		(layer "In2.Cu")
		(net "MEMCK_N")
	)
	(arc
		(start 28.964382 -144.371314)
		(mid 28.799614 -144.261156)
		(end 28.605226 -144.22247)
		(width 0.1016)
		(layer "In2.Cu")
		(net "MEMCK_N")
	)
	(arc
		(start 23.630128 -141.82725)
		(mid 23.578051 -141.736508)
		(end 23.560024 -141.633448)
		(width 0.1016)
		(layer "In2.Cu")
		(net "MEMCK_N")
	)
	(arc
		(start 33.174178 -144.687544)
		(mid 32.881422 -144.56628)
		(end 32.760158 -144.273524)
		(width 0.1016)
		(layer "In2.Cu")
		(net "MEMCK_N")
	)
	(arc
		(start 23.560024 -141.497558)
		(mid 23.521606 -141.304418)
		(end 23.412196 -141.140688)
		(width 0.1016)
		(layer "In2.Cu")
		(net "MEMCK_N")
	)
	(arc
		(start 27.669236 -144.22247)
		(mid 27.474847 -144.183786)
		(end 27.31008 -144.073626)
		(width 0.1016)
		(layer "In2.Cu")
		(net "MEMCK_N")
	)
	(arc
		(start 23.412196 -141.140688)
		(mid 23.24858 -141.031333)
		(end 23.05558 -140.99286)
		(width 0.1016)
		(layer "In2.Cu")
		(net "MEMCK_N")
	)
	(arc
		(start 31.583376 -143.766794)
		(mid 31.126461 -143.956055)
		(end 30.9372 -144.41297)
		(width 0.1016)
		(layer "In2.Cu")
		(net "MEMCK_N")
	)
	(arc
		(start 32.760158 -144.201134)
		(mid 32.632943 -143.894009)
		(end 32.325818 -143.766794)
		(width 0.1016)
		(layer "In2.Cu")
		(net "MEMCK_N")
	)
	(arc
		(start 29.73578 -144.9324)
		(mid 29.541391 -144.893716)
		(end 29.376624 -144.783556)
		(width 0.1016)
		(layer "In2.Cu")
		(net "MEMCK_N")
	)
	(arc
		(start 30.9372 -144.532858)
		(mid 30.823035 -144.812489)
		(end 30.545786 -144.9324)
		(width 0.1016)
		(layer "In2.Cu")
		(net "MEMCK_N")
	)
	(arc
		(start 25.318974 -142.08252)
		(mid 25.154206 -141.972362)
		(end 24.959818 -141.933676)
		(width 0.1016)
		(layer "In2.Cu")
		(net "MEMCK_N")
	)
	(segment
		(start 40.899842 -145.39976)
		(end 40.899842 -145.400014)
		(width 0.127)
		(layer "F.Cu")
		(net "MEMCKE")
	)
	(segment
		(start 17.634458 -141.361668)
		(end 18.034508 -141.761718)
		(width 0.127)
		(layer "F.Cu")
		(net "MEMCKE")
	)
	(segment
		(start 40.500046 -144.999964)
		(end 40.899842 -145.39976)
		(width 0.127)
		(layer "F.Cu")
		(net "MEMCKE")
	)
	(via
		(at 40.500046 -144.999964)
		(size 0.4572)
		(drill 0.2032)
		(layers "F.Cu" "B.Cu")
		(net "MEMCKE")
	)
	(via
		(at 18.034508 -141.761718)
		(size 0.508)
		(drill 0.254)
		(layers "F.Cu" "B.Cu")
		(net "MEMCKE")
	)
	(segment
		(start 16.599916 -144.561814)
		(end 16.834612 -144.327118)
		(width 0.0889)
		(layer "B.Cu")
		(net "MEMCKE")
	)
	(segment
		(start 13.768324 -145.23593)
		(end 13.768324 -146.051524)
		(width 0.127)
		(layer "B.Cu")
		(net "MEMCKE")
	)
	(segment
		(start 16.834612 -144.327118)
		(end 16.834612 -141.508988)
		(width 0.0889)
		(layer "B.Cu")
		(net "MEMCKE")
	)
	(segment
		(start 15.31747 -145.168366)
		(end 15.581122 -145.168366)
		(width 0.127)
		(layer "B.Cu")
		(net "MEMCKE")
	)
	(segment
		(start 13.835888 -145.168366)
		(end 14.55547 -145.168366)
		(width 0.127)
		(layer "B.Cu")
		(net "MEMCKE")
	)
	(segment
		(start 14.68247 -144.074134)
		(end 14.80947 -143.947134)
		(width 0.127)
		(layer "B.Cu")
		(net "MEMCKE")
	)
	(segment
		(start 14.80947 -143.947134)
		(end 15.06347 -143.947134)
		(width 0.127)
		(layer "B.Cu")
		(net "MEMCKE")
	)
	(segment
		(start 16.187674 -144.561814)
		(end 16.599916 -144.561814)
		(width 0.0889)
		(layer "B.Cu")
		(net "MEMCKE")
	)
	(segment
		(start 17.634458 -141.361668)
		(end 18.034508 -141.761718)
		(width 0.0889)
		(layer "B.Cu")
		(net "MEMCKE")
	)
	(segment
		(start 15.581122 -145.168366)
		(end 16.0147 -144.734788)
		(width 0.127)
		(layer "B.Cu")
		(net "MEMCKE")
	)
	(segment
		(start 16.834612 -141.508988)
		(end 16.981932 -141.361668)
		(width 0.0889)
		(layer "B.Cu")
		(net "MEMCKE")
	)
	(segment
		(start 13.768324 -146.051524)
		(end 13.9827 -146.2659)
		(width 0.127)
		(layer "B.Cu")
		(net "MEMCKE")
	)
	(segment
		(start 16.0147 -144.734788)
		(end 16.187674 -144.561814)
		(width 0.0889)
		(layer "B.Cu")
		(net "MEMCKE")
	)
	(segment
		(start 15.19047 -144.074134)
		(end 15.19047 -145.041366)
		(width 0.127)
		(layer "B.Cu")
		(net "MEMCKE")
	)
	(segment
		(start 14.68247 -145.041366)
		(end 14.68247 -144.074134)
		(width 0.127)
		(layer "B.Cu")
		(net "MEMCKE")
	)
	(segment
		(start 15.06347 -143.947134)
		(end 15.19047 -144.074134)
		(width 0.127)
		(layer "B.Cu")
		(net "MEMCKE")
	)
	(segment
		(start 14.55547 -145.168366)
		(end 14.68247 -145.041366)
		(width 0.127)
		(layer "B.Cu")
		(net "MEMCKE")
	)
	(segment
		(start 13.768324 -145.23593)
		(end 13.835888 -145.168366)
		(width 0.127)
		(layer "B.Cu")
		(net "MEMCKE")
	)
	(segment
		(start 16.981932 -141.361668)
		(end 17.634458 -141.361668)
		(width 0.0889)
		(layer "B.Cu")
		(net "MEMCKE")
	)
	(segment
		(start 15.19047 -145.041366)
		(end 15.31747 -145.168366)
		(width 0.127)
		(layer "B.Cu")
		(net "MEMCKE")
	)
	(segment
		(start 33.708086 -144.028668)
		(end 33.581086 -143.901668)
		(width 0.127)
		(layer "In5.Cu")
		(net "MEMCKE")
	)
	(segment
		(start 21.569172 -142.16126)
		(end 21.480272 -142.07236)
		(width 0.0889)
		(layer "In5.Cu")
		(net "MEMCKE")
	)
	(segment
		(start 29.2989 -144.78)
		(end 28.676346 -144.157446)
		(width 0.127)
		(layer "In5.Cu")
		(net "MEMCKE")
	)
	(segment
		(start 34.343086 -143.901668)
		(end 34.216086 -144.028668)
		(width 0.127)
		(layer "In5.Cu")
		(net "MEMCKE")
	)
	(segment
		(start 32.649668 -144.118076)
		(end 31.66745 -144.118076)
		(width 0.127)
		(layer "In5.Cu")
		(net "MEMCKE")
	)
	(segment
		(start 21.124672 -141.65072)
		(end 21.124672 -142.07236)
		(width 0.0889)
		(layer "In5.Cu")
		(net "MEMCKE")
	)
	(segment
		(start 30.36824 -144.653)
		(end 30.24124 -144.78)
		(width 0.127)
		(layer "In5.Cu")
		(net "MEMCKE")
	)
	(segment
		(start 33.581086 -143.901668)
		(end 32.866076 -143.901668)
		(width 0.127)
		(layer "In5.Cu")
		(net "MEMCKE")
	)
	(segment
		(start 31.03245 -144.245076)
		(end 30.90545 -144.118076)
		(width 0.127)
		(layer "In5.Cu")
		(net "MEMCKE")
	)
	(segment
		(start 31.15945 -145.161)
		(end 31.03245 -145.034)
		(width 0.127)
		(layer "In5.Cu")
		(net "MEMCKE")
	)
	(segment
		(start 31.54045 -145.034)
		(end 31.41345 -145.161)
		(width 0.127)
		(layer "In5.Cu")
		(net "MEMCKE")
	)
	(segment
		(start 23.885652 -141.959076)
		(end 23.683468 -142.16126)
		(width 0.127)
		(layer "In5.Cu")
		(net "MEMCKE")
	)
	(segment
		(start 21.480272 -142.07236)
		(end 21.480272 -141.65072)
		(width 0.0889)
		(layer "In5.Cu")
		(net "MEMCKE")
	)
	(segment
		(start 31.54045 -144.245076)
		(end 31.54045 -145.034)
		(width 0.127)
		(layer "In5.Cu")
		(net "MEMCKE")
	)
	(segment
		(start 34.216086 -144.58696)
		(end 34.089086 -144.71396)
		(width 0.127)
		(layer "In5.Cu")
		(net "MEMCKE")
	)
	(segment
		(start 33.708086 -144.58696)
		(end 33.708086 -144.028668)
		(width 0.127)
		(layer "In5.Cu")
		(net "MEMCKE")
	)
	(segment
		(start 34.216086 -144.028668)
		(end 34.216086 -144.58696)
		(width 0.127)
		(layer "In5.Cu")
		(net "MEMCKE")
	)
	(segment
		(start 28.097734 -144.157446)
		(end 25.899364 -141.959076)
		(width 0.127)
		(layer "In5.Cu")
		(net "MEMCKE")
	)
	(segment
		(start 30.90545 -144.118076)
		(end 30.501844 -144.118076)
		(width 0.127)
		(layer "In5.Cu")
		(net "MEMCKE")
	)
	(segment
		(start 40.106346 -145.393664)
		(end 39.228776 -145.393664)
		(width 0.127)
		(layer "In5.Cu")
		(net "MEMCKE")
	)
	(segment
		(start 31.41345 -145.161)
		(end 31.15945 -145.161)
		(width 0.127)
		(layer "In5.Cu")
		(net "MEMCKE")
	)
	(segment
		(start 21.213572 -141.56182)
		(end 21.124672 -141.65072)
		(width 0.0889)
		(layer "In5.Cu")
		(net "MEMCKE")
	)
	(segment
		(start 21.124672 -142.07236)
		(end 21.035772 -142.16126)
		(width 0.0889)
		(layer "In5.Cu")
		(net "MEMCKE")
	)
	(segment
		(start 31.66745 -144.118076)
		(end 31.54045 -144.245076)
		(width 0.127)
		(layer "In5.Cu")
		(net "MEMCKE")
	)
	(segment
		(start 21.391372 -141.56182)
		(end 21.213572 -141.56182)
		(width 0.0889)
		(layer "In5.Cu")
		(net "MEMCKE")
	)
	(segment
		(start 21.035772 -142.16126)
		(end 19.07032 -142.16126)
		(width 0.0889)
		(layer "In5.Cu")
		(net "MEMCKE")
	)
	(segment
		(start 28.676346 -144.157446)
		(end 28.097734 -144.157446)
		(width 0.127)
		(layer "In5.Cu")
		(net "MEMCKE")
	)
	(segment
		(start 37.73678 -143.901668)
		(end 34.343086 -143.901668)
		(width 0.127)
		(layer "In5.Cu")
		(net "MEMCKE")
	)
	(segment
		(start 39.228776 -145.393664)
		(end 37.73678 -143.901668)
		(width 0.127)
		(layer "In5.Cu")
		(net "MEMCKE")
	)
	(segment
		(start 21.480272 -141.65072)
		(end 21.391372 -141.56182)
		(width 0.0889)
		(layer "In5.Cu")
		(net "MEMCKE")
	)
	(segment
		(start 23.683468 -142.16126)
		(end 21.569172 -142.16126)
		(width 0.0889)
		(layer "In5.Cu")
		(net "MEMCKE")
	)
	(segment
		(start 18.59534 -141.68628)
		(end 18.109946 -141.68628)
		(width 0.0889)
		(layer "In5.Cu")
		(net "MEMCKE")
	)
	(segment
		(start 32.866076 -143.901668)
		(end 32.649668 -144.118076)
		(width 0.127)
		(layer "In5.Cu")
		(net "MEMCKE")
	)
	(segment
		(start 18.109946 -141.68628)
		(end 18.034508 -141.761718)
		(width 0.0889)
		(layer "In5.Cu")
		(net "MEMCKE")
	)
	(segment
		(start 19.07032 -142.16126)
		(end 18.59534 -141.68628)
		(width 0.0889)
		(layer "In5.Cu")
		(net "MEMCKE")
	)
	(segment
		(start 30.36824 -144.25168)
		(end 30.36824 -144.653)
		(width 0.127)
		(layer "In5.Cu")
		(net "MEMCKE")
	)
	(segment
		(start 31.03245 -145.034)
		(end 31.03245 -144.245076)
		(width 0.127)
		(layer "In5.Cu")
		(net "MEMCKE")
	)
	(segment
		(start 30.501844 -144.118076)
		(end 30.36824 -144.25168)
		(width 0.127)
		(layer "In5.Cu")
		(net "MEMCKE")
	)
	(segment
		(start 33.835086 -144.71396)
		(end 33.708086 -144.58696)
		(width 0.127)
		(layer "In5.Cu")
		(net "MEMCKE")
	)
	(segment
		(start 30.24124 -144.78)
		(end 29.2989 -144.78)
		(width 0.127)
		(layer "In5.Cu")
		(net "MEMCKE")
	)
	(segment
		(start 34.089086 -144.71396)
		(end 33.835086 -144.71396)
		(width 0.127)
		(layer "In5.Cu")
		(net "MEMCKE")
	)
	(segment
		(start 25.899364 -141.959076)
		(end 23.885652 -141.959076)
		(width 0.127)
		(layer "In5.Cu")
		(net "MEMCKE")
	)
	(segment
		(start 40.500046 -144.999964)
		(end 40.106346 -145.393664)
		(width 0.127)
		(layer "In5.Cu")
		(net "MEMCKE")
	)
	(segment
		(start 22.821646 -140.148564)
		(end 23.87346 -140.148564)
		(width 0.127)
		(layer "F.Cu")
		(net "MEMCASN")
	)
	(segment
		(start 26.59888 -142.45082)
		(end 24.638 -142.45082)
		(width 0.127)
		(layer "F.Cu")
		(net "MEMCASN")
	)
	(segment
		(start 21.225764 -139.361164)
		(end 22.034246 -139.361164)
		(width 0.127)
		(layer "F.Cu")
		(net "MEMCASN")
	)
	(segment
		(start 24.654002 -144.00784)
		(end 24.908002 -144.00784)
		(width 0.127)
		(layer "F.Cu")
		(net "MEMCASN")
	)
	(segment
		(start 24.68626 -141.81582)
		(end 24.81326 -141.94282)
		(width 0.127)
		(layer "F.Cu")
		(net "MEMCASN")
	)
	(segment
		(start 26.59888 -141.94282)
		(end 26.72588 -142.06982)
		(width 0.127)
		(layer "F.Cu")
		(net "MEMCASN")
	)
	(segment
		(start 24.81326 -141.43482)
		(end 24.68626 -141.56182)
		(width 0.127)
		(layer "F.Cu")
		(net "MEMCASN")
	)
	(segment
		(start 26.72588 -142.06982)
		(end 26.72588 -142.32382)
		(width 0.127)
		(layer "F.Cu")
		(net "MEMCASN")
	)
	(segment
		(start 20.5994 -133.9596)
		(end 20.5994 -138.7348)
		(width 0.127)
		(layer "F.Cu")
		(net "MEMCASN")
	)
	(segment
		(start 22.034246 -139.361164)
		(end 22.43455 -139.761468)
		(width 0.127)
		(layer "F.Cu")
		(net "MEMCASN")
	)
	(segment
		(start 26.051002 -143.88084)
		(end 26.051002 -143.08582)
		(width 0.127)
		(layer "F.Cu")
		(net "MEMCASN")
	)
	(segment
		(start 24.908002 -144.00784)
		(end 25.035002 -143.88084)
		(width 0.127)
		(layer "F.Cu")
		(net "MEMCASN")
	)
	(segment
		(start 24.81326 -141.94282)
		(end 26.59888 -141.94282)
		(width 0.127)
		(layer "F.Cu")
		(net "MEMCASN")
	)
	(segment
		(start 24.68626 -141.56182)
		(end 24.68626 -141.81582)
		(width 0.127)
		(layer "F.Cu")
		(net "MEMCASN")
	)
	(segment
		(start 25.162002 -142.95882)
		(end 25.416002 -142.95882)
		(width 0.127)
		(layer "F.Cu")
		(net "MEMCASN")
	)
	(segment
		(start 34.772346 -144.02054)
		(end 36.945824 -144.02054)
		(width 0.127)
		(layer "F.Cu")
		(net "MEMCASN")
	)
	(segment
		(start 24.527002 -143.88084)
		(end 24.654002 -144.00784)
		(width 0.127)
		(layer "F.Cu")
		(net "MEMCASN")
	)
	(segment
		(start 24.083264 -140.358368)
		(end 25.89784 -140.358368)
		(width 0.127)
		(layer "F.Cu")
		(net "MEMCASN")
	)
	(segment
		(start 25.543002 -143.88084)
		(end 25.670002 -144.00784)
		(width 0.127)
		(layer "F.Cu")
		(net "MEMCASN")
	)
	(segment
		(start 25.89784 -141.43482)
		(end 24.81326 -141.43482)
		(width 0.127)
		(layer "F.Cu")
		(net "MEMCASN")
	)
	(segment
		(start 26.178002 -142.95882)
		(end 33.710626 -142.95882)
		(width 0.127)
		(layer "F.Cu")
		(net "MEMCASN")
	)
	(segment
		(start 21.2852 -131.26593)
		(end 21.2852 -133.2738)
		(width 0.127)
		(layer "F.Cu")
		(net "MEMCASN")
	)
	(segment
		(start 25.416002 -142.95882)
		(end 25.543002 -143.08582)
		(width 0.127)
		(layer "F.Cu")
		(net "MEMCASN")
	)
	(segment
		(start 37.0586 -143.907764)
		(end 39.1922 -143.907764)
		(width 0.127)
		(layer "F.Cu")
		(net "MEMCASN")
	)
	(segment
		(start 24.527002 -142.561818)
		(end 24.527002 -143.88084)
		(width 0.127)
		(layer "F.Cu")
		(net "MEMCASN")
	)
	(segment
		(start 24.638 -142.45082)
		(end 24.527002 -142.561818)
		(width 0.127)
		(layer "F.Cu")
		(net "MEMCASN")
	)
	(segment
		(start 26.02484 -141.30782)
		(end 25.89784 -141.43482)
		(width 0.127)
		(layer "F.Cu")
		(net "MEMCASN")
	)
	(segment
		(start 25.543002 -143.08582)
		(end 25.543002 -143.88084)
		(width 0.127)
		(layer "F.Cu")
		(net "MEMCASN")
	)
	(segment
		(start 21.2852 -133.2738)
		(end 20.5994 -133.9596)
		(width 0.127)
		(layer "F.Cu")
		(net "MEMCASN")
	)
	(segment
		(start 26.02484 -140.485368)
		(end 26.02484 -141.30782)
		(width 0.127)
		(layer "F.Cu")
		(net "MEMCASN")
	)
	(segment
		(start 25.035002 -143.88084)
		(end 25.035002 -143.08582)
		(width 0.127)
		(layer "F.Cu")
		(net "MEMCASN")
	)
	(segment
		(start 36.945824 -144.02054)
		(end 37.0586 -143.907764)
		(width 0.127)
		(layer "F.Cu")
		(net "MEMCASN")
	)
	(segment
		(start 20.582128 -130.562858)
		(end 21.2852 -131.26593)
		(width 0.127)
		(layer "F.Cu")
		(net "MEMCASN")
	)
	(segment
		(start 20.582128 -130.562858)
		(end 20.582128 -129.527808)
		(width 0.127)
		(layer "F.Cu")
		(net "MEMCASN")
	)
	(segment
		(start 20.5994 -138.7348)
		(end 21.225764 -139.361164)
		(width 0.127)
		(layer "F.Cu")
		(net "MEMCASN")
	)
	(segment
		(start 23.87346 -140.148564)
		(end 24.083264 -140.358368)
		(width 0.127)
		(layer "F.Cu")
		(net "MEMCASN")
	)
	(segment
		(start 25.035002 -143.08582)
		(end 25.162002 -142.95882)
		(width 0.127)
		(layer "F.Cu")
		(net "MEMCASN")
	)
	(segment
		(start 20.582128 -129.527808)
		(end 20.591272 -129.518664)
		(width 0.127)
		(layer "F.Cu")
		(net "MEMCASN")
	)
	(segment
		(start 25.924002 -144.00784)
		(end 26.051002 -143.88084)
		(width 0.127)
		(layer "F.Cu")
		(net "MEMCASN")
	)
	(segment
		(start 39.1922 -143.907764)
		(end 39.299896 -143.800068)
		(width 0.127)
		(layer "F.Cu")
		(net "MEMCASN")
	)
	(segment
		(start 25.670002 -144.00784)
		(end 25.924002 -144.00784)
		(width 0.127)
		(layer "F.Cu")
		(net "MEMCASN")
	)
	(segment
		(start 25.89784 -140.358368)
		(end 26.02484 -140.485368)
		(width 0.127)
		(layer "F.Cu")
		(net "MEMCASN")
	)
	(segment
		(start 33.710626 -142.95882)
		(end 34.772346 -144.02054)
		(width 0.127)
		(layer "F.Cu")
		(net "MEMCASN")
	)
	(segment
		(start 26.72588 -142.32382)
		(end 26.59888 -142.45082)
		(width 0.127)
		(layer "F.Cu")
		(net "MEMCASN")
	)
	(segment
		(start 26.051002 -143.08582)
		(end 26.178002 -142.95882)
		(width 0.127)
		(layer "F.Cu")
		(net "MEMCASN")
	)
	(segment
		(start 22.43455 -139.761468)
		(end 22.821646 -140.148564)
		(width 0.127)
		(layer "F.Cu")
		(net "MEMCASN")
	)
	(segment
		(start 22.85365 -139.380722)
		(end 24.274272 -139.380722)
		(width 0.127)
		(layer "F.Cu")
		(net "MEMBA_1")
	)
	(segment
		(start 40.899334 -143.800068)
		(end 40.899842 -143.800068)
		(width 0.1016)
		(layer "F.Cu")
		(net "MEMBA_1")
	)
	(segment
		(start 33.921192 -142.45082)
		(end 34.982912 -143.51254)
		(width 0.127)
		(layer "F.Cu")
		(net "MEMBA_1")
	)
	(segment
		(start 27.2796 -141.72692)
		(end 27.2796 -142.32382)
		(width 0.127)
		(layer "F.Cu")
		(net "MEMBA_1")
	)
	(segment
		(start 40.615616 -143.516604)
		(end 40.899334 -143.800068)
		(width 0.1016)
		(layer "F.Cu")
		(net "MEMBA_1")
	)
	(segment
		(start 27.2796 -142.32382)
		(end 27.4066 -142.45082)
		(width 0.127)
		(layer "F.Cu")
		(net "MEMBA_1")
	)
	(segment
		(start 27.4066 -142.45082)
		(end 33.921192 -142.45082)
		(width 0.127)
		(layer "F.Cu")
		(net "MEMBA_1")
	)
	(segment
		(start 34.982912 -143.51254)
		(end 36.401502 -143.51254)
		(width 0.127)
		(layer "F.Cu")
		(net "MEMBA_1")
	)
	(segment
		(start 36.514278 -143.399764)
		(end 40.33393 -143.399764)
		(width 0.127)
		(layer "F.Cu")
		(net "MEMBA_1")
	)
	(segment
		(start 25.682702 -131.909058)
		(end 25.682702 -130.902202)
		(width 0.127)
		(layer "F.Cu")
		(net "MEMBA_1")
	)
	(segment
		(start 22.0345 -138.561572)
		(end 22.43455 -138.961622)
		(width 0.127)
		(layer "F.Cu")
		(net "MEMBA_1")
	)
	(segment
		(start 22.43455 -138.961622)
		(end 22.85365 -139.380722)
		(width 0.127)
		(layer "F.Cu")
		(net "MEMBA_1")
	)
	(segment
		(start 36.401502 -143.51254)
		(end 36.514278 -143.399764)
		(width 0.127)
		(layer "F.Cu")
		(net "MEMBA_1")
	)
	(segment
		(start 31.1404 -141.59992)
		(end 27.4066 -141.59992)
		(width 0.127)
		(layer "F.Cu")
		(net "MEMBA_1")
	)
	(segment
		(start 24.274272 -139.380722)
		(end 26.162 -137.492994)
		(width 0.127)
		(layer "F.Cu")
		(net "MEMBA_1")
	)
	(segment
		(start 26.162 -137.492994)
		(end 26.162 -132.388356)
		(width 0.127)
		(layer "F.Cu")
		(net "MEMBA_1")
	)
	(segment
		(start 26.162 -132.388356)
		(end 25.682702 -131.909058)
		(width 0.127)
		(layer "F.Cu")
		(net "MEMBA_1")
	)
	(segment
		(start 27.4066 -141.59992)
		(end 27.2796 -141.72692)
		(width 0.127)
		(layer "F.Cu")
		(net "MEMBA_1")
	)
	(segment
		(start 25.682702 -130.902202)
		(end 25.6794 -130.8989)
		(width 0.127)
		(layer "F.Cu")
		(net "MEMBA_1")
	)
	(via
		(at 31.1404 -141.59992)
		(size 0.508)
		(drill 0.254)
		(layers "F.Cu" "B.Cu")
		(net "MEMBA_1")
	)
	(via
		(at 22.0345 -138.561572)
		(size 0.508)
		(drill 0.254)
		(layers "F.Cu" "B.Cu")
		(net "MEMBA_1")
	)
	(arc
		(start 40.33393 -143.399764)
		(mid 40.486411 -143.43013)
		(end 40.615616 -143.516604)
		(width 0.1016)
		(layer "F.Cu")
		(net "MEMBA_1")
	)
	(segment
		(start 22.4536 -138.980672)
		(end 22.0345 -138.561572)
		(width 0.127)
		(layer "In2.Cu")
		(net "MEMBA_1")
	)
	(segment
		(start 23.446232 -138.542522)
		(end 23.008082 -138.980672)
		(width 0.127)
		(layer "In2.Cu")
		(net "MEMBA_1")
	)
	(segment
		(start 26.090626 -138.942318)
		(end 24.569674 -138.942318)
		(width 0.127)
		(layer "In2.Cu")
		(net "MEMBA_1")
	)
	(segment
		(start 27.27833 -139.53363)
		(end 26.681938 -139.53363)
		(width 0.127)
		(layer "In2.Cu")
		(net "MEMBA_1")
	)
	(segment
		(start 30.60192 -141.06144)
		(end 28.80614 -141.06144)
		(width 0.126746)
		(layer "In2.Cu")
		(net "MEMBA_1")
	)
	(segment
		(start 31.1404 -141.59992)
		(end 30.60192 -141.06144)
		(width 0.126746)
		(layer "In2.Cu")
		(net "MEMBA_1")
	)
	(segment
		(start 26.681938 -139.53363)
		(end 26.090626 -138.942318)
		(width 0.127)
		(layer "In2.Cu")
		(net "MEMBA_1")
	)
	(segment
		(start 23.008082 -138.980672)
		(end 22.4536 -138.980672)
		(width 0.127)
		(layer "In2.Cu")
		(net "MEMBA_1")
	)
	(segment
		(start 24.169878 -138.542522)
		(end 23.446232 -138.542522)
		(width 0.127)
		(layer "In2.Cu")
		(net "MEMBA_1")
	)
	(segment
		(start 28.80614 -141.06144)
		(end 27.27833 -139.53363)
		(width 0.126746)
		(layer "In2.Cu")
		(net "MEMBA_1")
	)
	(segment
		(start 24.569674 -138.942318)
		(end 24.169878 -138.542522)
		(width 0.127)
		(layer "In2.Cu")
		(net "MEMBA_1")
	)
	(segment
		(start 14.07541 -137.694416)
		(end 13.807186 -137.426192)
		(width 0.127)
		(layer "F.Cu")
		(net "MEMBA_0")
	)
	(segment
		(start 13.807186 -137.426192)
		(end 10.500106 -137.426192)
		(width 0.127)
		(layer "F.Cu")
		(net "MEMBA_0")
	)
	(segment
		(start 16.130778 -138.561572)
		(end 15.893542 -138.324336)
		(width 0.127)
		(layer "F.Cu")
		(net "MEMBA_0")
	)
	(segment
		(start 10.500106 -137.426192)
		(end 10.352024 -137.574274)
		(width 0.127)
		(layer "F.Cu")
		(net "MEMBA_0")
	)
	(segment
		(start 15.073376 -137.32129)
		(end 14.819376 -137.32129)
		(width 0.127)
		(layer "F.Cu")
		(net "MEMBA_0")
	)
	(segment
		(start 10.350754 -138.145774)
		(end 9.349232 -138.145774)
		(width 0.127)
		(layer "F.Cu")
		(net "MEMBA_0")
	)
	(segment
		(start 14.565376 -138.324336)
		(end 14.20368 -138.324336)
		(width 0.127)
		(layer "F.Cu")
		(net "MEMBA_0")
	)
	(segment
		(start 15.200376 -138.197336)
		(end 15.200376 -137.44829)
		(width 0.127)
		(layer "F.Cu")
		(net "MEMBA_0")
	)
	(segment
		(start 15.200376 -137.44829)
		(end 15.073376 -137.32129)
		(width 0.127)
		(layer "F.Cu")
		(net "MEMBA_0")
	)
	(segment
		(start 15.327376 -138.324336)
		(end 15.200376 -138.197336)
		(width 0.127)
		(layer "F.Cu")
		(net "MEMBA_0")
	)
	(segment
		(start 18.034508 -138.561572)
		(end 16.130778 -138.561572)
		(width 0.127)
		(layer "F.Cu")
		(net "MEMBA_0")
	)
	(segment
		(start 15.893542 -138.324336)
		(end 15.327376 -138.324336)
		(width 0.127)
		(layer "F.Cu")
		(net "MEMBA_0")
	)
	(segment
		(start 14.692376 -138.197336)
		(end 14.565376 -138.324336)
		(width 0.127)
		(layer "F.Cu")
		(net "MEMBA_0")
	)
	(segment
		(start 14.692376 -137.44829)
		(end 14.692376 -138.197336)
		(width 0.127)
		(layer "F.Cu")
		(net "MEMBA_0")
	)
	(segment
		(start 10.352024 -137.574274)
		(end 10.352024 -138.144504)
		(width 0.127)
		(layer "F.Cu")
		(net "MEMBA_0")
	)
	(segment
		(start 14.819376 -137.32129)
		(end 14.692376 -137.44829)
		(width 0.127)
		(layer "F.Cu")
		(net "MEMBA_0")
	)
	(segment
		(start 10.352024 -138.144504)
		(end 10.350754 -138.145774)
		(width 0.127)
		(layer "F.Cu")
		(net "MEMBA_0")
	)
	(segment
		(start 14.07541 -138.196066)
		(end 14.07541 -137.694416)
		(width 0.127)
		(layer "F.Cu")
		(net "MEMBA_0")
	)
	(segment
		(start 43.299888 -144.599914)
		(end 42.900092 -144.200118)
		(width 0.127)
		(layer "F.Cu")
		(net "MEMBA_0")
	)
	(segment
		(start 14.20368 -138.324336)
		(end 14.07541 -138.196066)
		(width 0.127)
		(layer "F.Cu")
		(net "MEMBA_0")
	)
	(segment
		(start 17.634458 -138.961622)
		(end 18.034508 -138.561572)
		(width 0.127)
		(layer "F.Cu")
		(net "MEMBA_0")
	)
	(via
		(at 18.034508 -138.561572)
		(size 0.508)
		(drill 0.254)
		(layers "F.Cu" "B.Cu")
		(net "MEMBA_0")
	)
	(via
		(at 42.900092 -144.200118)
		(size 0.4572)
		(drill 0.2032)
		(layers "F.Cu" "B.Cu")
		(net "MEMBA_0")
	)
	(segment
		(start 39.551356 -141.271244)
		(end 38.309804 -140.029692)
		(width 0.127)
		(layer "In5.Cu")
		(net "MEMBA_0")
	)
	(segment
		(start 24.323802 -137.03808)
		(end 23.827994 -136.542272)
		(width 0.127)
		(layer "In5.Cu")
		(net "MEMBA_0")
	)
	(segment
		(start 41.02862 -142.138654)
		(end 40.723058 -141.833092)
		(width 0.127)
		(layer "In5.Cu")
		(net "MEMBA_0")
	)
	(segment
		(start 42.49293 -143.501364)
		(end 42.49293 -143.30426)
		(width 0.127)
		(layer "In5.Cu")
		(net "MEMBA_0")
	)
	(segment
		(start 32.818832 -140.029692)
		(end 32.20974 -139.4206)
		(width 0.127)
		(layer "In5.Cu")
		(net "MEMBA_0")
	)
	(segment
		(start 18.240502 -138.355578)
		(end 18.034508 -138.561572)
		(width 0.0889)
		(layer "In5.Cu")
		(net "MEMBA_0")
	)
	(segment
		(start 28.995624 -138.2141)
		(end 27.819604 -137.03808)
		(width 0.127)
		(layer "In5.Cu")
		(net "MEMBA_0")
	)
	(segment
		(start 41.463214 -142.206218)
		(end 41.193466 -142.206218)
		(width 0.127)
		(layer "In5.Cu")
		(net "MEMBA_0")
	)
	(segment
		(start 19.383502 -138.141964)
		(end 18.754344 -138.141964)
		(width 0.0889)
		(layer "In5.Cu")
		(net "MEMBA_0")
	)
	(segment
		(start 23.827994 -136.542272)
		(end 20.983194 -136.542272)
		(width 0.127)
		(layer "In5.Cu")
		(net "MEMBA_0")
	)
	(segment
		(start 18.240502 -138.354816)
		(end 18.240502 -138.355578)
		(width 0.0889)
		(layer "In5.Cu")
		(net "MEMBA_0")
	)
	(segment
		(start 41.835324 -142.894558)
		(end 41.81983 -142.879064)
		(width 0.127)
		(layer "In5.Cu")
		(net "MEMBA_0")
	)
	(segment
		(start 41.70553 -142.60322)
		(end 41.693592 -142.516606)
		(width 0.127)
		(layer "In5.Cu")
		(net "MEMBA_0")
	)
	(segment
		(start 20.983194 -136.542272)
		(end 19.383502 -138.141964)
		(width 0.127)
		(layer "In5.Cu")
		(net "MEMBA_0")
	)
	(segment
		(start 41.193466 -142.206218)
		(end 41.19118 -142.205964)
		(width 0.127)
		(layer "In5.Cu")
		(net "MEMBA_0")
	)
	(segment
		(start 32.20974 -139.4206)
		(end 31.364936 -139.4206)
		(width 0.127)
		(layer "In5.Cu")
		(net "MEMBA_0")
	)
	(segment
		(start 38.309804 -140.029692)
		(end 32.818832 -140.029692)
		(width 0.127)
		(layer "In5.Cu")
		(net "MEMBA_0")
	)
	(segment
		(start 31.364936 -139.4206)
		(end 30.158436 -138.2141)
		(width 0.127)
		(layer "In5.Cu")
		(net "MEMBA_0")
	)
	(segment
		(start 27.819604 -137.03808)
		(end 24.323802 -137.03808)
		(width 0.127)
		(layer "In5.Cu")
		(net "MEMBA_0")
	)
	(segment
		(start 30.158436 -138.2141)
		(end 28.995624 -138.2141)
		(width 0.127)
		(layer "In5.Cu")
		(net "MEMBA_0")
	)
	(segment
		(start 40.022526 -141.51356)
		(end 40.013128 -141.503908)
		(width 0.127)
		(layer "In5.Cu")
		(net "MEMBA_0")
	)
	(segment
		(start 41.693592 -142.436596)
		(end 41.463214 -142.206218)
		(width 0.127)
		(layer "In5.Cu")
		(net "MEMBA_0")
	)
	(segment
		(start 41.693592 -142.516606)
		(end 41.693592 -142.436596)
		(width 0.127)
		(layer "In5.Cu")
		(net "MEMBA_0")
	)
	(segment
		(start 42.900092 -144.200118)
		(end 42.699178 -143.999204)
		(width 0.127)
		(layer "In5.Cu")
		(net "MEMBA_0")
	)
	(arc
		(start 42.07383 -142.993364)
		(mid 41.944746 -142.967688)
		(end 41.835324 -142.894558)
		(width 0.127)
		(layer "In5.Cu")
		(net "MEMBA_0")
	)
	(arc
		(start 39.776146 -141.364208)
		(mid 39.654518 -141.34005)
		(end 39.551356 -141.271244)
		(width 0.127)
		(layer "In5.Cu")
		(net "MEMBA_0")
	)
	(arc
		(start 40.723058 -141.833092)
		(mid 40.585073 -141.763084)
		(end 40.43553 -141.723364)
		(width 0.127)
		(layer "In5.Cu")
		(net "MEMBA_0")
	)
	(arc
		(start 42.699178 -143.999204)
		(mid 42.546559 -143.770793)
		(end 42.49293 -143.501364)
		(width 0.127)
		(layer "In5.Cu")
		(net "MEMBA_0")
	)
	(arc
		(start 40.43553 -141.723364)
		(mid 40.212352 -141.651291)
		(end 40.022526 -141.51356)
		(width 0.127)
		(layer "In5.Cu")
		(net "MEMBA_0")
	)
	(arc
		(start 18.754344 -138.141964)
		(mid 18.47625 -138.19728)
		(end 18.240502 -138.354816)
		(width 0.0889)
		(layer "In5.Cu")
		(net "MEMBA_0")
	)
	(arc
		(start 42.49293 -143.30426)
		(mid 42.473131 -143.204726)
		(end 42.41673 -143.120364)
		(width 0.127)
		(layer "In5.Cu")
		(net "MEMBA_0")
	)
	(arc
		(start 41.81983 -142.879064)
		(mid 41.735213 -142.75252)
		(end 41.70553 -142.60322)
		(width 0.127)
		(layer "In5.Cu")
		(net "MEMBA_0")
	)
	(arc
		(start 42.41673 -143.120364)
		(mid 42.256656 -143.026156)
		(end 42.07383 -142.993364)
		(width 0.127)
		(layer "In5.Cu")
		(net "MEMBA_0")
	)
	(arc
		(start 40.013128 -141.503908)
		(mid 39.903461 -141.419094)
		(end 39.776146 -141.364208)
		(width 0.127)
		(layer "In5.Cu")
		(net "MEMBA_0")
	)
	(arc
		(start 41.19118 -142.205964)
		(mid 41.103213 -142.188466)
		(end 41.02862 -142.138654)
		(width 0.127)
		(layer "In5.Cu")
		(net "MEMBA_0")
	)
	(segment
		(start 21.2344 -136.961626)
		(end 21.63445 -137.361676)
		(width 0.127)
		(layer "F.Cu")
		(net "MEMA_9")
	)
	(segment
		(start 40.500046 -140.999972)
		(end 40.899842 -141.399768)
		(width 0.127)
		(layer "F.Cu")
		(net "MEMA_9")
	)
	(segment
		(start 40.899842 -141.399768)
		(end 40.899842 -141.400022)
		(width 0.127)
		(layer "F.Cu")
		(net "MEMA_9")
	)
	(via
		(at 40.500046 -140.999972)
		(size 0.4572)
		(drill 0.2032)
		(layers "F.Cu" "B.Cu")
		(net "MEMA_9")
	)
	(via
		(at 21.2344 -136.961626)
		(size 0.508)
		(drill 0.254)
		(layers "F.Cu" "B.Cu")
		(net "MEMA_9")
	)
	(segment
		(start 21.493988 -133.028436)
		(end 21.493988 -134.435088)
		(width 0.127)
		(layer "B.Cu")
		(net "MEMA_9")
	)
	(segment
		(start 20.561046 -134.689088)
		(end 20.561046 -134.943088)
		(width 0.127)
		(layer "B.Cu")
		(net "MEMA_9")
	)
	(segment
		(start 20.561046 -134.943088)
		(end 20.688046 -135.070088)
		(width 0.127)
		(layer "B.Cu")
		(net "MEMA_9")
	)
	(segment
		(start 21.493988 -134.435088)
		(end 21.366988 -134.562088)
		(width 0.127)
		(layer "B.Cu")
		(net "MEMA_9")
	)
	(segment
		(start 21.366988 -135.070088)
		(end 21.493988 -135.197088)
		(width 0.127)
		(layer "B.Cu")
		(net "MEMA_9")
	)
	(segment
		(start 21.493988 -136.213088)
		(end 21.493988 -136.702038)
		(width 0.127)
		(layer "B.Cu")
		(net "MEMA_9")
	)
	(segment
		(start 20.688046 -135.578088)
		(end 20.561046 -135.705088)
		(width 0.127)
		(layer "B.Cu")
		(net "MEMA_9")
	)
	(segment
		(start 21.493988 -136.702038)
		(end 21.2344 -136.961626)
		(width 0.127)
		(layer "B.Cu")
		(net "MEMA_9")
	)
	(segment
		(start 20.871688 -130.753358)
		(end 21.280628 -131.162298)
		(width 0.127)
		(layer "B.Cu")
		(net "MEMA_9")
	)
	(segment
		(start 20.688046 -134.562088)
		(end 20.561046 -134.689088)
		(width 0.127)
		(layer "B.Cu")
		(net "MEMA_9")
	)
	(segment
		(start 20.688046 -135.070088)
		(end 21.366988 -135.070088)
		(width 0.127)
		(layer "B.Cu")
		(net "MEMA_9")
	)
	(segment
		(start 21.280628 -131.162298)
		(end 21.280628 -132.815076)
		(width 0.127)
		(layer "B.Cu")
		(net "MEMA_9")
	)
	(segment
		(start 21.366988 -135.578088)
		(end 20.688046 -135.578088)
		(width 0.127)
		(layer "B.Cu")
		(net "MEMA_9")
	)
	(segment
		(start 21.493988 -135.451088)
		(end 21.366988 -135.578088)
		(width 0.127)
		(layer "B.Cu")
		(net "MEMA_9")
	)
	(segment
		(start 20.591272 -130.553714)
		(end 20.582128 -130.562858)
		(width 0.127)
		(layer "B.Cu")
		(net "MEMA_9")
	)
	(segment
		(start 21.366988 -136.086088)
		(end 21.493988 -136.213088)
		(width 0.127)
		(layer "B.Cu")
		(net "MEMA_9")
	)
	(segment
		(start 20.772628 -130.753358)
		(end 20.871688 -130.753358)
		(width 0.127)
		(layer "B.Cu")
		(net "MEMA_9")
	)
	(segment
		(start 21.366988 -134.562088)
		(end 20.688046 -134.562088)
		(width 0.127)
		(layer "B.Cu")
		(net "MEMA_9")
	)
	(segment
		(start 21.493988 -135.197088)
		(end 21.493988 -135.451088)
		(width 0.127)
		(layer "B.Cu")
		(net "MEMA_9")
	)
	(segment
		(start 20.591272 -129.518664)
		(end 20.591272 -130.553714)
		(width 0.127)
		(layer "B.Cu")
		(net "MEMA_9")
	)
	(segment
		(start 20.688046 -136.086088)
		(end 21.366988 -136.086088)
		(width 0.127)
		(layer "B.Cu")
		(net "MEMA_9")
	)
	(segment
		(start 20.582128 -130.562858)
		(end 20.772628 -130.753358)
		(width 0.127)
		(layer "B.Cu")
		(net "MEMA_9")
	)
	(segment
		(start 20.561046 -135.959088)
		(end 20.688046 -136.086088)
		(width 0.127)
		(layer "B.Cu")
		(net "MEMA_9")
	)
	(segment
		(start 21.280628 -132.815076)
		(end 21.493988 -133.028436)
		(width 0.127)
		(layer "B.Cu")
		(net "MEMA_9")
	)
	(segment
		(start 20.561046 -135.705088)
		(end 20.561046 -135.959088)
		(width 0.127)
		(layer "B.Cu")
		(net "MEMA_9")
	)
	(segment
		(start 30.613096 -136.37514)
		(end 30.613096 -137.74674)
		(width 0.127)
		(layer "In2.Cu")
		(net "MEMA_9")
	)
	(segment
		(start 31.121096 -137.1727)
		(end 31.121096 -136.37514)
		(width 0.127)
		(layer "In2.Cu")
		(net "MEMA_9")
	)
	(segment
		(start 29.089096 -136.529318)
		(end 28.962096 -136.402318)
		(width 0.127)
		(layer "In2.Cu")
		(net "MEMA_9")
	)
	(segment
		(start 23.75916 -136.402318)
		(end 23.694136 -136.467342)
		(width 0.127)
		(layer "In2.Cu")
		(net "MEMA_9")
	)
	(segment
		(start 30.994096 -136.24814)
		(end 30.740096 -136.24814)
		(width 0.127)
		(layer "In2.Cu")
		(net "MEMA_9")
	)
	(segment
		(start 28.962096 -136.402318)
		(end 23.75916 -136.402318)
		(width 0.127)
		(layer "In2.Cu")
		(net "MEMA_9")
	)
	(segment
		(start 29.724096 -135.71728)
		(end 29.597096 -135.84428)
		(width 0.127)
		(layer "In2.Cu")
		(net "MEMA_9")
	)
	(segment
		(start 33.155382 -137.2235)
		(end 32.3342 -136.402318)
		(width 0.127)
		(layer "In2.Cu")
		(net "MEMA_9")
	)
	(segment
		(start 31.502096 -137.2997)
		(end 31.248096 -137.2997)
		(width 0.127)
		(layer "In2.Cu")
		(net "MEMA_9")
	)
	(segment
		(start 31.629096 -137.1727)
		(end 31.502096 -137.2997)
		(width 0.127)
		(layer "In2.Cu")
		(net "MEMA_9")
	)
	(segment
		(start 31.756096 -136.402318)
		(end 31.629096 -136.529318)
		(width 0.127)
		(layer "In2.Cu")
		(net "MEMA_9")
	)
	(segment
		(start 40.500046 -140.999972)
		(end 40.423592 -140.999972)
		(width 0.127)
		(layer "In2.Cu")
		(net "MEMA_9")
	)
	(segment
		(start 36.64712 -137.2235)
		(end 33.155382 -137.2235)
		(width 0.127)
		(layer "In2.Cu")
		(net "MEMA_9")
	)
	(segment
		(start 31.629096 -136.529318)
		(end 31.629096 -137.1727)
		(width 0.127)
		(layer "In2.Cu")
		(net "MEMA_9")
	)
	(segment
		(start 30.486096 -137.87374)
		(end 30.232096 -137.87374)
		(width 0.127)
		(layer "In2.Cu")
		(net "MEMA_9")
	)
	(segment
		(start 31.121096 -136.37514)
		(end 30.994096 -136.24814)
		(width 0.127)
		(layer "In2.Cu")
		(net "MEMA_9")
	)
	(segment
		(start 40.423592 -140.999972)
		(end 36.64712 -137.2235)
		(width 0.127)
		(layer "In2.Cu")
		(net "MEMA_9")
	)
	(segment
		(start 21.728684 -136.467342)
		(end 21.2344 -136.961626)
		(width 0.127)
		(layer "In2.Cu")
		(net "MEMA_9")
	)
	(segment
		(start 29.597096 -135.84428)
		(end 29.597096 -137.36066)
		(width 0.127)
		(layer "In2.Cu")
		(net "MEMA_9")
	)
	(segment
		(start 29.089096 -137.36066)
		(end 29.089096 -136.529318)
		(width 0.127)
		(layer "In2.Cu")
		(net "MEMA_9")
	)
	(segment
		(start 30.613096 -137.74674)
		(end 30.486096 -137.87374)
		(width 0.127)
		(layer "In2.Cu")
		(net "MEMA_9")
	)
	(segment
		(start 23.694136 -136.467342)
		(end 21.728684 -136.467342)
		(width 0.127)
		(layer "In2.Cu")
		(net "MEMA_9")
	)
	(segment
		(start 31.248096 -137.2997)
		(end 31.121096 -137.1727)
		(width 0.127)
		(layer "In2.Cu")
		(net "MEMA_9")
	)
	(segment
		(start 29.597096 -137.36066)
		(end 29.470096 -137.48766)
		(width 0.127)
		(layer "In2.Cu")
		(net "MEMA_9")
	)
	(segment
		(start 32.3342 -136.402318)
		(end 31.756096 -136.402318)
		(width 0.127)
		(layer "In2.Cu")
		(net "MEMA_9")
	)
	(segment
		(start 30.105096 -135.84428)
		(end 29.978096 -135.71728)
		(width 0.127)
		(layer "In2.Cu")
		(net "MEMA_9")
	)
	(segment
		(start 29.216096 -137.48766)
		(end 29.089096 -137.36066)
		(width 0.127)
		(layer "In2.Cu")
		(net "MEMA_9")
	)
	(segment
		(start 30.740096 -136.24814)
		(end 30.613096 -136.37514)
		(width 0.127)
		(layer "In2.Cu")
		(net "MEMA_9")
	)
	(segment
		(start 29.470096 -137.48766)
		(end 29.216096 -137.48766)
		(width 0.127)
		(layer "In2.Cu")
		(net "MEMA_9")
	)
	(segment
		(start 30.105096 -137.74674)
		(end 30.105096 -135.84428)
		(width 0.127)
		(layer "In2.Cu")
		(net "MEMA_9")
	)
	(segment
		(start 30.232096 -137.87374)
		(end 30.105096 -137.74674)
		(width 0.127)
		(layer "In2.Cu")
		(net "MEMA_9")
	)
	(segment
		(start 29.978096 -135.71728)
		(end 29.724096 -135.71728)
		(width 0.127)
		(layer "In2.Cu")
		(net "MEMA_9")
	)
	(segment
		(start 17.234408 -136.961626)
		(end 17.634458 -137.361676)
		(width 0.127)
		(layer "F.Cu")
		(net "MEMA_8")
	)
	(segment
		(start 41.699942 -141.400022)
		(end 42.099992 -140.999972)
		(width 0.127)
		(layer "F.Cu")
		(net "MEMA_8")
	)
	(via
		(at 17.234408 -136.961626)
		(size 0.508)
		(drill 0.254)
		(layers "F.Cu" "B.Cu")
		(net "MEMA_8")
	)
	(via
		(at 42.099992 -140.999972)
		(size 0.4572)
		(drill 0.2032)
		(layers "F.Cu" "B.Cu")
		(net "MEMA_8")
	)
	(segment
		(start 11.647424 -136.715246)
		(end 11.647424 -137.132822)
		(width 0.127)
		(layer "B.Cu")
		(net "MEMA_8")
	)
	(segment
		(start 14.752066 -136.56183)
		(end 14.752066 -137.55497)
		(width 0.127)
		(layer "B.Cu")
		(net "MEMA_8")
	)
	(segment
		(start 15.641066 -136.43483)
		(end 15.768066 -136.56183)
		(width 0.127)
		(layer "B.Cu")
		(net "MEMA_8")
	)
	(segment
		(start 15.768066 -137.182352)
		(end 15.923514 -137.3378)
		(width 0.127)
		(layer "B.Cu")
		(net "MEMA_8")
	)
	(segment
		(start 14.244066 -137.29843)
		(end 14.244066 -136.56183)
		(width 0.127)
		(layer "B.Cu")
		(net "MEMA_8")
	)
	(segment
		(start 14.12875 -137.413746)
		(end 14.244066 -137.29843)
		(width 0.127)
		(layer "B.Cu")
		(net "MEMA_8")
	)
	(segment
		(start 15.260066 -137.519918)
		(end 15.260066 -136.56183)
		(width 0.127)
		(layer "B.Cu")
		(net "MEMA_8")
	)
	(segment
		(start 14.752066 -137.55497)
		(end 14.86154 -137.664444)
		(width 0.127)
		(layer "B.Cu")
		(net "MEMA_8")
	)
	(segment
		(start 16.858234 -137.3378)
		(end 17.234408 -136.961626)
		(width 0.127)
		(layer "B.Cu")
		(net "MEMA_8")
	)
	(segment
		(start 14.625066 -136.43483)
		(end 14.752066 -136.56183)
		(width 0.127)
		(layer "B.Cu")
		(net "MEMA_8")
	)
	(segment
		(start 11.928348 -137.413746)
		(end 14.12875 -137.413746)
		(width 0.127)
		(layer "B.Cu")
		(net "MEMA_8")
	)
	(segment
		(start 15.11554 -137.664444)
		(end 15.260066 -137.519918)
		(width 0.127)
		(layer "B.Cu")
		(net "MEMA_8")
	)
	(segment
		(start 15.387066 -136.43483)
		(end 15.641066 -136.43483)
		(width 0.127)
		(layer "B.Cu")
		(net "MEMA_8")
	)
	(segment
		(start 11.647424 -137.132822)
		(end 11.928348 -137.413746)
		(width 0.127)
		(layer "B.Cu")
		(net "MEMA_8")
	)
	(segment
		(start 10.619232 -136.716516)
		(end 11.646154 -136.716516)
		(width 0.127)
		(layer "B.Cu")
		(net "MEMA_8")
	)
	(segment
		(start 14.244066 -136.56183)
		(end 14.371066 -136.43483)
		(width 0.127)
		(layer "B.Cu")
		(net "MEMA_8")
	)
	(segment
		(start 15.923514 -137.3378)
		(end 16.858234 -137.3378)
		(width 0.127)
		(layer "B.Cu")
		(net "MEMA_8")
	)
	(segment
		(start 14.86154 -137.664444)
		(end 15.11554 -137.664444)
		(width 0.127)
		(layer "B.Cu")
		(net "MEMA_8")
	)
	(segment
		(start 14.371066 -136.43483)
		(end 14.625066 -136.43483)
		(width 0.127)
		(layer "B.Cu")
		(net "MEMA_8")
	)
	(segment
		(start 11.646154 -136.716516)
		(end 11.647424 -136.715246)
		(width 0.127)
		(layer "B.Cu")
		(net "MEMA_8")
	)
	(segment
		(start 15.768066 -136.56183)
		(end 15.768066 -137.182352)
		(width 0.127)
		(layer "B.Cu")
		(net "MEMA_8")
	)
	(segment
		(start 15.260066 -136.56183)
		(end 15.387066 -136.43483)
		(width 0.127)
		(layer "B.Cu")
		(net "MEMA_8")
	)
	(segment
		(start 40.24884 -139.8016)
		(end 39.457122 -139.009882)
		(width 0.1016)
		(layer "In5.Cu")
		(net "MEMA_8")
	)
	(segment
		(start 28.61183 -133.216396)
		(end 20.790662 -133.216396)
		(width 0.127)
		(layer "In5.Cu")
		(net "MEMA_8")
	)
	(segment
		(start 17.234408 -136.77265)
		(end 17.234408 -136.961626)
		(width 0.127)
		(layer "In5.Cu")
		(net "MEMA_8")
	)
	(segment
		(start 42.099992 -140.999972)
		(end 41.908984 -140.809218)
		(width 0.1016)
		(layer "In5.Cu")
		(net "MEMA_8")
	)
	(segment
		(start 35.19424 -134.747)
		(end 32.9692 -134.747)
		(width 0.127)
		(layer "In5.Cu")
		(net "MEMA_8")
	)
	(segment
		(start 20.790662 -133.216396)
		(end 17.234408 -136.77265)
		(width 0.127)
		(layer "In5.Cu")
		(net "MEMA_8")
	)
	(segment
		(start 41.908984 -140.613384)
		(end 41.7068 -140.4112)
		(width 0.1016)
		(layer "In5.Cu")
		(net "MEMA_8")
	)
	(segment
		(start 39.457122 -139.009882)
		(end 35.19424 -134.747)
		(width 0.127)
		(layer "In5.Cu")
		(net "MEMA_8")
	)
	(segment
		(start 41.908984 -140.809218)
		(end 41.908984 -140.613384)
		(width 0.1016)
		(layer "In5.Cu")
		(net "MEMA_8")
	)
	(segment
		(start 41.5036 -139.8016)
		(end 40.24884 -139.8016)
		(width 0.1016)
		(layer "In5.Cu")
		(net "MEMA_8")
	)
	(segment
		(start 29.34589 -133.950456)
		(end 28.61183 -133.216396)
		(width 0.127)
		(layer "In5.Cu")
		(net "MEMA_8")
	)
	(segment
		(start 41.7068 -140.4112)
		(end 41.7068 -140.0048)
		(width 0.1016)
		(layer "In5.Cu")
		(net "MEMA_8")
	)
	(segment
		(start 32.9692 -134.747)
		(end 32.172656 -133.950456)
		(width 0.127)
		(layer "In5.Cu")
		(net "MEMA_8")
	)
	(segment
		(start 41.7068 -140.0048)
		(end 41.5036 -139.8016)
		(width 0.1016)
		(layer "In5.Cu")
		(net "MEMA_8")
	)
	(segment
		(start 32.172656 -133.950456)
		(end 29.34589 -133.950456)
		(width 0.127)
		(layer "In5.Cu")
		(net "MEMA_8")
	)
	(segment
		(start 32.935672 -136.54278)
		(end 31.82366 -136.54278)
		(width 0.127)
		(layer "F.Cu")
		(net "MEMA_7")
	)
	(segment
		(start 28.95092 -138.6332)
		(end 29.07792 -138.7602)
		(width 0.127)
		(layer "F.Cu")
		(net "MEMA_7")
	)
	(segment
		(start 36.767262 -140.999464)
		(end 36.022788 -140.25499)
		(width 0.127)
		(layer "F.Cu")
		(net "MEMA_7")
	)
	(segment
		(start 36.022788 -140.25499)
		(end 35.980624 -140.25499)
		(width 0.127)
		(layer "F.Cu")
		(net "MEMA_7")
	)
	(segment
		(start 22.834346 -136.96188)
		(end 22.834346 -136.961372)
		(width 0.127)
		(layer "F.Cu")
		(net "MEMA_7")
	)
	(segment
		(start 40.099996 -141.400022)
		(end 39.933118 -141.233398)
		(width 0.127)
		(layer "F.Cu")
		(net "MEMA_7")
	)
	(segment
		(start 22.43455 -137.361676)
		(end 22.834346 -136.96188)
		(width 0.127)
		(layer "F.Cu")
		(net "MEMA_7")
	)
	(segment
		(start 28.95092 -137.59561)
		(end 28.82392 -137.72261)
		(width 0.127)
		(layer "F.Cu")
		(net "MEMA_7")
	)
	(segment
		(start 35.980624 -140.25499)
		(end 34.645854 -138.92022)
		(width 0.127)
		(layer "F.Cu")
		(net "MEMA_7")
	)
	(segment
		(start 28.06192 -135.9408)
		(end 27.93492 -136.0678)
		(width 0.127)
		(layer "F.Cu")
		(net "MEMA_7")
	)
	(segment
		(start 27.93492 -138.10361)
		(end 28.06192 -138.23061)
		(width 0.127)
		(layer "F.Cu")
		(net "MEMA_7")
	)
	(segment
		(start 34.645854 -138.92022)
		(end 34.645854 -138.252962)
		(width 0.127)
		(layer "F.Cu")
		(net "MEMA_7")
	)
	(segment
		(start 31.82366 -136.54278)
		(end 31.57728 -136.2964)
		(width 0.127)
		(layer "F.Cu")
		(net "MEMA_7")
	)
	(segment
		(start 29.07792 -138.7602)
		(end 29.7688 -138.7602)
		(width 0.127)
		(layer "F.Cu")
		(net "MEMA_7")
	)
	(segment
		(start 28.31592 -135.9408)
		(end 28.06192 -135.9408)
		(width 0.127)
		(layer "F.Cu")
		(net "MEMA_7")
	)
	(segment
		(start 28.06192 -138.23061)
		(end 28.82392 -138.23061)
		(width 0.127)
		(layer "F.Cu")
		(net "MEMA_7")
	)
	(segment
		(start 28.44292 -136.0678)
		(end 28.31592 -135.9408)
		(width 0.127)
		(layer "F.Cu")
		(net "MEMA_7")
	)
	(segment
		(start 39.36873 -140.999464)
		(end 36.767262 -140.999464)
		(width 0.127)
		(layer "F.Cu")
		(net "MEMA_7")
	)
	(segment
		(start 28.82392 -137.72261)
		(end 28.56992 -137.72261)
		(width 0.127)
		(layer "F.Cu")
		(net "MEMA_7")
	)
	(segment
		(start 28.56992 -137.72261)
		(end 28.44292 -137.59561)
		(width 0.127)
		(layer "F.Cu")
		(net "MEMA_7")
	)
	(segment
		(start 31.57728 -136.2964)
		(end 31.082234 -136.2964)
		(width 0.127)
		(layer "F.Cu")
		(net "MEMA_7")
	)
	(segment
		(start 28.44292 -137.59561)
		(end 28.44292 -136.0678)
		(width 0.127)
		(layer "F.Cu")
		(net "MEMA_7")
	)
	(segment
		(start 28.82392 -138.23061)
		(end 28.95092 -138.35761)
		(width 0.127)
		(layer "F.Cu")
		(net "MEMA_7")
	)
	(segment
		(start 31.026354 -136.24052)
		(end 29.1338 -136.24052)
		(width 0.127)
		(layer "F.Cu")
		(net "MEMA_7")
	)
	(segment
		(start 28.95092 -138.35761)
		(end 28.95092 -138.6332)
		(width 0.127)
		(layer "F.Cu")
		(net "MEMA_7")
	)
	(segment
		(start 27.93492 -136.0678)
		(end 27.93492 -138.10361)
		(width 0.127)
		(layer "F.Cu")
		(net "MEMA_7")
	)
	(segment
		(start 28.95092 -136.4234)
		(end 28.95092 -137.59561)
		(width 0.127)
		(layer "F.Cu")
		(net "MEMA_7")
	)
	(segment
		(start 29.1338 -136.24052)
		(end 28.95092 -136.4234)
		(width 0.127)
		(layer "F.Cu")
		(net "MEMA_7")
	)
	(segment
		(start 31.082234 -136.2964)
		(end 31.026354 -136.24052)
		(width 0.127)
		(layer "F.Cu")
		(net "MEMA_7")
	)
	(segment
		(start 34.645854 -138.252962)
		(end 32.935672 -136.54278)
		(width 0.127)
		(layer "F.Cu")
		(net "MEMA_7")
	)
	(via
		(at 22.834346 -136.961372)
		(size 0.508)
		(drill 0.254)
		(layers "F.Cu" "B.Cu")
		(net "MEMA_7")
	)
	(via
		(at 29.7688 -138.7602)
		(size 0.508)
		(drill 0.254)
		(layers "F.Cu" "B.Cu")
		(net "MEMA_7")
	)
	(arc
		(start 39.933118 -141.233398)
		(mid 39.674203 -141.06027)
		(end 39.36873 -140.999464)
		(width 0.127)
		(layer "F.Cu")
		(net "MEMA_7")
	)
	(segment
		(start 23.440644 -129.556002)
		(end 23.437342 -129.5527)
		(width 0.127)
		(layer "B.Cu")
		(net "MEMA_7")
	)
	(segment
		(start 22.310852 -136.312656)
		(end 22.310852 -136.058656)
		(width 0.127)
		(layer "B.Cu")
		(net "MEMA_7")
	)
	(segment
		(start 22.437852 -136.439656)
		(end 22.310852 -136.312656)
		(width 0.127)
		(layer "B.Cu")
		(net "MEMA_7")
	)
	(segment
		(start 23.539704 -130.562858)
		(end 23.440644 -130.562858)
		(width 0.127)
		(layer "B.Cu")
		(net "MEMA_7")
	)
	(segment
		(start 25.355042 -133.650736)
		(end 25.355042 -133.440424)
		(width 0.127)
		(layer "B.Cu")
		(net "MEMA_7")
	)
	(segment
		(start 25.206198 -133.79958)
		(end 25.355042 -133.650736)
		(width 0.127)
		(layer "B.Cu")
		(net "MEMA_7")
	)
	(segment
		(start 24.139144 -131.162298)
		(end 23.539704 -130.562858)
		(width 0.127)
		(layer "B.Cu")
		(net "MEMA_7")
	)
	(segment
		(start 22.310852 -136.058656)
		(end 22.437852 -135.931656)
		(width 0.127)
		(layer "B.Cu")
		(net "MEMA_7")
	)
	(segment
		(start 23.440644 -130.562858)
		(end 23.440644 -129.556002)
		(width 0.127)
		(layer "B.Cu")
		(net "MEMA_7")
	)
	(segment
		(start 22.707346 -135.931656)
		(end 22.834346 -135.804656)
		(width 0.127)
		(layer "B.Cu")
		(net "MEMA_7")
	)
	(segment
		(start 22.707346 -136.439656)
		(end 22.437852 -136.439656)
		(width 0.127)
		(layer "B.Cu")
		(net "MEMA_7")
	)
	(segment
		(start 22.834346 -136.961372)
		(end 22.834346 -136.566656)
		(width 0.127)
		(layer "B.Cu")
		(net "MEMA_7")
	)
	(segment
		(start 24.139144 -133.92658)
		(end 24.266144 -133.79958)
		(width 0.127)
		(layer "B.Cu")
		(net "MEMA_7")
	)
	(segment
		(start 24.266144 -133.29158)
		(end 24.139144 -133.16458)
		(width 0.127)
		(layer "B.Cu")
		(net "MEMA_7")
	)
	(segment
		(start 24.139144 -133.16458)
		(end 24.139144 -131.162298)
		(width 0.127)
		(layer "B.Cu")
		(net "MEMA_7")
	)
	(segment
		(start 22.834346 -135.804656)
		(end 22.834346 -135.545068)
		(width 0.127)
		(layer "B.Cu")
		(net "MEMA_7")
	)
	(segment
		(start 24.139144 -134.24027)
		(end 24.139144 -133.92658)
		(width 0.127)
		(layer "B.Cu")
		(net "MEMA_7")
	)
	(segment
		(start 24.266144 -133.79958)
		(end 25.206198 -133.79958)
		(width 0.127)
		(layer "B.Cu")
		(net "MEMA_7")
	)
	(segment
		(start 22.834346 -135.545068)
		(end 24.139144 -134.24027)
		(width 0.127)
		(layer "B.Cu")
		(net "MEMA_7")
	)
	(segment
		(start 22.437852 -135.931656)
		(end 22.707346 -135.931656)
		(width 0.127)
		(layer "B.Cu")
		(net "MEMA_7")
	)
	(segment
		(start 25.355042 -133.440424)
		(end 25.206198 -133.29158)
		(width 0.127)
		(layer "B.Cu")
		(net "MEMA_7")
	)
	(segment
		(start 25.206198 -133.29158)
		(end 24.266144 -133.29158)
		(width 0.127)
		(layer "B.Cu")
		(net "MEMA_7")
	)
	(segment
		(start 22.834346 -136.566656)
		(end 22.707346 -136.439656)
		(width 0.127)
		(layer "B.Cu")
		(net "MEMA_7")
	)
	(segment
		(start 22.8854 -136.910318)
		(end 22.834346 -136.961372)
		(width 0.127)
		(layer "In2.Cu")
		(net "MEMA_7")
	)
	(segment
		(start 29.7688 -138.7602)
		(end 27.918918 -136.910318)
		(width 0.127)
		(layer "In2.Cu")
		(net "MEMA_7")
	)
	(segment
		(start 27.918918 -136.910318)
		(end 22.8854 -136.910318)
		(width 0.127)
		(layer "In2.Cu")
		(net "MEMA_7")
	)
	(segment
		(start 35.812222 -140.76299)
		(end 35.770058 -140.76299)
		(width 0.127)
		(layer "F.Cu")
		(net "MEMA_6")
	)
	(segment
		(start 18.034508 -137.761472)
		(end 17.634458 -138.161522)
		(width 0.127)
		(layer "F.Cu")
		(net "MEMA_6")
	)
	(segment
		(start 31.805626 -137.804906)
		(end 31.97352 -137.9728)
		(width 0.127)
		(layer "F.Cu")
		(net "MEMA_6")
	)
	(segment
		(start 31.93288 -137.1346)
		(end 31.805626 -137.261854)
		(width 0.127)
		(layer "F.Cu")
		(net "MEMA_6")
	)
	(segment
		(start 32.808926 -137.1346)
		(end 31.93288 -137.1346)
		(width 0.127)
		(layer "F.Cu")
		(net "MEMA_6")
	)
	(segment
		(start 34.137854 -139.130786)
		(end 34.137854 -138.463528)
		(width 0.127)
		(layer "F.Cu")
		(net "MEMA_6")
	)
	(segment
		(start 36.449254 -141.400022)
		(end 35.812222 -140.76299)
		(width 0.127)
		(layer "F.Cu")
		(net "MEMA_6")
	)
	(segment
		(start 34.137854 -138.463528)
		(end 32.808926 -137.1346)
		(width 0.127)
		(layer "F.Cu")
		(net "MEMA_6")
	)
	(segment
		(start 31.805626 -137.261854)
		(end 31.805626 -137.804906)
		(width 0.127)
		(layer "F.Cu")
		(net "MEMA_6")
	)
	(segment
		(start 35.770058 -140.76299)
		(end 34.137854 -139.130786)
		(width 0.127)
		(layer "F.Cu")
		(net "MEMA_6")
	)
	(segment
		(start 31.97352 -137.9728)
		(end 32.3342 -137.9728)
		(width 0.127)
		(layer "F.Cu")
		(net "MEMA_6")
	)
	(segment
		(start 39.299896 -141.400022)
		(end 36.449254 -141.400022)
		(width 0.127)
		(layer "F.Cu")
		(net "MEMA_6")
	)
	(via
		(at 18.034508 -137.761472)
		(size 0.508)
		(drill 0.254)
		(layers "F.Cu" "B.Cu")
		(net "MEMA_6")
	)
	(via
		(at 32.3342 -137.9728)
		(size 0.508)
		(drill 0.254)
		(layers "F.Cu" "B.Cu")
		(net "MEMA_6")
	)
	(segment
		(start 14.806168 -138.1887)
		(end 14.613382 -138.381486)
		(width 0.127)
		(layer "B.Cu")
		(net "MEMA_6")
	)
	(segment
		(start 14.613382 -140.0175)
		(end 14.498066 -140.132816)
		(width 0.127)
		(layer "B.Cu")
		(net "MEMA_6")
	)
	(segment
		(start 11.646154 -138.145774)
		(end 11.647424 -138.144504)
		(width 0.127)
		(layer "B.Cu")
		(net "MEMA_6")
	)
	(segment
		(start 14.244066 -140.132816)
		(end 14.105382 -139.994132)
		(width 0.127)
		(layer "B.Cu")
		(net "MEMA_6")
	)
	(segment
		(start 13.978382 -138.872722)
		(end 11.975846 -138.872722)
		(width 0.127)
		(layer "B.Cu")
		(net "MEMA_6")
	)
	(segment
		(start 17.60728 -138.1887)
		(end 14.806168 -138.1887)
		(width 0.127)
		(layer "B.Cu")
		(net "MEMA_6")
	)
	(segment
		(start 14.105382 -138.999722)
		(end 13.978382 -138.872722)
		(width 0.127)
		(layer "B.Cu")
		(net "MEMA_6")
	)
	(segment
		(start 10.644632 -138.145774)
		(end 11.646154 -138.145774)
		(width 0.127)
		(layer "B.Cu")
		(net "MEMA_6")
	)
	(segment
		(start 14.498066 -140.132816)
		(end 14.244066 -140.132816)
		(width 0.127)
		(layer "B.Cu")
		(net "MEMA_6")
	)
	(segment
		(start 11.975846 -138.872722)
		(end 11.647424 -138.5443)
		(width 0.127)
		(layer "B.Cu")
		(net "MEMA_6")
	)
	(segment
		(start 11.647424 -138.5443)
		(end 11.647424 -138.144504)
		(width 0.127)
		(layer "B.Cu")
		(net "MEMA_6")
	)
	(segment
		(start 18.034508 -137.761472)
		(end 17.60728 -138.1887)
		(width 0.127)
		(layer "B.Cu")
		(net "MEMA_6")
	)
	(segment
		(start 14.105382 -139.994132)
		(end 14.105382 -138.999722)
		(width 0.127)
		(layer "B.Cu")
		(net "MEMA_6")
	)
	(segment
		(start 14.613382 -138.381486)
		(end 14.613382 -140.0175)
		(width 0.127)
		(layer "B.Cu")
		(net "MEMA_6")
	)
	(segment
		(start 26.472388 -135.98398)
		(end 26.345388 -135.85698)
		(width 0.127)
		(layer "In5.Cu")
		(net "MEMA_6")
	)
	(segment
		(start 32.3342 -137.9728)
		(end 32.3342 -137.74166)
		(width 0.127)
		(layer "In5.Cu")
		(net "MEMA_6")
	)
	(segment
		(start 30.199076 -136.817608)
		(end 29.338778 -136.817608)
		(width 0.127)
		(layer "In5.Cu")
		(net "MEMA_6")
	)
	(segment
		(start 25.456388 -135.98398)
		(end 25.329388 -135.85698)
		(width 0.127)
		(layer "In5.Cu")
		(net "MEMA_6")
	)
	(segment
		(start 26.726388 -135.98398)
		(end 26.472388 -135.98398)
		(width 0.127)
		(layer "In5.Cu")
		(net "MEMA_6")
	)
	(segment
		(start 25.837388 -135.85698)
		(end 25.710388 -135.98398)
		(width 0.127)
		(layer "In5.Cu")
		(net "MEMA_6")
	)
	(segment
		(start 25.329388 -135.375396)
		(end 25.202388 -135.248396)
		(width 0.127)
		(layer "In5.Cu")
		(net "MEMA_6")
	)
	(segment
		(start 25.837388 -135.375396)
		(end 25.837388 -135.85698)
		(width 0.127)
		(layer "In5.Cu")
		(net "MEMA_6")
	)
	(segment
		(start 27.769566 -135.248396)
		(end 26.980388 -135.248396)
		(width 0.127)
		(layer "In5.Cu")
		(net "MEMA_6")
	)
	(segment
		(start 25.964388 -135.248396)
		(end 25.837388 -135.375396)
		(width 0.127)
		(layer "In5.Cu")
		(net "MEMA_6")
	)
	(segment
		(start 18.996406 -137.265664)
		(end 18.530316 -137.265664)
		(width 0.127)
		(layer "In5.Cu")
		(net "MEMA_6")
	)
	(segment
		(start 26.218388 -135.248396)
		(end 25.964388 -135.248396)
		(width 0.127)
		(layer "In5.Cu")
		(net "MEMA_6")
	)
	(segment
		(start 26.980388 -135.248396)
		(end 26.853388 -135.375396)
		(width 0.127)
		(layer "In5.Cu")
		(net "MEMA_6")
	)
	(segment
		(start 25.202388 -135.248396)
		(end 21.013674 -135.248396)
		(width 0.127)
		(layer "In5.Cu")
		(net "MEMA_6")
	)
	(segment
		(start 25.329388 -135.85698)
		(end 25.329388 -135.375396)
		(width 0.127)
		(layer "In5.Cu")
		(net "MEMA_6")
	)
	(segment
		(start 21.013674 -135.248396)
		(end 18.996406 -137.265664)
		(width 0.127)
		(layer "In5.Cu")
		(net "MEMA_6")
	)
	(segment
		(start 32.3342 -137.74166)
		(end 32.2072 -137.61466)
		(width 0.127)
		(layer "In5.Cu")
		(net "MEMA_6")
	)
	(segment
		(start 29.338778 -136.817608)
		(end 27.769566 -135.248396)
		(width 0.127)
		(layer "In5.Cu")
		(net "MEMA_6")
	)
	(segment
		(start 18.530316 -137.265664)
		(end 18.034508 -137.761472)
		(width 0.127)
		(layer "In5.Cu")
		(net "MEMA_6")
	)
	(segment
		(start 26.853388 -135.375396)
		(end 26.853388 -135.85698)
		(width 0.127)
		(layer "In5.Cu")
		(net "MEMA_6")
	)
	(segment
		(start 26.345388 -135.375396)
		(end 26.218388 -135.248396)
		(width 0.127)
		(layer "In5.Cu")
		(net "MEMA_6")
	)
	(segment
		(start 30.996128 -137.61466)
		(end 30.199076 -136.817608)
		(width 0.127)
		(layer "In5.Cu")
		(net "MEMA_6")
	)
	(segment
		(start 25.710388 -135.98398)
		(end 25.456388 -135.98398)
		(width 0.127)
		(layer "In5.Cu")
		(net "MEMA_6")
	)
	(segment
		(start 26.853388 -135.85698)
		(end 26.726388 -135.98398)
		(width 0.127)
		(layer "In5.Cu")
		(net "MEMA_6")
	)
	(segment
		(start 26.345388 -135.85698)
		(end 26.345388 -135.375396)
		(width 0.127)
		(layer "In5.Cu")
		(net "MEMA_6")
	)
	(segment
		(start 32.2072 -137.61466)
		(end 30.996128 -137.61466)
		(width 0.127)
		(layer "In5.Cu")
		(net "MEMA_6")
	)
	(segment
		(start 22.43455 -138.161776)
		(end 22.834346 -138.561572)
		(width 0.127)
		(layer "F.Cu")
		(net "MEMA_5")
	)
	(segment
		(start 42.500296 -142.199868)
		(end 42.500042 -142.199868)
		(width 0.127)
		(layer "F.Cu")
		(net "MEMA_5")
	)
	(segment
		(start 22.43455 -138.161522)
		(end 22.43455 -138.161776)
		(width 0.127)
		(layer "F.Cu")
		(net "MEMA_5")
	)
	(segment
		(start 42.900092 -141.800072)
		(end 42.500296 -142.199868)
		(width 0.127)
		(layer "F.Cu")
		(net "MEMA_5")
	)
	(via
		(at 42.900092 -141.800072)
		(size 0.4572)
		(drill 0.2032)
		(layers "F.Cu" "B.Cu")
		(net "MEMA_5")
	)
	(via
		(at 22.834346 -138.561572)
		(size 0.508)
		(drill 0.254)
		(layers "F.Cu" "B.Cu")
		(net "MEMA_5")
	)
	(segment
		(start 25.159462 -130.753358)
		(end 25.88006 -131.473956)
		(width 0.127)
		(layer "B.Cu")
		(net "MEMA_5")
	)
	(segment
		(start 24.373078 -135.03275)
		(end 23.9395 -135.466328)
		(width 0.127)
		(layer "B.Cu")
		(net "MEMA_5")
	)
	(segment
		(start 25.88006 -131.473956)
		(end 25.88006 -134.638288)
		(width 0.127)
		(layer "B.Cu")
		(net "MEMA_5")
	)
	(segment
		(start 24.869902 -130.562858)
		(end 25.060402 -130.753358)
		(width 0.127)
		(layer "B.Cu")
		(net "MEMA_5")
	)
	(segment
		(start 23.9395 -135.466328)
		(end 23.9395 -136.7155)
		(width 0.127)
		(layer "B.Cu")
		(net "MEMA_5")
	)
	(segment
		(start 25.060402 -130.753358)
		(end 25.159462 -130.753358)
		(width 0.127)
		(layer "B.Cu")
		(net "MEMA_5")
	)
	(segment
		(start 25.88006 -134.638288)
		(end 25.485598 -135.03275)
		(width 0.127)
		(layer "B.Cu")
		(net "MEMA_5")
	)
	(segment
		(start 24.869902 -130.562858)
		(end 24.869902 -129.556002)
		(width 0.127)
		(layer "B.Cu")
		(net "MEMA_5")
	)
	(segment
		(start 23.9395 -136.7155)
		(end 22.834346 -137.820654)
		(width 0.127)
		(layer "B.Cu")
		(net "MEMA_5")
	)
	(segment
		(start 25.485598 -135.03275)
		(end 24.373078 -135.03275)
		(width 0.127)
		(layer "B.Cu")
		(net "MEMA_5")
	)
	(segment
		(start 24.869902 -129.556002)
		(end 24.8666 -129.5527)
		(width 0.127)
		(layer "B.Cu")
		(net "MEMA_5")
	)
	(segment
		(start 22.834346 -137.820654)
		(end 22.834346 -138.561572)
		(width 0.127)
		(layer "B.Cu")
		(net "MEMA_5")
	)
	(segment
		(start 33.592516 -139.61872)
		(end 33.846516 -139.61872)
		(width 0.127)
		(layer "In2.Cu")
		(net "MEMA_5")
	)
	(segment
		(start 33.846516 -139.61872)
		(end 33.973516 -139.74572)
		(width 0.127)
		(layer "In2.Cu")
		(net "MEMA_5")
	)
	(segment
		(start 42.506392 -142.193772)
		(end 42.900092 -141.800072)
		(width 0.127)
		(layer "In2.Cu")
		(net "MEMA_5")
	)
	(segment
		(start 33.338516 -140.26769)
		(end 33.465516 -140.14069)
		(width 0.127)
		(layer "In2.Cu")
		(net "MEMA_5")
	)
	(segment
		(start 31.89478 -140.26769)
		(end 32.322516 -140.26769)
		(width 0.127)
		(layer "In2.Cu")
		(net "MEMA_5")
	)
	(segment
		(start 37.148516 -140.26769)
		(end 38.725856 -140.26769)
		(width 0.127)
		(layer "In2.Cu")
		(net "MEMA_5")
	)
	(segment
		(start 34.354516 -140.26769)
		(end 34.481516 -140.14069)
		(width 0.127)
		(layer "In2.Cu")
		(net "MEMA_5")
	)
	(segment
		(start 34.100516 -140.26769)
		(end 34.354516 -140.26769)
		(width 0.127)
		(layer "In2.Cu")
		(net "MEMA_5")
	)
	(segment
		(start 33.465516 -140.14069)
		(end 33.465516 -139.74572)
		(width 0.127)
		(layer "In2.Cu")
		(net "MEMA_5")
	)
	(segment
		(start 36.386516 -140.26769)
		(end 36.513516 -140.14069)
		(width 0.127)
		(layer "In2.Cu")
		(net "MEMA_5")
	)
	(segment
		(start 32.449516 -139.74572)
		(end 32.576516 -139.61872)
		(width 0.127)
		(layer "In2.Cu")
		(net "MEMA_5")
	)
	(segment
		(start 37.021516 -139.39012)
		(end 37.021516 -140.14069)
		(width 0.127)
		(layer "In2.Cu")
		(net "MEMA_5")
	)
	(segment
		(start 36.894516 -139.26312)
		(end 37.021516 -139.39012)
		(width 0.127)
		(layer "In2.Cu")
		(net "MEMA_5")
	)
	(segment
		(start 32.322516 -140.26769)
		(end 32.449516 -140.14069)
		(width 0.127)
		(layer "In2.Cu")
		(net "MEMA_5")
	)
	(segment
		(start 32.957516 -139.74572)
		(end 32.957516 -140.14069)
		(width 0.127)
		(layer "In2.Cu")
		(net "MEMA_5")
	)
	(segment
		(start 32.449516 -140.14069)
		(end 32.449516 -139.74572)
		(width 0.127)
		(layer "In2.Cu")
		(net "MEMA_5")
	)
	(segment
		(start 23.081996 -138.313922)
		(end 24.336248 -138.313922)
		(width 0.127)
		(layer "In2.Cu")
		(net "MEMA_5")
	)
	(segment
		(start 34.481516 -140.14069)
		(end 34.481516 -139.56792)
		(width 0.127)
		(layer "In2.Cu")
		(net "MEMA_5")
	)
	(segment
		(start 35.497516 -139.44092)
		(end 35.624516 -139.31392)
		(width 0.127)
		(layer "In2.Cu")
		(net "MEMA_5")
	)
	(segment
		(start 40.249348 -141.791182)
		(end 40.706548 -141.791182)
		(width 0.127)
		(layer "In2.Cu")
		(net "MEMA_5")
	)
	(segment
		(start 34.862516 -139.44092)
		(end 34.989516 -139.56792)
		(width 0.127)
		(layer "In2.Cu")
		(net "MEMA_5")
	)
	(segment
		(start 36.513516 -140.14069)
		(end 36.513516 -139.39012)
		(width 0.127)
		(layer "In2.Cu")
		(net "MEMA_5")
	)
	(segment
		(start 38.725856 -140.26769)
		(end 40.249348 -141.791182)
		(width 0.127)
		(layer "In2.Cu")
		(net "MEMA_5")
	)
	(segment
		(start 32.576516 -139.61872)
		(end 32.830516 -139.61872)
		(width 0.127)
		(layer "In2.Cu")
		(net "MEMA_5")
	)
	(segment
		(start 33.084516 -140.26769)
		(end 33.338516 -140.26769)
		(width 0.127)
		(layer "In2.Cu")
		(net "MEMA_5")
	)
	(segment
		(start 32.830516 -139.61872)
		(end 32.957516 -139.74572)
		(width 0.127)
		(layer "In2.Cu")
		(net "MEMA_5")
	)
	(segment
		(start 34.989516 -139.56792)
		(end 34.989516 -140.14069)
		(width 0.127)
		(layer "In2.Cu")
		(net "MEMA_5")
	)
	(segment
		(start 36.640516 -139.26312)
		(end 36.894516 -139.26312)
		(width 0.127)
		(layer "In2.Cu")
		(net "MEMA_5")
	)
	(segment
		(start 35.370516 -140.26769)
		(end 35.497516 -140.14069)
		(width 0.127)
		(layer "In2.Cu")
		(net "MEMA_5")
	)
	(segment
		(start 22.834346 -138.561572)
		(end 23.081996 -138.313922)
		(width 0.127)
		(layer "In2.Cu")
		(net "MEMA_5")
	)
	(segment
		(start 35.116516 -140.26769)
		(end 35.370516 -140.26769)
		(width 0.127)
		(layer "In2.Cu")
		(net "MEMA_5")
	)
	(segment
		(start 24.336248 -138.313922)
		(end 24.456644 -138.434318)
		(width 0.127)
		(layer "In2.Cu")
		(net "MEMA_5")
	)
	(segment
		(start 29.18968 -140.55344)
		(end 31.60903 -140.55344)
		(width 0.127)
		(layer "In2.Cu")
		(net "MEMA_5")
	)
	(segment
		(start 37.021516 -140.14069)
		(end 37.148516 -140.26769)
		(width 0.127)
		(layer "In2.Cu")
		(net "MEMA_5")
	)
	(segment
		(start 36.005516 -139.44092)
		(end 36.005516 -140.14069)
		(width 0.127)
		(layer "In2.Cu")
		(net "MEMA_5")
	)
	(segment
		(start 34.989516 -140.14069)
		(end 35.116516 -140.26769)
		(width 0.127)
		(layer "In2.Cu")
		(net "MEMA_5")
	)
	(segment
		(start 36.513516 -139.39012)
		(end 36.640516 -139.26312)
		(width 0.127)
		(layer "In2.Cu")
		(net "MEMA_5")
	)
	(segment
		(start 35.497516 -140.14069)
		(end 35.497516 -139.44092)
		(width 0.127)
		(layer "In2.Cu")
		(net "MEMA_5")
	)
	(segment
		(start 41.109138 -142.193772)
		(end 42.506392 -142.193772)
		(width 0.127)
		(layer "In2.Cu")
		(net "MEMA_5")
	)
	(segment
		(start 33.465516 -139.74572)
		(end 33.592516 -139.61872)
		(width 0.127)
		(layer "In2.Cu")
		(net "MEMA_5")
	)
	(segment
		(start 33.973516 -140.14069)
		(end 34.100516 -140.26769)
		(width 0.127)
		(layer "In2.Cu")
		(net "MEMA_5")
	)
	(segment
		(start 24.456644 -138.434318)
		(end 27.070558 -138.434318)
		(width 0.127)
		(layer "In2.Cu")
		(net "MEMA_5")
	)
	(segment
		(start 31.60903 -140.55344)
		(end 31.89478 -140.26769)
		(width 0.127)
		(layer "In2.Cu")
		(net "MEMA_5")
	)
	(segment
		(start 40.706548 -141.791182)
		(end 41.109138 -142.193772)
		(width 0.127)
		(layer "In2.Cu")
		(net "MEMA_5")
	)
	(segment
		(start 36.005516 -140.14069)
		(end 36.132516 -140.26769)
		(width 0.127)
		(layer "In2.Cu")
		(net "MEMA_5")
	)
	(segment
		(start 34.608516 -139.44092)
		(end 34.862516 -139.44092)
		(width 0.127)
		(layer "In2.Cu")
		(net "MEMA_5")
	)
	(segment
		(start 32.957516 -140.14069)
		(end 33.084516 -140.26769)
		(width 0.127)
		(layer "In2.Cu")
		(net "MEMA_5")
	)
	(segment
		(start 35.878516 -139.31392)
		(end 36.005516 -139.44092)
		(width 0.127)
		(layer "In2.Cu")
		(net "MEMA_5")
	)
	(segment
		(start 34.481516 -139.56792)
		(end 34.608516 -139.44092)
		(width 0.127)
		(layer "In2.Cu")
		(net "MEMA_5")
	)
	(segment
		(start 27.070558 -138.434318)
		(end 29.18968 -140.55344)
		(width 0.127)
		(layer "In2.Cu")
		(net "MEMA_5")
	)
	(segment
		(start 33.973516 -139.74572)
		(end 33.973516 -140.14069)
		(width 0.127)
		(layer "In2.Cu")
		(net "MEMA_5")
	)
	(segment
		(start 35.624516 -139.31392)
		(end 35.878516 -139.31392)
		(width 0.127)
		(layer "In2.Cu")
		(net "MEMA_5")
	)
	(segment
		(start 36.132516 -140.26769)
		(end 36.386516 -140.26769)
		(width 0.127)
		(layer "In2.Cu")
		(net "MEMA_5")
	)
	(segment
		(start 41.699688 -142.199868)
		(end 41.699942 -142.199868)
		(width 0.127)
		(layer "F.Cu")
		(net "MEMA_4")
	)
	(segment
		(start 19.07413 -139.000738)
		(end 19.26844 -138.806428)
		(width 0.127)
		(layer "F.Cu")
		(net "MEMA_4")
	)
	(segment
		(start 19.26844 -137.8077)
		(end 19.179032 -137.718292)
		(width 0.127)
		(layer "F.Cu")
		(net "MEMA_4")
	)
	(segment
		(start 41.299892 -141.800072)
		(end 41.699688 -142.199868)
		(width 0.127)
		(layer "F.Cu")
		(net "MEMA_4")
	)
	(segment
		(start 18.434558 -138.961622)
		(end 18.473674 -139.000738)
		(width 0.127)
		(layer "F.Cu")
		(net "MEMA_4")
	)
	(segment
		(start 18.473674 -139.000738)
		(end 19.07413 -139.000738)
		(width 0.127)
		(layer "F.Cu")
		(net "MEMA_4")
	)
	(segment
		(start 19.26844 -138.806428)
		(end 19.26844 -137.8077)
		(width 0.127)
		(layer "F.Cu")
		(net "MEMA_4")
	)
	(via
		(at 19.179032 -137.718292)
		(size 0.508)
		(drill 0.254)
		(layers "F.Cu" "B.Cu")
		(net "MEMA_4")
	)
	(via
		(at 41.299892 -141.800072)
		(size 0.4572)
		(drill 0.2032)
		(layers "F.Cu" "B.Cu")
		(net "MEMA_4")
	)
	(segment
		(start 15.279624 -133.763512)
		(end 15.406624 -133.890512)
		(width 0.127)
		(layer "B.Cu")
		(net "MEMA_4")
	)
	(segment
		(start 14.898624 -134.42823)
		(end 14.898624 -133.890512)
		(width 0.127)
		(layer "B.Cu")
		(net "MEMA_4")
	)
	(segment
		(start 11.647424 -133.85673)
		(end 11.647424 -134.075424)
		(width 0.127)
		(layer "B.Cu")
		(net "MEMA_4")
	)
	(segment
		(start 18.453608 -136.792208)
		(end 19.179032 -137.517632)
		(width 0.127)
		(layer "B.Cu")
		(net "MEMA_4")
	)
	(segment
		(start 12.12723 -134.55523)
		(end 14.771624 -134.55523)
		(width 0.127)
		(layer "B.Cu")
		(net "MEMA_4")
	)
	(segment
		(start 15.025624 -133.763512)
		(end 15.279624 -133.763512)
		(width 0.127)
		(layer "B.Cu")
		(net "MEMA_4")
	)
	(segment
		(start 18.208244 -136.542526)
		(end 18.453608 -136.78789)
		(width 0.127)
		(layer "B.Cu")
		(net "MEMA_4")
	)
	(segment
		(start 19.179032 -137.517632)
		(end 19.179032 -137.718292)
		(width 0.127)
		(layer "B.Cu")
		(net "MEMA_4")
	)
	(segment
		(start 10.64895 -133.85673)
		(end 11.647424 -133.85673)
		(width 0.127)
		(layer "B.Cu")
		(net "MEMA_4")
	)
	(segment
		(start 14.898624 -133.890512)
		(end 15.025624 -133.763512)
		(width 0.127)
		(layer "B.Cu")
		(net "MEMA_4")
	)
	(segment
		(start 15.533624 -134.55523)
		(end 16.21663 -134.55523)
		(width 0.127)
		(layer "B.Cu")
		(net "MEMA_4")
	)
	(segment
		(start 14.771624 -134.55523)
		(end 14.898624 -134.42823)
		(width 0.127)
		(layer "B.Cu")
		(net "MEMA_4")
	)
	(segment
		(start 11.647424 -134.075424)
		(end 12.12723 -134.55523)
		(width 0.127)
		(layer "B.Cu")
		(net "MEMA_4")
	)
	(segment
		(start 16.21663 -134.55523)
		(end 18.203926 -136.542526)
		(width 0.127)
		(layer "B.Cu")
		(net "MEMA_4")
	)
	(segment
		(start 15.406624 -133.890512)
		(end 15.406624 -134.42823)
		(width 0.127)
		(layer "B.Cu")
		(net "MEMA_4")
	)
	(segment
		(start 18.453608 -136.78789)
		(end 18.453608 -136.792208)
		(width 0.127)
		(layer "B.Cu")
		(net "MEMA_4")
	)
	(segment
		(start 15.406624 -134.42823)
		(end 15.533624 -134.55523)
		(width 0.127)
		(layer "B.Cu")
		(net "MEMA_4")
	)
	(segment
		(start 18.203926 -136.542526)
		(end 18.208244 -136.542526)
		(width 0.127)
		(layer "B.Cu")
		(net "MEMA_4")
	)
	(segment
		(start 22.996398 -135.756142)
		(end 23.123398 -135.629142)
		(width 0.127)
		(layer "In5.Cu")
		(net "MEMA_4")
	)
	(segment
		(start 21.065998 -135.629142)
		(end 21.345398 -135.629142)
		(width 0.127)
		(layer "In5.Cu")
		(net "MEMA_4")
	)
	(segment
		(start 21.853398 -136.25068)
		(end 21.980398 -136.12368)
		(width 0.127)
		(layer "In5.Cu")
		(net "MEMA_4")
	)
	(segment
		(start 21.980398 -135.756142)
		(end 22.107398 -135.629142)
		(width 0.127)
		(layer "In5.Cu")
		(net "MEMA_4")
	)
	(segment
		(start 22.488398 -135.756142)
		(end 22.488398 -136.12368)
		(width 0.127)
		(layer "In5.Cu")
		(net "MEMA_4")
	)
	(segment
		(start 23.123398 -135.629142)
		(end 23.766018 -135.629142)
		(width 0.127)
		(layer "In5.Cu")
		(net "MEMA_4")
	)
	(segment
		(start 21.472398 -136.12368)
		(end 21.599398 -136.25068)
		(width 0.127)
		(layer "In5.Cu")
		(net "MEMA_4")
	)
	(segment
		(start 22.107398 -135.629142)
		(end 22.361398 -135.629142)
		(width 0.127)
		(layer "In5.Cu")
		(net "MEMA_4")
	)
	(segment
		(start 38.411658 -139.521692)
		(end 40.097202 -141.207236)
		(width 0.127)
		(layer "In5.Cu")
		(net "MEMA_4")
	)
	(segment
		(start 29.508704 -137.7061)
		(end 30.369002 -137.7061)
		(width 0.127)
		(layer "In5.Cu")
		(net "MEMA_4")
	)
	(segment
		(start 21.980398 -136.12368)
		(end 21.980398 -135.756142)
		(width 0.127)
		(layer "In5.Cu")
		(net "MEMA_4")
	)
	(segment
		(start 22.488398 -136.12368)
		(end 22.615398 -136.25068)
		(width 0.127)
		(layer "In5.Cu")
		(net "MEMA_4")
	)
	(segment
		(start 32.420306 -138.9126)
		(end 33.029398 -139.521692)
		(width 0.127)
		(layer "In5.Cu")
		(net "MEMA_4")
	)
	(segment
		(start 21.345398 -135.629142)
		(end 21.472398 -135.756142)
		(width 0.127)
		(layer "In5.Cu")
		(net "MEMA_4")
	)
	(segment
		(start 22.361398 -135.629142)
		(end 22.488398 -135.756142)
		(width 0.127)
		(layer "In5.Cu")
		(net "MEMA_4")
	)
	(segment
		(start 30.369002 -137.7061)
		(end 31.575502 -138.9126)
		(width 0.127)
		(layer "In5.Cu")
		(net "MEMA_4")
	)
	(segment
		(start 22.615398 -136.25068)
		(end 22.869398 -136.25068)
		(width 0.127)
		(layer "In5.Cu")
		(net "MEMA_4")
	)
	(segment
		(start 21.472398 -135.756142)
		(end 21.472398 -136.12368)
		(width 0.127)
		(layer "In5.Cu")
		(net "MEMA_4")
	)
	(segment
		(start 23.766018 -135.629142)
		(end 24.666956 -136.53008)
		(width 0.127)
		(layer "In5.Cu")
		(net "MEMA_4")
	)
	(segment
		(start 33.029398 -139.521692)
		(end 38.411658 -139.521692)
		(width 0.127)
		(layer "In5.Cu")
		(net "MEMA_4")
	)
	(segment
		(start 24.666956 -136.53008)
		(end 28.332684 -136.53008)
		(width 0.127)
		(layer "In5.Cu")
		(net "MEMA_4")
	)
	(segment
		(start 19.179032 -137.718292)
		(end 19.179032 -137.516108)
		(width 0.127)
		(layer "In5.Cu")
		(net "MEMA_4")
	)
	(segment
		(start 41.054782 -141.554962)
		(end 41.299892 -141.800072)
		(width 0.127)
		(layer "In5.Cu")
		(net "MEMA_4")
	)
	(segment
		(start 19.179032 -137.516108)
		(end 21.065998 -135.629142)
		(width 0.127)
		(layer "In5.Cu")
		(net "MEMA_4")
	)
	(segment
		(start 28.332684 -136.53008)
		(end 29.508704 -137.7061)
		(width 0.127)
		(layer "In5.Cu")
		(net "MEMA_4")
	)
	(segment
		(start 31.575502 -138.9126)
		(end 32.420306 -138.9126)
		(width 0.127)
		(layer "In5.Cu")
		(net "MEMA_4")
	)
	(segment
		(start 21.599398 -136.25068)
		(end 21.853398 -136.25068)
		(width 0.127)
		(layer "In5.Cu")
		(net "MEMA_4")
	)
	(segment
		(start 22.869398 -136.25068)
		(end 22.996398 -136.12368)
		(width 0.127)
		(layer "In5.Cu")
		(net "MEMA_4")
	)
	(segment
		(start 22.996398 -136.12368)
		(end 22.996398 -135.756142)
		(width 0.127)
		(layer "In5.Cu")
		(net "MEMA_4")
	)
	(arc
		(start 40.097202 -141.207236)
		(mid 40.339618 -141.385575)
		(end 40.63873 -141.418564)
		(width 0.127)
		(layer "In5.Cu")
		(net "MEMA_4")
	)
	(arc
		(start 40.63873 -141.418564)
		(mid 40.863055 -141.43707)
		(end 41.054782 -141.554962)
		(width 0.127)
		(layer "In5.Cu")
		(net "MEMA_4")
	)
	(segment
		(start 21.2344 -138.561572)
		(end 21.63445 -138.961622)
		(width 0.127)
		(layer "F.Cu")
		(net "MEMA_3")
	)
	(segment
		(start 43.299888 -142.999968)
		(end 43.699938 -142.599918)
		(width 0.127)
		(layer "F.Cu")
		(net "MEMA_3")
	)
	(via
		(at 43.699938 -142.599918)
		(size 0.4572)
		(drill 0.2032)
		(layers "F.Cu" "B.Cu")
		(net "MEMA_3")
	)
	(via
		(at 21.2344 -138.561572)
		(size 0.508)
		(drill 0.254)
		(layers "F.Cu" "B.Cu")
		(net "MEMA_3")
	)
	(segment
		(start 17.723612 -129.521458)
		(end 17.749012 -129.496058)
		(width 0.127)
		(layer "B.Cu")
		(net "MEMA_3")
	)
	(segment
		(start 18.957036 -134.491984)
		(end 18.957036 -134.745984)
		(width 0.127)
		(layer "B.Cu")
		(net "MEMA_3")
	)
	(segment
		(start 19.084036 -134.872984)
		(end 19.325844 -134.872984)
		(width 0.127)
		(layer "B.Cu")
		(net "MEMA_3")
	)
	(segment
		(start 19.452844 -134.237984)
		(end 19.325844 -134.364984)
		(width 0.127)
		(layer "B.Cu")
		(net "MEMA_3")
	)
	(segment
		(start 18.422112 -132.72516)
		(end 19.452844 -133.755892)
		(width 0.127)
		(layer "B.Cu")
		(net "MEMA_3")
	)
	(segment
		(start 19.685 -137.012172)
		(end 21.2344 -138.561572)
		(width 0.127)
		(layer "B.Cu")
		(net "MEMA_3")
	)
	(segment
		(start 19.325844 -134.872984)
		(end 19.452844 -134.999984)
		(width 0.127)
		(layer "B.Cu")
		(net "MEMA_3")
	)
	(segment
		(start 19.325844 -134.364984)
		(end 19.084036 -134.364984)
		(width 0.127)
		(layer "B.Cu")
		(net "MEMA_3")
	)
	(segment
		(start 18.422112 -131.162298)
		(end 18.422112 -132.72516)
		(width 0.127)
		(layer "B.Cu")
		(net "MEMA_3")
	)
	(segment
		(start 19.084036 -134.364984)
		(end 18.957036 -134.491984)
		(width 0.127)
		(layer "B.Cu")
		(net "MEMA_3")
	)
	(segment
		(start 19.452844 -134.999984)
		(end 19.452844 -135.30326)
		(width 0.127)
		(layer "B.Cu")
		(net "MEMA_3")
	)
	(segment
		(start 18.013172 -130.753358)
		(end 18.422112 -131.162298)
		(width 0.127)
		(layer "B.Cu")
		(net "MEMA_3")
	)
	(segment
		(start 17.723612 -130.562858)
		(end 17.723612 -129.521458)
		(width 0.127)
		(layer "B.Cu")
		(net "MEMA_3")
	)
	(segment
		(start 17.723612 -130.562858)
		(end 17.914112 -130.753358)
		(width 0.127)
		(layer "B.Cu")
		(net "MEMA_3")
	)
	(segment
		(start 19.685 -135.535416)
		(end 19.685 -137.012172)
		(width 0.127)
		(layer "B.Cu")
		(net "MEMA_3")
	)
	(segment
		(start 18.957036 -134.745984)
		(end 19.084036 -134.872984)
		(width 0.127)
		(layer "B.Cu")
		(net "MEMA_3")
	)
	(segment
		(start 17.914112 -130.753358)
		(end 18.013172 -130.753358)
		(width 0.127)
		(layer "B.Cu")
		(net "MEMA_3")
	)
	(segment
		(start 19.452844 -133.755892)
		(end 19.452844 -134.237984)
		(width 0.127)
		(layer "B.Cu")
		(net "MEMA_3")
	)
	(segment
		(start 19.452844 -135.30326)
		(end 19.685 -135.535416)
		(width 0.127)
		(layer "B.Cu")
		(net "MEMA_3")
	)
	(segment
		(start 40.650668 -142.193518)
		(end 39.29634 -142.193518)
		(width 0.127)
		(layer "In2.Cu")
		(net "MEMA_3")
	)
	(segment
		(start 38.48354 -140.79982)
		(end 34.26206 -140.79982)
		(width 0.127)
		(layer "In2.Cu")
		(net "MEMA_3")
	)
	(segment
		(start 40.906192 -142.449042)
		(end 40.650668 -142.193518)
		(width 0.127)
		(layer "In2.Cu")
		(net "MEMA_3")
	)
	(segment
		(start 32.427672 -141.4907)
		(end 32.300672 -141.3637)
		(width 0.127)
		(layer "In2.Cu")
		(net "MEMA_3")
	)
	(segment
		(start 39.09568 -141.992858)
		(end 39.09568 -141.41196)
		(width 0.127)
		(layer "In2.Cu")
		(net "MEMA_3")
	)
	(segment
		(start 32.300672 -141.3637)
		(end 32.046672 -141.3637)
		(width 0.127)
		(layer "In2.Cu")
		(net "MEMA_3")
	)
	(segment
		(start 39.09568 -141.41196)
		(end 38.48354 -140.79982)
		(width 0.127)
		(layer "In2.Cu")
		(net "MEMA_3")
	)
	(segment
		(start 31.919672 -141.4907)
		(end 31.919672 -141.964918)
		(width 0.127)
		(layer "In2.Cu")
		(net "MEMA_3")
	)
	(segment
		(start 34.26206 -140.79982)
		(end 34.13506 -140.92682)
		(width 0.127)
		(layer "In2.Cu")
		(net "MEMA_3")
	)
	(segment
		(start 28.848812 -141.822678)
		(end 27.067764 -140.04163)
		(width 0.127)
		(layer "In2.Cu")
		(net "MEMA_3")
	)
	(segment
		(start 31.919672 -141.964918)
		(end 31.792672 -142.091918)
		(width 0.127)
		(layer "In2.Cu")
		(net "MEMA_3")
	)
	(segment
		(start 26.471372 -140.04163)
		(end 25.88006 -139.450318)
		(width 0.127)
		(layer "In2.Cu")
		(net "MEMA_3")
	)
	(segment
		(start 25.88006 -139.450318)
		(end 24.426164 -139.450318)
		(width 0.127)
		(layer "In2.Cu")
		(net "MEMA_3")
	)
	(segment
		(start 34.13506 -140.92682)
		(end 34.13506 -141.95044)
		(width 0.127)
		(layer "In2.Cu")
		(net "MEMA_3")
	)
	(segment
		(start 24.426164 -139.450318)
		(end 24.356568 -139.380722)
		(width 0.127)
		(layer "In2.Cu")
		(net "MEMA_3")
	)
	(segment
		(start 33.443672 -141.964918)
		(end 33.443672 -140.95984)
		(width 0.127)
		(layer "In2.Cu")
		(net "MEMA_3")
	)
	(segment
		(start 41.13657 -142.993618)
		(end 40.906192 -142.76324)
		(width 0.127)
		(layer "In2.Cu")
		(net "MEMA_3")
	)
	(segment
		(start 32.808672 -142.091918)
		(end 32.554672 -142.091918)
		(width 0.127)
		(layer "In2.Cu")
		(net "MEMA_3")
	)
	(segment
		(start 27.067764 -140.04163)
		(end 26.471372 -140.04163)
		(width 0.127)
		(layer "In2.Cu")
		(net "MEMA_3")
	)
	(segment
		(start 22.05355 -139.380722)
		(end 21.2344 -138.561572)
		(width 0.127)
		(layer "In2.Cu")
		(net "MEMA_3")
	)
	(segment
		(start 43.699938 -142.599918)
		(end 43.306238 -142.993618)
		(width 0.127)
		(layer "In2.Cu")
		(net "MEMA_3")
	)
	(segment
		(start 30.168342 -142.091918)
		(end 29.899102 -141.822678)
		(width 0.127)
		(layer "In2.Cu")
		(net "MEMA_3")
	)
	(segment
		(start 31.792672 -142.091918)
		(end 30.168342 -142.091918)
		(width 0.127)
		(layer "In2.Cu")
		(net "MEMA_3")
	)
	(segment
		(start 33.316672 -140.83284)
		(end 33.062672 -140.83284)
		(width 0.127)
		(layer "In2.Cu")
		(net "MEMA_3")
	)
	(segment
		(start 33.443672 -140.95984)
		(end 33.316672 -140.83284)
		(width 0.127)
		(layer "In2.Cu")
		(net "MEMA_3")
	)
	(segment
		(start 32.554672 -142.091918)
		(end 32.427672 -141.964918)
		(width 0.127)
		(layer "In2.Cu")
		(net "MEMA_3")
	)
	(segment
		(start 40.906192 -142.76324)
		(end 40.906192 -142.449042)
		(width 0.127)
		(layer "In2.Cu")
		(net "MEMA_3")
	)
	(segment
		(start 32.046672 -141.3637)
		(end 31.919672 -141.4907)
		(width 0.127)
		(layer "In2.Cu")
		(net "MEMA_3")
	)
	(segment
		(start 32.935672 -141.964918)
		(end 32.808672 -142.091918)
		(width 0.127)
		(layer "In2.Cu")
		(net "MEMA_3")
	)
	(segment
		(start 43.306238 -142.993618)
		(end 41.13657 -142.993618)
		(width 0.127)
		(layer "In2.Cu")
		(net "MEMA_3")
	)
	(segment
		(start 33.993582 -142.091918)
		(end 33.570672 -142.091918)
		(width 0.127)
		(layer "In2.Cu")
		(net "MEMA_3")
	)
	(segment
		(start 34.13506 -141.95044)
		(end 33.993582 -142.091918)
		(width 0.127)
		(layer "In2.Cu")
		(net "MEMA_3")
	)
	(segment
		(start 32.427672 -141.964918)
		(end 32.427672 -141.4907)
		(width 0.127)
		(layer "In2.Cu")
		(net "MEMA_3")
	)
	(segment
		(start 29.899102 -141.822678)
		(end 28.848812 -141.822678)
		(width 0.127)
		(layer "In2.Cu")
		(net "MEMA_3")
	)
	(segment
		(start 33.062672 -140.83284)
		(end 32.935672 -140.95984)
		(width 0.127)
		(layer "In2.Cu")
		(net "MEMA_3")
	)
	(segment
		(start 24.356568 -139.380722)
		(end 22.05355 -139.380722)
		(width 0.127)
		(layer "In2.Cu")
		(net "MEMA_3")
	)
	(segment
		(start 33.570672 -142.091918)
		(end 33.443672 -141.964918)
		(width 0.127)
		(layer "In2.Cu")
		(net "MEMA_3")
	)
	(segment
		(start 39.29634 -142.193518)
		(end 39.09568 -141.992858)
		(width 0.127)
		(layer "In2.Cu")
		(net "MEMA_3")
	)
	(segment
		(start 32.935672 -140.95984)
		(end 32.935672 -141.964918)
		(width 0.127)
		(layer "In2.Cu")
		(net "MEMA_3")
	)
	(segment
		(start 41.699942 -142.999968)
		(end 42.099992 -142.599918)
		(width 0.127)
		(layer "F.Cu")
		(net "MEMA_2")
	)
	(segment
		(start 18.434558 -137.361676)
		(end 18.815304 -136.98093)
		(width 0.127)
		(layer "F.Cu")
		(net "MEMA_2")
	)
	(segment
		(start 18.815304 -136.98093)
		(end 18.815304 -136.135364)
		(width 0.127)
		(layer "F.Cu")
		(net "MEMA_2")
	)
	(via
		(at 42.099992 -142.599918)
		(size 0.4572)
		(drill 0.2032)
		(layers "F.Cu" "B.Cu")
		(net "MEMA_2")
	)
	(via
		(at 18.815304 -136.135364)
		(size 0.508)
		(drill 0.254)
		(layers "F.Cu" "B.Cu")
		(net "MEMA_2")
	)
	(segment
		(start 15.046198 -132.398516)
		(end 15.173198 -132.525516)
		(width 0.127)
		(layer "B.Cu")
		(net "MEMA_2")
	)
	(segment
		(start 11.647424 -132.402326)
		(end 11.647424 -132.501386)
		(width 0.127)
		(layer "B.Cu")
		(net "MEMA_2")
	)
	(segment
		(start 14.665198 -133.03123)
		(end 14.665198 -132.525516)
		(width 0.127)
		(layer "B.Cu")
		(net "MEMA_2")
	)
	(segment
		(start 12.304268 -133.15823)
		(end 14.538198 -133.15823)
		(width 0.127)
		(layer "B.Cu")
		(net "MEMA_2")
	)
	(segment
		(start 15.173198 -133.03123)
		(end 15.300198 -133.15823)
		(width 0.127)
		(layer "B.Cu")
		(net "MEMA_2")
	)
	(segment
		(start 10.638028 -132.402834)
		(end 11.646916 -132.402834)
		(width 0.127)
		(layer "B.Cu")
		(net "MEMA_2")
	)
	(segment
		(start 14.792198 -132.398516)
		(end 15.046198 -132.398516)
		(width 0.127)
		(layer "B.Cu")
		(net "MEMA_2")
	)
	(segment
		(start 11.646916 -132.402834)
		(end 11.647424 -132.402326)
		(width 0.127)
		(layer "B.Cu")
		(net "MEMA_2")
	)
	(segment
		(start 14.538198 -133.15823)
		(end 14.665198 -133.03123)
		(width 0.127)
		(layer "B.Cu")
		(net "MEMA_2")
	)
	(segment
		(start 11.647424 -132.501386)
		(end 12.304268 -133.15823)
		(width 0.127)
		(layer "B.Cu")
		(net "MEMA_2")
	)
	(segment
		(start 15.173198 -132.525516)
		(end 15.173198 -133.03123)
		(width 0.127)
		(layer "B.Cu")
		(net "MEMA_2")
	)
	(segment
		(start 15.300198 -133.15823)
		(end 15.83817 -133.15823)
		(width 0.127)
		(layer "B.Cu")
		(net "MEMA_2")
	)
	(segment
		(start 15.83817 -133.15823)
		(end 18.815304 -136.135364)
		(width 0.127)
		(layer "B.Cu")
		(net "MEMA_2")
	)
	(segment
		(start 14.665198 -132.525516)
		(end 14.792198 -132.398516)
		(width 0.127)
		(layer "B.Cu")
		(net "MEMA_2")
	)
	(segment
		(start 41.680638 -140.842238)
		(end 41.681146 -140.842746)
		(width 0.1016)
		(layer "In5.Cu")
		(net "MEMA_2")
	)
	(segment
		(start 41.681146 -141.629638)
		(end 41.680892 -141.629892)
		(width 0.1016)
		(layer "In5.Cu")
		(net "MEMA_2")
	)
	(segment
		(start 41.457626 -140.618972)
		(end 41.680638 -140.841984)
		(width 0.1016)
		(layer "In5.Cu")
		(net "MEMA_2")
	)
	(segment
		(start 34.983674 -135.255)
		(end 35.980624 -136.25195)
		(width 0.127)
		(layer "In5.Cu")
		(net "MEMA_2")
	)
	(segment
		(start 41.680638 -140.841984)
		(end 41.680638 -140.842238)
		(width 0.1016)
		(layer "In5.Cu")
		(net "MEMA_2")
	)
	(segment
		(start 41.681146 -140.842746)
		(end 41.681146 -141.629638)
		(width 0.1016)
		(layer "In5.Cu")
		(net "MEMA_2")
	)
	(segment
		(start 18.815304 -136.135364)
		(end 18.815304 -136.009634)
		(width 0.127)
		(layer "In5.Cu")
		(net "MEMA_2")
	)
	(segment
		(start 35.980624 -136.25195)
		(end 35.985704 -136.25195)
		(width 0.127)
		(layer "In5.Cu")
		(net "MEMA_2")
	)
	(segment
		(start 41.680892 -141.629892)
		(end 41.680892 -142.010638)
		(width 0.1016)
		(layer "In5.Cu")
		(net "MEMA_2")
	)
	(segment
		(start 41.680892 -142.010638)
		(end 42.099992 -142.429738)
		(width 0.1016)
		(layer "In5.Cu")
		(net "MEMA_2")
	)
	(segment
		(start 42.099992 -142.429738)
		(end 42.099992 -142.599918)
		(width 0.1016)
		(layer "In5.Cu")
		(net "MEMA_2")
	)
	(segment
		(start 40.352726 -140.618972)
		(end 41.457626 -140.618972)
		(width 0.1016)
		(layer "In5.Cu")
		(net "MEMA_2")
	)
	(segment
		(start 21.100542 -133.724396)
		(end 28.401264 -133.724396)
		(width 0.127)
		(layer "In5.Cu")
		(net "MEMA_2")
	)
	(segment
		(start 28.401264 -133.724396)
		(end 29.931868 -135.255)
		(width 0.127)
		(layer "In5.Cu")
		(net "MEMA_2")
	)
	(segment
		(start 35.985704 -136.25195)
		(end 40.10025 -140.366496)
		(width 0.127)
		(layer "In5.Cu")
		(net "MEMA_2")
	)
	(segment
		(start 29.931868 -135.255)
		(end 34.983674 -135.255)
		(width 0.127)
		(layer "In5.Cu")
		(net "MEMA_2")
	)
	(segment
		(start 40.10025 -140.366496)
		(end 40.352726 -140.618972)
		(width 0.1016)
		(layer "In5.Cu")
		(net "MEMA_2")
	)
	(segment
		(start 18.815304 -136.009634)
		(end 21.100542 -133.724396)
		(width 0.127)
		(layer "In5.Cu")
		(net "MEMA_2")
	)
	(segment
		(start 31.057088 -139.3317)
		(end 31.184088 -139.4587)
		(width 0.127)
		(layer "F.Cu")
		(net "MEMA_13")
	)
	(segment
		(start 32.073088 -138.64844)
		(end 32.073088 -139.28852)
		(width 0.127)
		(layer "F.Cu")
		(net "MEMA_13")
	)
	(segment
		(start 22.43455 -136.561576)
		(end 22.034754 -136.961372)
		(width 0.127)
		(layer "F.Cu")
		(net "MEMA_13")
	)
	(segment
		(start 31.565088 -138.64844)
		(end 31.692088 -138.52144)
		(width 0.127)
		(layer "F.Cu")
		(net "MEMA_13")
	)
	(segment
		(start 39.09568 -141.76502)
		(end 39.299896 -141.969236)
		(width 0.127)
		(layer "F.Cu")
		(net "MEMA_13")
	)
	(segment
		(start 32.200088 -139.41552)
		(end 32.454088 -139.41552)
		(width 0.127)
		(layer "F.Cu")
		(net "MEMA_13")
	)
	(segment
		(start 31.946088 -138.52144)
		(end 32.073088 -138.64844)
		(width 0.127)
		(layer "F.Cu")
		(net "MEMA_13")
	)
	(segment
		(start 30.37967 -136.962896)
		(end 30.540706 -136.80186)
		(width 0.127)
		(layer "F.Cu")
		(net "MEMA_13")
	)
	(segment
		(start 29.57576 -137.593832)
		(end 30.25267 -137.593832)
		(width 0.127)
		(layer "F.Cu")
		(net "MEMA_13")
	)
	(segment
		(start 29.44876 -137.974832)
		(end 29.44876 -137.720832)
		(width 0.127)
		(layer "F.Cu")
		(net "MEMA_13")
	)
	(segment
		(start 31.184088 -139.4587)
		(end 31.438088 -139.4587)
		(width 0.127)
		(layer "F.Cu")
		(net "MEMA_13")
	)
	(segment
		(start 29.57576 -138.101832)
		(end 29.44876 -137.974832)
		(width 0.127)
		(layer "F.Cu")
		(net "MEMA_13")
	)
	(segment
		(start 22.034754 -136.961372)
		(end 22.0345 -136.961372)
		(width 0.127)
		(layer "F.Cu")
		(net "MEMA_13")
	)
	(segment
		(start 33.606994 -139.318492)
		(end 36.053522 -141.76502)
		(width 0.127)
		(layer "F.Cu")
		(net "MEMA_13")
	)
	(segment
		(start 30.540706 -136.80186)
		(end 30.930088 -136.80186)
		(width 0.127)
		(layer "F.Cu")
		(net "MEMA_13")
	)
	(segment
		(start 31.057088 -136.92886)
		(end 31.057088 -139.3317)
		(width 0.127)
		(layer "F.Cu")
		(net "MEMA_13")
	)
	(segment
		(start 31.565088 -139.3317)
		(end 31.565088 -138.64844)
		(width 0.127)
		(layer "F.Cu")
		(net "MEMA_13")
	)
	(segment
		(start 30.930088 -136.80186)
		(end 31.057088 -136.92886)
		(width 0.127)
		(layer "F.Cu")
		(net "MEMA_13")
	)
	(segment
		(start 32.454088 -139.41552)
		(end 32.581088 -139.28852)
		(width 0.127)
		(layer "F.Cu")
		(net "MEMA_13")
	)
	(segment
		(start 31.692088 -138.52144)
		(end 31.946088 -138.52144)
		(width 0.127)
		(layer "F.Cu")
		(net "MEMA_13")
	)
	(segment
		(start 30.37967 -139.37107)
		(end 30.37967 -138.228832)
		(width 0.127)
		(layer "F.Cu")
		(net "MEMA_13")
	)
	(segment
		(start 31.438088 -139.4587)
		(end 31.565088 -139.3317)
		(width 0.127)
		(layer "F.Cu")
		(net "MEMA_13")
	)
	(segment
		(start 33.17748 -138.22172)
		(end 33.606994 -138.651234)
		(width 0.127)
		(layer "F.Cu")
		(net "MEMA_13")
	)
	(segment
		(start 30.25267 -138.101832)
		(end 29.57576 -138.101832)
		(width 0.127)
		(layer "F.Cu")
		(net "MEMA_13")
	)
	(segment
		(start 32.581088 -138.444478)
		(end 32.803846 -138.22172)
		(width 0.127)
		(layer "F.Cu")
		(net "MEMA_13")
	)
	(segment
		(start 36.053522 -141.76502)
		(end 39.09568 -141.76502)
		(width 0.127)
		(layer "F.Cu")
		(net "MEMA_13")
	)
	(segment
		(start 30.37967 -138.228832)
		(end 30.25267 -138.101832)
		(width 0.127)
		(layer "F.Cu")
		(net "MEMA_13")
	)
	(segment
		(start 30.37967 -137.466832)
		(end 30.37967 -136.962896)
		(width 0.127)
		(layer "F.Cu")
		(net "MEMA_13")
	)
	(segment
		(start 33.606994 -138.651234)
		(end 33.606994 -139.318492)
		(width 0.127)
		(layer "F.Cu")
		(net "MEMA_13")
	)
	(segment
		(start 32.581088 -139.28852)
		(end 32.581088 -138.444478)
		(width 0.127)
		(layer "F.Cu")
		(net "MEMA_13")
	)
	(segment
		(start 32.803846 -138.22172)
		(end 33.17748 -138.22172)
		(width 0.127)
		(layer "F.Cu")
		(net "MEMA_13")
	)
	(segment
		(start 29.44876 -137.720832)
		(end 29.57576 -137.593832)
		(width 0.127)
		(layer "F.Cu")
		(net "MEMA_13")
	)
	(segment
		(start 32.073088 -139.28852)
		(end 32.200088 -139.41552)
		(width 0.127)
		(layer "F.Cu")
		(net "MEMA_13")
	)
	(segment
		(start 30.25267 -137.593832)
		(end 30.37967 -137.466832)
		(width 0.127)
		(layer "F.Cu")
		(net "MEMA_13")
	)
	(segment
		(start 39.299896 -141.969236)
		(end 39.299896 -142.199868)
		(width 0.127)
		(layer "F.Cu")
		(net "MEMA_13")
	)
	(via
		(at 30.37967 -139.37107)
		(size 0.508)
		(drill 0.254)
		(layers "F.Cu" "B.Cu")
		(net "MEMA_13")
	)
	(via
		(at 22.0345 -136.961372)
		(size 0.508)
		(drill 0.254)
		(layers "F.Cu" "B.Cu")
		(net "MEMA_13")
	)
	(segment
		(start 22.201886 -130.753358)
		(end 22.011386 -130.562858)
		(width 0.127)
		(layer "B.Cu")
		(net "MEMA_13")
	)
	(segment
		(start 22.300946 -130.753358)
		(end 22.201886 -130.753358)
		(width 0.127)
		(layer "B.Cu")
		(net "MEMA_13")
	)
	(segment
		(start 22.634448 -134.903718)
		(end 22.507448 -134.776718)
		(width 0.127)
		(layer "B.Cu")
		(net "MEMA_13")
	)
	(segment
		(start 22.0345 -134.649718)
		(end 22.0345 -134.395718)
		(width 0.127)
		(layer "B.Cu")
		(net "MEMA_13")
	)
	(segment
		(start 22.215348 -133.595872)
		(end 22.215348 -133.19379)
		(width 0.127)
		(layer "B.Cu")
		(net "MEMA_13")
	)
	(segment
		(start 22.0345 -135.411718)
		(end 22.1615 -135.284718)
		(width 0.127)
		(layer "B.Cu")
		(net "MEMA_13")
	)
	(segment
		(start 22.0345 -134.395718)
		(end 22.1615 -134.268718)
		(width 0.127)
		(layer "B.Cu")
		(net "MEMA_13")
	)
	(segment
		(start 23.532592 -134.119874)
		(end 23.532592 -133.909562)
		(width 0.127)
		(layer "B.Cu")
		(net "MEMA_13")
	)
	(segment
		(start 23.532592 -133.909562)
		(end 23.383748 -133.760718)
		(width 0.127)
		(layer "B.Cu")
		(net "MEMA_13")
	)
	(segment
		(start 22.1615 -135.284718)
		(end 22.507448 -135.284718)
		(width 0.127)
		(layer "B.Cu")
		(net "MEMA_13")
	)
	(segment
		(start 22.0345 -136.961372)
		(end 22.0345 -135.411718)
		(width 0.127)
		(layer "B.Cu")
		(net "MEMA_13")
	)
	(segment
		(start 22.709886 -132.699252)
		(end 22.709886 -131.162298)
		(width 0.127)
		(layer "B.Cu")
		(net "MEMA_13")
	)
	(segment
		(start 23.383748 -133.760718)
		(end 22.380194 -133.760718)
		(width 0.127)
		(layer "B.Cu")
		(net "MEMA_13")
	)
	(segment
		(start 22.709886 -131.162298)
		(end 22.300946 -130.753358)
		(width 0.127)
		(layer "B.Cu")
		(net "MEMA_13")
	)
	(segment
		(start 22.1615 -134.268718)
		(end 23.383748 -134.268718)
		(width 0.127)
		(layer "B.Cu")
		(net "MEMA_13")
	)
	(segment
		(start 22.1615 -134.776718)
		(end 22.0345 -134.649718)
		(width 0.127)
		(layer "B.Cu")
		(net "MEMA_13")
	)
	(segment
		(start 22.011386 -129.556256)
		(end 22.014942 -129.5527)
		(width 0.127)
		(layer "B.Cu")
		(net "MEMA_13")
	)
	(segment
		(start 22.380194 -133.760718)
		(end 22.215348 -133.595872)
		(width 0.127)
		(layer "B.Cu")
		(net "MEMA_13")
	)
	(segment
		(start 22.507448 -134.776718)
		(end 22.1615 -134.776718)
		(width 0.127)
		(layer "B.Cu")
		(net "MEMA_13")
	)
	(segment
		(start 22.215348 -133.19379)
		(end 22.709886 -132.699252)
		(width 0.127)
		(layer "B.Cu")
		(net "MEMA_13")
	)
	(segment
		(start 22.011386 -130.562858)
		(end 22.011386 -129.556256)
		(width 0.127)
		(layer "B.Cu")
		(net "MEMA_13")
	)
	(segment
		(start 23.383748 -134.268718)
		(end 23.532592 -134.119874)
		(width 0.127)
		(layer "B.Cu")
		(net "MEMA_13")
	)
	(segment
		(start 22.634448 -135.157718)
		(end 22.634448 -134.903718)
		(width 0.127)
		(layer "B.Cu")
		(net "MEMA_13")
	)
	(segment
		(start 22.507448 -135.284718)
		(end 22.634448 -135.157718)
		(width 0.127)
		(layer "B.Cu")
		(net "MEMA_13")
	)
	(segment
		(start 23.33879 -137.253726)
		(end 24.261572 -137.253726)
		(width 0.127)
		(layer "In2.Cu")
		(net "MEMA_13")
	)
	(segment
		(start 24.426164 -137.418318)
		(end 27.49169 -137.418318)
		(width 0.127)
		(layer "In2.Cu")
		(net "MEMA_13")
	)
	(segment
		(start 30.338776 -139.411964)
		(end 30.37967 -139.37107)
		(width 0.127)
		(layer "In2.Cu")
		(net "MEMA_13")
	)
	(segment
		(start 23.231094 -137.361422)
		(end 23.33879 -137.253726)
		(width 0.127)
		(layer "In2.Cu")
		(net "MEMA_13")
	)
	(segment
		(start 27.49169 -137.418318)
		(end 29.485336 -139.411964)
		(width 0.127)
		(layer "In2.Cu")
		(net "MEMA_13")
	)
	(segment
		(start 24.261572 -137.253726)
		(end 24.426164 -137.418318)
		(width 0.127)
		(layer "In2.Cu")
		(net "MEMA_13")
	)
	(segment
		(start 22.43455 -137.361422)
		(end 23.231094 -137.361422)
		(width 0.0889)
		(layer "In2.Cu")
		(net "MEMA_13")
	)
	(segment
		(start 29.485336 -139.411964)
		(end 30.338776 -139.411964)
		(width 0.127)
		(layer "In2.Cu")
		(net "MEMA_13")
	)
	(segment
		(start 22.0345 -136.961372)
		(end 22.43455 -137.361422)
		(width 0.0889)
		(layer "In2.Cu")
		(net "MEMA_13")
	)
	(segment
		(start 21.63445 -139.761468)
		(end 21.548852 -139.67587)
		(width 0.127)
		(layer "F.Cu")
		(net "MEMA_12")
	)
	(segment
		(start 40.500046 -142.599918)
		(end 40.899842 -142.999714)
		(width 0.127)
		(layer "F.Cu")
		(net "MEMA_12")
	)
	(segment
		(start 20.93341 -139.67587)
		(end 20.644104 -139.386564)
		(width 0.127)
		(layer "F.Cu")
		(net "MEMA_12")
	)
	(segment
		(start 40.899842 -142.999714)
		(end 40.899842 -142.999968)
		(width 0.127)
		(layer "F.Cu")
		(net "MEMA_12")
	)
	(segment
		(start 21.548852 -139.67587)
		(end 20.93341 -139.67587)
		(width 0.127)
		(layer "F.Cu")
		(net "MEMA_12")
	)
	(via
		(at 20.644104 -139.386564)
		(size 0.508)
		(drill 0.254)
		(layers "F.Cu" "B.Cu")
		(net "MEMA_12")
	)
	(via
		(at 40.500046 -142.599918)
		(size 0.4572)
		(drill 0.2032)
		(layers "F.Cu" "B.Cu")
		(net "MEMA_12")
	)
	(segment
		(start 18.373598 -134.36981)
		(end 16.992854 -132.989066)
		(width 0.127)
		(layer "B.Cu")
		(net "MEMA_12")
	)
	(segment
		(start 16.992854 -131.162298)
		(end 16.393414 -130.562858)
		(width 0.127)
		(layer "B.Cu")
		(net "MEMA_12")
	)
	(segment
		(start 20.644104 -138.525504)
		(end 19.304 -137.1854)
		(width 0.127)
		(layer "B.Cu")
		(net "MEMA_12")
	)
	(segment
		(start 18.373598 -134.975092)
		(end 18.373598 -134.36981)
		(width 0.127)
		(layer "B.Cu")
		(net "MEMA_12")
	)
	(segment
		(start 20.644104 -139.386564)
		(end 20.644104 -138.525504)
		(width 0.127)
		(layer "B.Cu")
		(net "MEMA_12")
	)
	(segment
		(start 16.294354 -129.546858)
		(end 16.319754 -129.521458)
		(width 0.127)
		(layer "B.Cu")
		(net "MEMA_12")
	)
	(segment
		(start 16.992854 -132.989066)
		(end 16.992854 -131.162298)
		(width 0.127)
		(layer "B.Cu")
		(net "MEMA_12")
	)
	(segment
		(start 16.294354 -130.562858)
		(end 16.294354 -129.546858)
		(width 0.127)
		(layer "B.Cu")
		(net "MEMA_12")
	)
	(segment
		(start 19.304 -137.1854)
		(end 19.304 -135.905494)
		(width 0.127)
		(layer "B.Cu")
		(net "MEMA_12")
	)
	(segment
		(start 16.393414 -130.562858)
		(end 16.294354 -130.562858)
		(width 0.127)
		(layer "B.Cu")
		(net "MEMA_12")
	)
	(segment
		(start 19.304 -135.905494)
		(end 18.373598 -134.975092)
		(width 0.127)
		(layer "B.Cu")
		(net "MEMA_12")
	)
	(segment
		(start 34.77006 -142.091918)
		(end 37.81806 -142.091918)
		(width 0.127)
		(layer "In2.Cu")
		(net "MEMA_12")
	)
	(segment
		(start 40.500046 -142.599918)
		(end 39.2684 -142.599918)
		(width 0.127)
		(layer "In2.Cu")
		(net "MEMA_12")
	)
	(segment
		(start 24.12873 -139.609322)
		(end 20.866862 -139.609322)
		(width 0.127)
		(layer "In2.Cu")
		(net "MEMA_12")
	)
	(segment
		(start 29.957776 -142.599918)
		(end 29.688536 -142.330678)
		(width 0.127)
		(layer "In2.Cu")
		(net "MEMA_12")
	)
	(segment
		(start 39.2684 -142.599918)
		(end 38.2524 -141.583918)
		(width 0.127)
		(layer "In2.Cu")
		(net "MEMA_12")
	)
	(segment
		(start 29.688536 -142.330678)
		(end 28.638246 -142.330678)
		(width 0.127)
		(layer "In2.Cu")
		(net "MEMA_12")
	)
	(segment
		(start 37.94506 -142.472918)
		(end 37.81806 -142.599918)
		(width 0.127)
		(layer "In2.Cu")
		(net "MEMA_12")
	)
	(segment
		(start 38.2524 -141.583918)
		(end 34.77006 -141.583918)
		(width 0.127)
		(layer "In2.Cu")
		(net "MEMA_12")
	)
	(segment
		(start 34.64306 -141.964918)
		(end 34.77006 -142.091918)
		(width 0.127)
		(layer "In2.Cu")
		(net "MEMA_12")
	)
	(segment
		(start 34.77006 -141.583918)
		(end 34.64306 -141.710918)
		(width 0.127)
		(layer "In2.Cu")
		(net "MEMA_12")
	)
	(segment
		(start 24.495506 -139.976098)
		(end 24.12873 -139.609322)
		(width 0.127)
		(layer "In2.Cu")
		(net "MEMA_12")
	)
	(segment
		(start 28.638246 -142.330678)
		(end 26.857198 -140.54963)
		(width 0.127)
		(layer "In2.Cu")
		(net "MEMA_12")
	)
	(segment
		(start 37.81806 -142.599918)
		(end 29.957776 -142.599918)
		(width 0.127)
		(layer "In2.Cu")
		(net "MEMA_12")
	)
	(segment
		(start 20.866862 -139.609322)
		(end 20.644104 -139.386564)
		(width 0.127)
		(layer "In2.Cu")
		(net "MEMA_12")
	)
	(segment
		(start 26.857198 -140.54963)
		(end 26.260806 -140.54963)
		(width 0.127)
		(layer "In2.Cu")
		(net "MEMA_12")
	)
	(segment
		(start 37.94506 -142.218918)
		(end 37.94506 -142.472918)
		(width 0.127)
		(layer "In2.Cu")
		(net "MEMA_12")
	)
	(segment
		(start 37.81806 -142.091918)
		(end 37.94506 -142.218918)
		(width 0.127)
		(layer "In2.Cu")
		(net "MEMA_12")
	)
	(segment
		(start 34.64306 -141.710918)
		(end 34.64306 -141.964918)
		(width 0.127)
		(layer "In2.Cu")
		(net "MEMA_12")
	)
	(segment
		(start 26.260806 -140.54963)
		(end 25.687274 -139.976098)
		(width 0.127)
		(layer "In2.Cu")
		(net "MEMA_12")
	)
	(segment
		(start 25.687274 -139.976098)
		(end 24.495506 -139.976098)
		(width 0.127)
		(layer "In2.Cu")
		(net "MEMA_12")
	)
	(segment
		(start 34.797238 -141.227302)
		(end 34.61766 -141.047724)
		(width 0.127)
		(layer "F.Cu")
		(net "MEMA_11")
	)
	(segment
		(start 18.034508 -136.961626)
		(end 17.634458 -136.561576)
		(width 0.127)
		(layer "F.Cu")
		(net "MEMA_11")
	)
	(segment
		(start 34.437828 -141.047724)
		(end 34.307272 -141.17828)
		(width 0.127)
		(layer "F.Cu")
		(net "MEMA_11")
	)
	(segment
		(start 35.026092 -141.8971)
		(end 34.84626 -141.8971)
		(width 0.127)
		(layer "F.Cu")
		(net "MEMA_11")
	)
	(segment
		(start 34.797238 -141.407134)
		(end 34.797238 -141.227302)
		(width 0.127)
		(layer "F.Cu")
		(net "MEMA_11")
	)
	(segment
		(start 33.098994 -139.529058)
		(end 33.098994 -138.8618)
		(width 0.127)
		(layer "F.Cu")
		(net "MEMA_11")
	)
	(segment
		(start 34.12744 -141.17828)
		(end 33.947862 -140.998702)
		(width 0.127)
		(layer "F.Cu")
		(net "MEMA_11")
	)
	(segment
		(start 33.40862 -140.45946)
		(end 33.229042 -140.279882)
		(width 0.127)
		(layer "F.Cu")
		(net "MEMA_11")
	)
	(segment
		(start 35.33648 -141.766544)
		(end 35.156648 -141.766544)
		(width 0.127)
		(layer "F.Cu")
		(net "MEMA_11")
	)
	(segment
		(start 40.099234 -142.999968)
		(end 39.83228 -142.733014)
		(width 0.1016)
		(layer "F.Cu")
		(net "MEMA_11")
	)
	(segment
		(start 37.996114 -142.56004)
		(end 37.932614 -142.49654)
		(width 0.127)
		(layer "F.Cu")
		(net "MEMA_11")
	)
	(segment
		(start 33.588452 -140.45946)
		(end 33.40862 -140.45946)
		(width 0.127)
		(layer "F.Cu")
		(net "MEMA_11")
	)
	(segment
		(start 33.947862 -140.81887)
		(end 34.078418 -140.688314)
		(width 0.127)
		(layer "F.Cu")
		(net "MEMA_11")
	)
	(segment
		(start 33.229042 -140.10005)
		(end 33.359598 -139.969494)
		(width 0.127)
		(layer "F.Cu")
		(net "MEMA_11")
	)
	(segment
		(start 33.359598 -139.789662)
		(end 33.098994 -139.529058)
		(width 0.127)
		(layer "F.Cu")
		(net "MEMA_11")
	)
	(segment
		(start 33.229042 -140.279882)
		(end 33.229042 -140.10005)
		(width 0.127)
		(layer "F.Cu")
		(net "MEMA_11")
	)
	(segment
		(start 33.947862 -140.998702)
		(end 33.947862 -140.81887)
		(width 0.127)
		(layer "F.Cu")
		(net "MEMA_11")
	)
	(segment
		(start 40.099996 -142.999968)
		(end 40.099234 -142.999968)
		(width 0.1016)
		(layer "F.Cu")
		(net "MEMA_11")
	)
	(segment
		(start 37.932614 -142.49654)
		(end 36.066476 -142.49654)
		(width 0.127)
		(layer "F.Cu")
		(net "MEMA_11")
	)
	(segment
		(start 34.078418 -140.508482)
		(end 33.89884 -140.328904)
		(width 0.127)
		(layer "F.Cu")
		(net "MEMA_11")
	)
	(segment
		(start 33.359598 -139.969494)
		(end 33.359598 -139.789662)
		(width 0.127)
		(layer "F.Cu")
		(net "MEMA_11")
	)
	(segment
		(start 35.156648 -141.766544)
		(end 35.026092 -141.8971)
		(width 0.127)
		(layer "F.Cu")
		(net "MEMA_11")
	)
	(segment
		(start 39.414704 -142.56004)
		(end 37.996114 -142.56004)
		(width 0.127)
		(layer "F.Cu")
		(net "MEMA_11")
	)
	(segment
		(start 34.307272 -141.17828)
		(end 34.12744 -141.17828)
		(width 0.127)
		(layer "F.Cu")
		(net "MEMA_11")
	)
	(segment
		(start 34.666682 -141.717522)
		(end 34.666682 -141.53769)
		(width 0.127)
		(layer "F.Cu")
		(net "MEMA_11")
	)
	(segment
		(start 36.066476 -142.49654)
		(end 35.33648 -141.766544)
		(width 0.127)
		(layer "F.Cu")
		(net "MEMA_11")
	)
	(segment
		(start 34.666682 -141.53769)
		(end 34.797238 -141.407134)
		(width 0.127)
		(layer "F.Cu")
		(net "MEMA_11")
	)
	(segment
		(start 34.84626 -141.8971)
		(end 34.666682 -141.717522)
		(width 0.127)
		(layer "F.Cu")
		(net "MEMA_11")
	)
	(segment
		(start 34.078418 -140.688314)
		(end 34.078418 -140.508482)
		(width 0.127)
		(layer "F.Cu")
		(net "MEMA_11")
	)
	(segment
		(start 33.89884 -140.328904)
		(end 33.719008 -140.328904)
		(width 0.127)
		(layer "F.Cu")
		(net "MEMA_11")
	)
	(segment
		(start 34.61766 -141.047724)
		(end 34.437828 -141.047724)
		(width 0.127)
		(layer "F.Cu")
		(net "MEMA_11")
	)
	(segment
		(start 33.719008 -140.328904)
		(end 33.588452 -140.45946)
		(width 0.127)
		(layer "F.Cu")
		(net "MEMA_11")
	)
	(via
		(at 18.034508 -136.961626)
		(size 0.508)
		(drill 0.254)
		(layers "F.Cu" "B.Cu")
		(net "MEMA_11")
	)
	(via
		(at 33.098994 -138.8618)
		(size 0.508)
		(drill 0.254)
		(layers "F.Cu" "B.Cu")
		(net "MEMA_11")
	)
	(arc
		(start 39.83228 -142.733014)
		(mid 39.640709 -142.604947)
		(end 39.414704 -142.56004)
		(width 0.1016)
		(layer "F.Cu")
		(net "MEMA_11")
	)
	(segment
		(start 14.804898 -135.081518)
		(end 14.550898 -135.081518)
		(width 0.127)
		(layer "B.Cu")
		(net "MEMA_11")
	)
	(segment
		(start 10.64641 -135.290052)
		(end 11.64336 -135.290052)
		(width 0.127)
		(layer "B.Cu")
		(net "MEMA_11")
	)
	(segment
		(start 14.081252 -135.828278)
		(end 13.892784 -136.016746)
		(width 0.127)
		(layer "B.Cu")
		(net "MEMA_11")
	)
	(segment
		(start 14.423898 -135.701278)
		(end 14.296898 -135.828278)
		(width 0.127)
		(layer "B.Cu")
		(net "MEMA_11")
	)
	(segment
		(start 14.296898 -135.828278)
		(end 14.081252 -135.828278)
		(width 0.127)
		(layer "B.Cu")
		(net "MEMA_11")
	)
	(segment
		(start 15.439898 -135.208518)
		(end 15.439898 -135.701278)
		(width 0.127)
		(layer "B.Cu")
		(net "MEMA_11")
	)
	(segment
		(start 15.312898 -135.828278)
		(end 15.058898 -135.828278)
		(width 0.127)
		(layer "B.Cu")
		(net "MEMA_11")
	)
	(segment
		(start 15.947898 -135.208518)
		(end 15.820898 -135.081518)
		(width 0.127)
		(layer "B.Cu")
		(net "MEMA_11")
	)
	(segment
		(start 14.423898 -135.208518)
		(end 14.423898 -135.701278)
		(width 0.127)
		(layer "B.Cu")
		(net "MEMA_11")
	)
	(segment
		(start 11.64336 -135.290052)
		(end 11.647424 -135.285988)
		(width 0.127)
		(layer "B.Cu")
		(net "MEMA_11")
	)
	(segment
		(start 14.550898 -135.081518)
		(end 14.423898 -135.208518)
		(width 0.127)
		(layer "B.Cu")
		(net "MEMA_11")
	)
	(segment
		(start 14.931898 -135.701278)
		(end 14.931898 -135.208518)
		(width 0.127)
		(layer "B.Cu")
		(net "MEMA_11")
	)
	(segment
		(start 14.931898 -135.208518)
		(end 14.804898 -135.081518)
		(width 0.127)
		(layer "B.Cu")
		(net "MEMA_11")
	)
	(segment
		(start 12.039346 -136.016746)
		(end 11.647424 -135.624824)
		(width 0.127)
		(layer "B.Cu")
		(net "MEMA_11")
	)
	(segment
		(start 16.074898 -135.828278)
		(end 15.947898 -135.701278)
		(width 0.127)
		(layer "B.Cu")
		(net "MEMA_11")
	)
	(segment
		(start 18.034508 -136.961626)
		(end 16.90116 -135.828278)
		(width 0.127)
		(layer "B.Cu")
		(net "MEMA_11")
	)
	(segment
		(start 15.058898 -135.828278)
		(end 14.931898 -135.701278)
		(width 0.127)
		(layer "B.Cu")
		(net "MEMA_11")
	)
	(segment
		(start 15.566898 -135.081518)
		(end 15.439898 -135.208518)
		(width 0.127)
		(layer "B.Cu")
		(net "MEMA_11")
	)
	(segment
		(start 15.439898 -135.701278)
		(end 15.312898 -135.828278)
		(width 0.127)
		(layer "B.Cu")
		(net "MEMA_11")
	)
	(segment
		(start 13.892784 -136.016746)
		(end 12.039346 -136.016746)
		(width 0.127)
		(layer "B.Cu")
		(net "MEMA_11")
	)
	(segment
		(start 16.90116 -135.828278)
		(end 16.074898 -135.828278)
		(width 0.127)
		(layer "B.Cu")
		(net "MEMA_11")
	)
	(segment
		(start 15.820898 -135.081518)
		(end 15.566898 -135.081518)
		(width 0.127)
		(layer "B.Cu")
		(net "MEMA_11")
	)
	(segment
		(start 15.947898 -135.701278)
		(end 15.947898 -135.208518)
		(width 0.127)
		(layer "B.Cu")
		(net "MEMA_11")
	)
	(segment
		(start 11.647424 -135.624824)
		(end 11.647424 -135.285988)
		(width 0.127)
		(layer "B.Cu")
		(net "MEMA_11")
	)
	(segment
		(start 33.098994 -137.97026)
		(end 33.098994 -138.8618)
		(width 0.127)
		(layer "In5.Cu")
		(net "MEMA_11")
	)
	(segment
		(start 18.034508 -136.961626)
		(end 18.977102 -136.961626)
		(width 0.127)
		(layer "In5.Cu")
		(net "MEMA_11")
	)
	(segment
		(start 27.980132 -134.740396)
		(end 29.510736 -136.271)
		(width 0.127)
		(layer "In5.Cu")
		(net "MEMA_11")
	)
	(segment
		(start 33.63722 -137.71626)
		(end 33.51022 -137.84326)
		(width 0.127)
		(layer "In5.Cu")
		(net "MEMA_11")
	)
	(segment
		(start 21.198332 -134.740396)
		(end 27.980132 -134.740396)
		(width 0.127)
		(layer "In5.Cu")
		(net "MEMA_11")
	)
	(segment
		(start 31.206694 -137.10666)
		(end 33.51022 -137.10666)
		(width 0.127)
		(layer "In5.Cu")
		(net "MEMA_11")
	)
	(segment
		(start 29.510736 -136.271)
		(end 30.371034 -136.271)
		(width 0.127)
		(layer "In5.Cu")
		(net "MEMA_11")
	)
	(segment
		(start 30.371034 -136.271)
		(end 31.206694 -137.10666)
		(width 0.127)
		(layer "In5.Cu")
		(net "MEMA_11")
	)
	(segment
		(start 33.51022 -137.10666)
		(end 33.63722 -137.23366)
		(width 0.127)
		(layer "In5.Cu")
		(net "MEMA_11")
	)
	(segment
		(start 18.977102 -136.961626)
		(end 21.198332 -134.740396)
		(width 0.127)
		(layer "In5.Cu")
		(net "MEMA_11")
	)
	(segment
		(start 33.225994 -137.84326)
		(end 33.098994 -137.97026)
		(width 0.127)
		(layer "In5.Cu")
		(net "MEMA_11")
	)
	(segment
		(start 33.63722 -137.23366)
		(end 33.63722 -137.71626)
		(width 0.127)
		(layer "In5.Cu")
		(net "MEMA_11")
	)
	(segment
		(start 33.51022 -137.84326)
		(end 33.225994 -137.84326)
		(width 0.127)
		(layer "In5.Cu")
		(net "MEMA_11")
	)
	(segment
		(start 43.29938 -143.800068)
		(end 43.299888 -143.800068)
		(width 0.127)
		(layer "F.Cu")
		(net "MEMA_10")
	)
	(segment
		(start 18.819368 -140.146278)
		(end 18.922492 -140.146278)
		(width 0.127)
		(layer "F.Cu")
		(net "MEMA_10")
	)
	(segment
		(start 18.434558 -139.761468)
		(end 18.819368 -140.146278)
		(width 0.127)
		(layer "F.Cu")
		(net "MEMA_10")
	)
	(segment
		(start 42.89933 -143.400018)
		(end 43.29938 -143.800068)
		(width 0.127)
		(layer "F.Cu")
		(net "MEMA_10")
	)
	(via
		(at 18.922492 -140.146278)
		(size 0.508)
		(drill 0.254)
		(layers "F.Cu" "B.Cu")
		(net "MEMA_10")
	)
	(via
		(at 42.89933 -143.400018)
		(size 0.4572)
		(drill 0.2032)
		(layers "F.Cu" "B.Cu")
		(net "MEMA_10")
	)
	(segment
		(start 14.211808 -141.450822)
		(end 13.865098 -141.450822)
		(width 0.127)
		(layer "B.Cu")
		(net "MEMA_10")
	)
	(segment
		(start 13.608558 -141.707362)
		(end 11.880342 -141.707362)
		(width 0.127)
		(layer "B.Cu")
		(net "MEMA_10")
	)
	(segment
		(start 15.195296 -141.135608)
		(end 14.940026 -141.390878)
		(width 0.127)
		(layer "B.Cu")
		(net "MEMA_10")
	)
	(segment
		(start 18.75917 -140.3096)
		(end 16.637 -140.3096)
		(width 0.127)
		(layer "B.Cu")
		(net "MEMA_10")
	)
	(segment
		(start 14.940026 -141.390878)
		(end 14.940026 -142.37335)
		(width 0.127)
		(layer "B.Cu")
		(net "MEMA_10")
	)
	(segment
		(start 15.993364 -140.506704)
		(end 15.36446 -141.135608)
		(width 0.127)
		(layer "B.Cu")
		(net "MEMA_10")
	)
	(segment
		(start 16.439896 -140.506704)
		(end 15.993364 -140.506704)
		(width 0.127)
		(layer "B.Cu")
		(net "MEMA_10")
	)
	(segment
		(start 11.66749 -141.008862)
		(end 10.65149 -141.008862)
		(width 0.127)
		(layer "B.Cu")
		(net "MEMA_10")
	)
	(segment
		(start 14.559026 -142.50035)
		(end 14.432026 -142.37335)
		(width 0.127)
		(layer "B.Cu")
		(net "MEMA_10")
	)
	(segment
		(start 14.813026 -142.50035)
		(end 14.559026 -142.50035)
		(width 0.127)
		(layer "B.Cu")
		(net "MEMA_10")
	)
	(segment
		(start 15.36446 -141.135608)
		(end 15.195296 -141.135608)
		(width 0.127)
		(layer "B.Cu")
		(net "MEMA_10")
	)
	(segment
		(start 16.637 -140.3096)
		(end 16.439896 -140.506704)
		(width 0.127)
		(layer "B.Cu")
		(net "MEMA_10")
	)
	(segment
		(start 11.66749 -141.49451)
		(end 11.66749 -141.008862)
		(width 0.127)
		(layer "B.Cu")
		(net "MEMA_10")
	)
	(segment
		(start 14.432026 -142.37335)
		(end 14.432026 -141.67104)
		(width 0.127)
		(layer "B.Cu")
		(net "MEMA_10")
	)
	(segment
		(start 13.865098 -141.450822)
		(end 13.608558 -141.707362)
		(width 0.127)
		(layer "B.Cu")
		(net "MEMA_10")
	)
	(segment
		(start 11.880342 -141.707362)
		(end 11.66749 -141.49451)
		(width 0.127)
		(layer "B.Cu")
		(net "MEMA_10")
	)
	(segment
		(start 18.922492 -140.146278)
		(end 18.75917 -140.3096)
		(width 0.127)
		(layer "B.Cu")
		(net "MEMA_10")
	)
	(segment
		(start 14.940026 -142.37335)
		(end 14.813026 -142.50035)
		(width 0.127)
		(layer "B.Cu")
		(net "MEMA_10")
	)
	(segment
		(start 14.432026 -141.67104)
		(end 14.211808 -141.450822)
		(width 0.127)
		(layer "B.Cu")
		(net "MEMA_10")
	)
	(segment
		(start 21.400262 -140.561568)
		(end 19.337782 -140.561568)
		(width 0.0889)
		(layer "In5.Cu")
		(net "MEMA_10")
	)
	(segment
		(start 43.30573 -143.581628)
		(end 43.30573 -144.351248)
		(width 0.127)
		(layer "In5.Cu")
		(net "MEMA_10")
	)
	(segment
		(start 33.53435 -142.377414)
		(end 32.143954 -142.377414)
		(width 0.127)
		(layer "In5.Cu")
		(net "MEMA_10")
	)
	(segment
		(start 27.284934 -140.09624)
		(end 22.829266 -140.09624)
		(width 0.127)
		(layer "In5.Cu")
		(net "MEMA_10")
	)
	(segment
		(start 32.143954 -142.377414)
		(end 31.943548 -142.57782)
		(width 0.127)
		(layer "In5.Cu")
		(net "MEMA_10")
	)
	(segment
		(start 37.838634 -142.377668)
		(end 36.190936 -142.377668)
		(width 0.127)
		(layer "In5.Cu")
		(net "MEMA_10")
	)
	(segment
		(start 29.766514 -142.57782)
		(end 27.284934 -140.09624)
		(width 0.127)
		(layer "In5.Cu")
		(net "MEMA_10")
	)
	(segment
		(start 36.190936 -142.377668)
		(end 33.53435 -142.377414)
		(width 0.127)
		(layer "In5.Cu")
		(net "MEMA_10")
	)
	(segment
		(start 41.474644 -143.806164)
		(end 41.275508 -143.806164)
		(width 0.127)
		(layer "In5.Cu")
		(net "MEMA_10")
	)
	(segment
		(start 22.42439 -139.691364)
		(end 21.839936 -139.691364)
		(width 0.127)
		(layer "In5.Cu")
		(net "MEMA_10")
	)
	(segment
		(start 31.943548 -142.57782)
		(end 29.766514 -142.57782)
		(width 0.127)
		(layer "In5.Cu")
		(net "MEMA_10")
	)
	(segment
		(start 43.106848 -143.399764)
		(end 43.123866 -143.399764)
		(width 0.127)
		(layer "In5.Cu")
		(net "MEMA_10")
	)
	(segment
		(start 21.63445 -140.32738)
		(end 21.400262 -140.561568)
		(width 0.0889)
		(layer "In5.Cu")
		(net "MEMA_10")
	)
	(segment
		(start 21.839936 -139.691364)
		(end 21.63445 -139.89685)
		(width 0.0889)
		(layer "In5.Cu")
		(net "MEMA_10")
	)
	(segment
		(start 41.706292 -144.36344)
		(end 41.706292 -144.037812)
		(width 0.127)
		(layer "In5.Cu")
		(net "MEMA_10")
	)
	(segment
		(start 43.02633 -144.593818)
		(end 41.93667 -144.593818)
		(width 0.127)
		(layer "In5.Cu")
		(net "MEMA_10")
	)
	(segment
		(start 21.63445 -139.89685)
		(end 21.63445 -140.32738)
		(width 0.0889)
		(layer "In5.Cu")
		(net "MEMA_10")
	)
	(segment
		(start 19.337782 -140.561568)
		(end 18.922492 -140.146278)
		(width 0.0889)
		(layer "In5.Cu")
		(net "MEMA_10")
	)
	(segment
		(start 22.829266 -140.09624)
		(end 22.42439 -139.691364)
		(width 0.127)
		(layer "In5.Cu")
		(net "MEMA_10")
	)
	(segment
		(start 40.734234 -143.552164)
		(end 39.300404 -143.552164)
		(width 0.127)
		(layer "In5.Cu")
		(net "MEMA_10")
	)
	(segment
		(start 38.80993 -143.348964)
		(end 37.838634 -142.377668)
		(width 0.127)
		(layer "In5.Cu")
		(net "MEMA_10")
	)
	(segment
		(start 40.96893 -143.679164)
		(end 40.91813 -143.628364)
		(width 0.127)
		(layer "In5.Cu")
		(net "MEMA_10")
	)
	(arc
		(start 41.706292 -144.037812)
		(mid 41.638444 -143.874012)
		(end 41.474644 -143.806164)
		(width 0.127)
		(layer "In5.Cu")
		(net "MEMA_10")
	)
	(arc
		(start 41.275508 -143.806164)
		(mid 41.109585 -143.77316)
		(end 40.96893 -143.679164)
		(width 0.127)
		(layer "In5.Cu")
		(net "MEMA_10")
	)
	(arc
		(start 42.89933 -143.400018)
		(mid 43.003089 -143.399828)
		(end 43.106848 -143.399764)
		(width 0.127)
		(layer "In5.Cu")
		(net "MEMA_10")
	)
	(arc
		(start 43.123866 -143.399764)
		(mid 43.252463 -143.453031)
		(end 43.30573 -143.581628)
		(width 0.127)
		(layer "In5.Cu")
		(net "MEMA_10")
	)
	(arc
		(start 43.30573 -144.351248)
		(mid 43.211334 -144.524716)
		(end 43.02633 -144.593818)
		(width 0.127)
		(layer "In5.Cu")
		(net "MEMA_10")
	)
	(arc
		(start 41.93667 -144.593818)
		(mid 41.773768 -144.526342)
		(end 41.706292 -144.36344)
		(width 0.127)
		(layer "In5.Cu")
		(net "MEMA_10")
	)
	(arc
		(start 40.91813 -143.628364)
		(mid 40.833758 -143.571988)
		(end 40.734234 -143.552164)
		(width 0.127)
		(layer "In5.Cu")
		(net "MEMA_10")
	)
	(arc
		(start 39.300404 -143.552164)
		(mid 39.034946 -143.499361)
		(end 38.80993 -143.348964)
		(width 0.127)
		(layer "In5.Cu")
		(net "MEMA_10")
	)
	(segment
		(start 33.196276 -141.186662)
		(end 32.856932 -141.52626)
		(width 0.127)
		(layer "F.Cu")
		(net "MEMA_1")
	)
	(segment
		(start 32.721042 -140.532104)
		(end 33.196276 -141.007338)
		(width 0.127)
		(layer "F.Cu")
		(net "MEMA_1")
	)
	(segment
		(start 22.0345 -137.761472)
		(end 21.63445 -138.161522)
		(width 0.127)
		(layer "F.Cu")
		(net "MEMA_1")
	)
	(segment
		(start 35.193478 -143.00454)
		(end 36.504626 -143.00454)
		(width 0.127)
		(layer "F.Cu")
		(net "MEMA_1")
	)
	(segment
		(start 32.594042 -139.98194)
		(end 32.721042 -140.10894)
		(width 0.127)
		(layer "F.Cu")
		(net "MEMA_1")
	)
	(segment
		(start 32.721042 -140.10894)
		(end 32.721042 -140.532104)
		(width 0.127)
		(layer "F.Cu")
		(net "MEMA_1")
	)
	(segment
		(start 33.216342 -141.88567)
		(end 33.555686 -141.546072)
		(width 0.127)
		(layer "F.Cu")
		(net "MEMA_1")
	)
	(segment
		(start 33.196276 -141.007338)
		(end 33.196276 -141.186662)
		(width 0.127)
		(layer "F.Cu")
		(net "MEMA_1")
	)
	(segment
		(start 28.400756 -140.75918)
		(end 28.400756 -140.10894)
		(width 0.127)
		(layer "F.Cu")
		(net "MEMA_1")
	)
	(segment
		(start 28.527756 -140.88618)
		(end 28.400756 -140.75918)
		(width 0.127)
		(layer "F.Cu")
		(net "MEMA_1")
	)
	(segment
		(start 28.400756 -140.10894)
		(end 28.527756 -139.98194)
		(width 0.127)
		(layer "F.Cu")
		(net "MEMA_1")
	)
	(segment
		(start 32.856932 -141.705584)
		(end 33.037018 -141.88567)
		(width 0.127)
		(layer "F.Cu")
		(net "MEMA_1")
	)
	(segment
		(start 28.527756 -139.98194)
		(end 32.594042 -139.98194)
		(width 0.127)
		(layer "F.Cu")
		(net "MEMA_1")
	)
	(segment
		(start 33.555686 -141.546072)
		(end 33.73501 -141.546072)
		(width 0.127)
		(layer "F.Cu")
		(net "MEMA_1")
	)
	(segment
		(start 32.856932 -141.52626)
		(end 32.856932 -141.705584)
		(width 0.127)
		(layer "F.Cu")
		(net "MEMA_1")
	)
	(segment
		(start 33.73501 -141.546072)
		(end 35.193478 -143.00454)
		(width 0.127)
		(layer "F.Cu")
		(net "MEMA_1")
	)
	(segment
		(start 36.509198 -142.999968)
		(end 39.299896 -142.999968)
		(width 0.127)
		(layer "F.Cu")
		(net "MEMA_1")
	)
	(segment
		(start 32.089598 -140.73759)
		(end 31.941008 -140.88618)
		(width 0.127)
		(layer "F.Cu")
		(net "MEMA_1")
	)
	(segment
		(start 31.941008 -140.88618)
		(end 28.527756 -140.88618)
		(width 0.127)
		(layer "F.Cu")
		(net "MEMA_1")
	)
	(segment
		(start 36.504626 -143.00454)
		(end 36.509198 -142.999968)
		(width 0.127)
		(layer "F.Cu")
		(net "MEMA_1")
	)
	(segment
		(start 33.037018 -141.88567)
		(end 33.216342 -141.88567)
		(width 0.127)
		(layer "F.Cu")
		(net "MEMA_1")
	)
	(via
		(at 22.0345 -137.761472)
		(size 0.508)
		(drill 0.254)
		(layers "F.Cu" "B.Cu")
		(net "MEMA_1")
	)
	(via
		(at 32.089598 -140.73759)
		(size 0.508)
		(drill 0.254)
		(layers "F.Cu" "B.Cu")
		(net "MEMA_1")
	)
	(segment
		(start 20.2438 -133.46684)
		(end 20.1168 -133.33984)
		(width 0.127)
		(layer "B.Cu")
		(net "MEMA_1")
	)
	(segment
		(start 20.945856 -133.59384)
		(end 20.818856 -133.46684)
		(width 0.127)
		(layer "B.Cu")
		(net "MEMA_1")
	)
	(segment
		(start 19.15287 -130.562858)
		(end 19.15287 -129.530094)
		(width 0.127)
		(layer "B.Cu")
		(net "MEMA_1")
	)
	(segment
		(start 22.0345 -137.761472)
		(end 21.22297 -137.761472)
		(width 0.127)
		(layer "B.Cu")
		(net "MEMA_1")
	)
	(segment
		(start 19.15287 -129.530094)
		(end 19.144742 -129.521966)
		(width 0.127)
		(layer "B.Cu")
		(net "MEMA_1")
	)
	(segment
		(start 20.2438 -133.97484)
		(end 20.818856 -133.97484)
		(width 0.127)
		(layer "B.Cu")
		(net "MEMA_1")
	)
	(segment
		(start 20.1168 -133.179312)
		(end 19.85137 -132.913882)
		(width 0.127)
		(layer "B.Cu")
		(net "MEMA_1")
	)
	(segment
		(start 21.22297 -137.761472)
		(end 20.1168 -136.655302)
		(width 0.127)
		(layer "B.Cu")
		(net "MEMA_1")
	)
	(segment
		(start 20.945856 -133.84784)
		(end 20.945856 -133.59384)
		(width 0.127)
		(layer "B.Cu")
		(net "MEMA_1")
	)
	(segment
		(start 19.25193 -130.562858)
		(end 19.15287 -130.562858)
		(width 0.127)
		(layer "B.Cu")
		(net "MEMA_1")
	)
	(segment
		(start 20.818856 -133.46684)
		(end 20.2438 -133.46684)
		(width 0.127)
		(layer "B.Cu")
		(net "MEMA_1")
	)
	(segment
		(start 20.1168 -136.655302)
		(end 20.1168 -134.10184)
		(width 0.127)
		(layer "B.Cu")
		(net "MEMA_1")
	)
	(segment
		(start 20.1168 -133.33984)
		(end 20.1168 -133.179312)
		(width 0.127)
		(layer "B.Cu")
		(net "MEMA_1")
	)
	(segment
		(start 19.85137 -132.913882)
		(end 19.85137 -131.162298)
		(width 0.127)
		(layer "B.Cu")
		(net "MEMA_1")
	)
	(segment
		(start 19.85137 -131.162298)
		(end 19.25193 -130.562858)
		(width 0.127)
		(layer "B.Cu")
		(net "MEMA_1")
	)
	(segment
		(start 20.1168 -134.10184)
		(end 20.2438 -133.97484)
		(width 0.127)
		(layer "B.Cu")
		(net "MEMA_1")
	)
	(segment
		(start 20.818856 -133.97484)
		(end 20.945856 -133.84784)
		(width 0.127)
		(layer "B.Cu")
		(net "MEMA_1")
	)
	(segment
		(start 31.788608 -140.4366)
		(end 29.780992 -140.4366)
		(width 0.127)
		(layer "In5.Cu")
		(net "MEMA_1")
	)
	(segment
		(start 27.398472 -138.05408)
		(end 24.022558 -138.05408)
		(width 0.127)
		(layer "In5.Cu")
		(net "MEMA_1")
	)
	(segment
		(start 32.089598 -140.73759)
		(end 31.788608 -140.4366)
		(width 0.127)
		(layer "In5.Cu")
		(net "MEMA_1")
	)
	(segment
		(start 23.471632 -138.161522)
		(end 22.43455 -138.161522)
		(width 0.0889)
		(layer "In5.Cu")
		(net "MEMA_1")
	)
	(segment
		(start 23.915116 -138.161522)
		(end 23.471632 -138.161522)
		(width 0.127)
		(layer "In5.Cu")
		(net "MEMA_1")
	)
	(segment
		(start 22.43455 -138.161522)
		(end 22.0345 -137.761472)
		(width 0.0889)
		(layer "In5.Cu")
		(net "MEMA_1")
	)
	(segment
		(start 29.780992 -140.4366)
		(end 27.398472 -138.05408)
		(width 0.127)
		(layer "In5.Cu")
		(net "MEMA_1")
	)
	(segment
		(start 24.022558 -138.05408)
		(end 23.915116 -138.161522)
		(width 0.127)
		(layer "In5.Cu")
		(net "MEMA_1")
	)
	(segment
		(start 18.434558 -138.161522)
		(end 18.434812 -138.161522)
		(width 0.127)
		(layer "F.Cu")
		(net "MEMA_0")
	)
	(segment
		(start 42.09923 -143.400018)
		(end 42.49928 -143.800068)
		(width 0.127)
		(layer "F.Cu")
		(net "MEMA_0")
	)
	(segment
		(start 42.49928 -143.800068)
		(end 42.500042 -143.800068)
		(width 0.127)
		(layer "F.Cu")
		(net "MEMA_0")
	)
	(segment
		(start 18.434812 -138.161522)
		(end 18.834354 -138.561064)
		(width 0.127)
		(layer "F.Cu")
		(net "MEMA_0")
	)
	(via
		(at 18.834354 -138.561064)
		(size 0.508)
		(drill 0.254)
		(layers "F.Cu" "B.Cu")
		(net "MEMA_0")
	)
	(via
		(at 42.09923 -143.400018)
		(size 0.4572)
		(drill 0.2032)
		(layers "F.Cu" "B.Cu")
		(net "MEMA_0")
	)
	(segment
		(start 16.236696 -140.278104)
		(end 15.743428 -140.278104)
		(width 0.127)
		(layer "B.Cu")
		(net "MEMA_0")
	)
	(segment
		(start 15.743428 -140.278104)
		(end 15.363952 -140.65758)
		(width 0.127)
		(layer "B.Cu")
		(net "MEMA_0")
	)
	(segment
		(start 19.551904 -139.147042)
		(end 19.65706 -139.252198)
		(width 0.127)
		(layer "B.Cu")
		(net "MEMA_0")
	)
	(segment
		(start 19.65706 -139.566904)
		(end 19.523202 -139.700762)
		(width 0.127)
		(layer "B.Cu")
		(net "MEMA_0")
	)
	(segment
		(start 18.414238 -139.700762)
		(end 18.0467 -140.0683)
		(width 0.127)
		(layer "B.Cu")
		(net "MEMA_0")
	)
	(segment
		(start 19.523202 -139.700762)
		(end 18.414238 -139.700762)
		(width 0.127)
		(layer "B.Cu")
		(net "MEMA_0")
	)
	(segment
		(start 11.66749 -139.579604)
		(end 10.660634 -139.579604)
		(width 0.127)
		(layer "B.Cu")
		(net "MEMA_0")
	)
	(segment
		(start 13.94714 -140.65758)
		(end 13.567664 -140.278104)
		(width 0.127)
		(layer "B.Cu")
		(net "MEMA_0")
	)
	(segment
		(start 10.660634 -139.579604)
		(end 10.656062 -139.575032)
		(width 0.127)
		(layer "B.Cu")
		(net "MEMA_0")
	)
	(segment
		(start 12.26693 -140.278104)
		(end 11.66749 -139.678664)
		(width 0.127)
		(layer "B.Cu")
		(net "MEMA_0")
	)
	(segment
		(start 18.0467 -140.0683)
		(end 16.4465 -140.0683)
		(width 0.127)
		(layer "B.Cu")
		(net "MEMA_0")
	)
	(segment
		(start 18.834354 -138.561064)
		(end 18.834354 -138.954256)
		(width 0.127)
		(layer "B.Cu")
		(net "MEMA_0")
	)
	(segment
		(start 16.4465 -140.0683)
		(end 16.236696 -140.278104)
		(width 0.127)
		(layer "B.Cu")
		(net "MEMA_0")
	)
	(segment
		(start 19.65706 -139.252198)
		(end 19.65706 -139.566904)
		(width 0.127)
		(layer "B.Cu")
		(net "MEMA_0")
	)
	(segment
		(start 11.66749 -139.678664)
		(end 11.66749 -139.579604)
		(width 0.127)
		(layer "B.Cu")
		(net "MEMA_0")
	)
	(segment
		(start 18.834354 -138.954256)
		(end 19.02714 -139.147042)
		(width 0.127)
		(layer "B.Cu")
		(net "MEMA_0")
	)
	(segment
		(start 13.567664 -140.278104)
		(end 12.26693 -140.278104)
		(width 0.127)
		(layer "B.Cu")
		(net "MEMA_0")
	)
	(segment
		(start 19.02714 -139.147042)
		(end 19.551904 -139.147042)
		(width 0.127)
		(layer "B.Cu")
		(net "MEMA_0")
	)
	(segment
		(start 15.363952 -140.65758)
		(end 13.94714 -140.65758)
		(width 0.127)
		(layer "B.Cu")
		(net "MEMA_0")
	)
	(segment
		(start 35.750246 -141.361414)
		(end 36.004246 -141.361414)
		(width 0.127)
		(layer "In5.Cu")
		(net "MEMA_0")
	)
	(segment
		(start 31.566612 -141.361414)
		(end 32.956246 -141.361414)
		(width 0.127)
		(layer "In5.Cu")
		(net "MEMA_0")
	)
	(segment
		(start 27.187906 -138.56208)
		(end 29.570426 -140.9446)
		(width 0.127)
		(layer "In5.Cu")
		(net "MEMA_0")
	)
	(segment
		(start 37.782246 -141.361414)
		(end 37.99078 -141.361414)
		(width 0.127)
		(layer "In5.Cu")
		(net "MEMA_0")
	)
	(segment
		(start 26.270458 -139.06246)
		(end 26.397458 -138.93546)
		(width 0.127)
		(layer "In5.Cu")
		(net "MEMA_0")
	)
	(segment
		(start 36.131246 -141.234414)
		(end 36.131246 -141.19352)
		(width 0.127)
		(layer "In5.Cu")
		(net "MEMA_0")
	)
	(segment
		(start 26.524458 -138.56208)
		(end 27.187906 -138.56208)
		(width 0.127)
		(layer "In5.Cu")
		(net "MEMA_0")
	)
	(segment
		(start 33.464246 -141.06652)
		(end 33.591246 -141.19352)
		(width 0.127)
		(layer "In5.Cu")
		(net "MEMA_0")
	)
	(segment
		(start 33.718246 -141.361414)
		(end 33.972246 -141.361414)
		(width 0.127)
		(layer "In5.Cu")
		(net "MEMA_0")
	)
	(segment
		(start 33.210246 -141.06652)
		(end 33.464246 -141.06652)
		(width 0.127)
		(layer "In5.Cu")
		(net "MEMA_0")
	)
	(segment
		(start 35.623246 -141.234414)
		(end 35.750246 -141.361414)
		(width 0.127)
		(layer "In5.Cu")
		(net "MEMA_0")
	)
	(segment
		(start 29.939996 -141.0716)
		(end 29.939996 -141.29766)
		(width 0.127)
		(layer "In5.Cu")
		(net "MEMA_0")
	)
	(segment
		(start 24.426164 -138.56208)
		(end 24.746458 -138.56208)
		(width 0.127)
		(layer "In5.Cu")
		(net "MEMA_0")
	)
	(segment
		(start 24.406606 -138.542522)
		(end 24.426164 -138.56208)
		(width 0.127)
		(layer "In5.Cu")
		(net "MEMA_0")
	)
	(segment
		(start 30.447996 -141.0716)
		(end 30.574996 -140.9446)
		(width 0.127)
		(layer "In5.Cu")
		(net "MEMA_0")
	)
	(segment
		(start 33.083246 -141.19352)
		(end 33.210246 -141.06652)
		(width 0.127)
		(layer "In5.Cu")
		(net "MEMA_0")
	)
	(segment
		(start 29.812996 -140.9446)
		(end 29.939996 -141.0716)
		(width 0.127)
		(layer "In5.Cu")
		(net "MEMA_0")
	)
	(segment
		(start 34.988246 -141.361414)
		(end 35.115246 -141.234414)
		(width 0.127)
		(layer "In5.Cu")
		(net "MEMA_0")
	)
	(segment
		(start 35.115246 -141.19352)
		(end 35.242246 -141.06652)
		(width 0.127)
		(layer "In5.Cu")
		(net "MEMA_0")
	)
	(segment
		(start 33.083246 -141.234414)
		(end 33.083246 -141.19352)
		(width 0.127)
		(layer "In5.Cu")
		(net "MEMA_0")
	)
	(segment
		(start 25.889458 -138.68908)
		(end 25.889458 -138.93546)
		(width 0.127)
		(layer "In5.Cu")
		(net "MEMA_0")
	)
	(segment
		(start 25.000458 -139.06246)
		(end 25.254458 -139.06246)
		(width 0.127)
		(layer "In5.Cu")
		(net "MEMA_0")
	)
	(segment
		(start 19.982434 -139.30884)
		(end 20.503134 -138.78814)
		(width 0.127)
		(layer "In5.Cu")
		(net "MEMA_0")
	)
	(segment
		(start 37.655246 -141.19352)
		(end 37.655246 -141.234414)
		(width 0.127)
		(layer "In5.Cu")
		(net "MEMA_0")
	)
	(segment
		(start 30.574996 -140.9446)
		(end 31.149798 -140.9446)
		(width 0.127)
		(layer "In5.Cu")
		(net "MEMA_0")
	)
	(segment
		(start 31.149798 -140.9446)
		(end 31.566612 -141.361414)
		(width 0.127)
		(layer "In5.Cu")
		(net "MEMA_0")
	)
	(segment
		(start 36.131246 -141.19352)
		(end 36.258246 -141.06652)
		(width 0.127)
		(layer "In5.Cu")
		(net "MEMA_0")
	)
	(segment
		(start 20.710398 -138.78814)
		(end 20.90293 -138.980672)
		(width 0.127)
		(layer "In5.Cu")
		(net "MEMA_0")
	)
	(segment
		(start 34.226246 -141.06652)
		(end 34.480246 -141.06652)
		(width 0.127)
		(layer "In5.Cu")
		(net "MEMA_0")
	)
	(segment
		(start 26.016458 -139.06246)
		(end 26.270458 -139.06246)
		(width 0.127)
		(layer "In5.Cu")
		(net "MEMA_0")
	)
	(segment
		(start 34.734246 -141.361414)
		(end 34.988246 -141.361414)
		(width 0.127)
		(layer "In5.Cu")
		(net "MEMA_0")
	)
	(segment
		(start 37.020246 -141.361414)
		(end 37.147246 -141.234414)
		(width 0.127)
		(layer "In5.Cu")
		(net "MEMA_0")
	)
	(segment
		(start 29.570426 -140.9446)
		(end 29.812996 -140.9446)
		(width 0.127)
		(layer "In5.Cu")
		(net "MEMA_0")
	)
	(segment
		(start 34.099246 -141.19352)
		(end 34.226246 -141.06652)
		(width 0.127)
		(layer "In5.Cu")
		(net "MEMA_0")
	)
	(segment
		(start 18.834354 -138.561064)
		(end 19.58213 -139.30884)
		(width 0.127)
		(layer "In5.Cu")
		(net "MEMA_0")
	)
	(segment
		(start 41.57853 -143.120364)
		(end 41.70553 -143.247364)
		(width 0.127)
		(layer "In5.Cu")
		(net "MEMA_0")
	)
	(segment
		(start 25.889458 -138.93546)
		(end 26.016458 -139.06246)
		(width 0.127)
		(layer "In5.Cu")
		(net "MEMA_0")
	)
	(segment
		(start 19.58213 -139.30884)
		(end 19.982434 -139.30884)
		(width 0.127)
		(layer "In5.Cu")
		(net "MEMA_0")
	)
	(segment
		(start 25.381458 -138.68908)
		(end 25.508458 -138.56208)
		(width 0.127)
		(layer "In5.Cu")
		(net "MEMA_0")
	)
	(segment
		(start 24.873458 -138.93546)
		(end 25.000458 -139.06246)
		(width 0.127)
		(layer "In5.Cu")
		(net "MEMA_0")
	)
	(segment
		(start 37.147246 -141.19352)
		(end 37.274246 -141.06652)
		(width 0.127)
		(layer "In5.Cu")
		(net "MEMA_0")
	)
	(segment
		(start 29.939996 -141.29766)
		(end 30.066996 -141.42466)
		(width 0.127)
		(layer "In5.Cu")
		(net "MEMA_0")
	)
	(segment
		(start 37.528246 -141.06652)
		(end 37.655246 -141.19352)
		(width 0.127)
		(layer "In5.Cu")
		(net "MEMA_0")
	)
	(segment
		(start 37.274246 -141.06652)
		(end 37.528246 -141.06652)
		(width 0.127)
		(layer "In5.Cu")
		(net "MEMA_0")
	)
	(segment
		(start 37.147246 -141.234414)
		(end 37.147246 -141.19352)
		(width 0.127)
		(layer "In5.Cu")
		(net "MEMA_0")
	)
	(segment
		(start 25.508458 -138.56208)
		(end 25.762458 -138.56208)
		(width 0.127)
		(layer "In5.Cu")
		(net "MEMA_0")
	)
	(segment
		(start 34.099246 -141.234414)
		(end 34.099246 -141.19352)
		(width 0.127)
		(layer "In5.Cu")
		(net "MEMA_0")
	)
	(segment
		(start 35.242246 -141.06652)
		(end 35.496246 -141.06652)
		(width 0.127)
		(layer "In5.Cu")
		(net "MEMA_0")
	)
	(segment
		(start 36.258246 -141.06652)
		(end 36.512246 -141.06652)
		(width 0.127)
		(layer "In5.Cu")
		(net "MEMA_0")
	)
	(segment
		(start 40.736266 -142.993364)
		(end 41.271952 -142.993364)
		(width 0.127)
		(layer "In5.Cu")
		(net "MEMA_0")
	)
	(segment
		(start 32.956246 -141.361414)
		(end 33.083246 -141.234414)
		(width 0.127)
		(layer "In5.Cu")
		(net "MEMA_0")
	)
	(segment
		(start 24.873458 -138.68908)
		(end 24.873458 -138.93546)
		(width 0.127)
		(layer "In5.Cu")
		(net "MEMA_0")
	)
	(segment
		(start 35.623246 -141.19352)
		(end 35.623246 -141.234414)
		(width 0.127)
		(layer "In5.Cu")
		(net "MEMA_0")
	)
	(segment
		(start 26.397458 -138.68908)
		(end 26.524458 -138.56208)
		(width 0.127)
		(layer "In5.Cu")
		(net "MEMA_0")
	)
	(segment
		(start 36.004246 -141.361414)
		(end 36.131246 -141.234414)
		(width 0.127)
		(layer "In5.Cu")
		(net "MEMA_0")
	)
	(segment
		(start 20.90293 -138.980672)
		(end 23.079964 -138.980672)
		(width 0.127)
		(layer "In5.Cu")
		(net "MEMA_0")
	)
	(segment
		(start 33.972246 -141.361414)
		(end 34.099246 -141.234414)
		(width 0.127)
		(layer "In5.Cu")
		(net "MEMA_0")
	)
	(segment
		(start 23.518114 -138.542522)
		(end 24.406606 -138.542522)
		(width 0.127)
		(layer "In5.Cu")
		(net "MEMA_0")
	)
	(segment
		(start 23.079964 -138.980672)
		(end 23.518114 -138.542522)
		(width 0.127)
		(layer "In5.Cu")
		(net "MEMA_0")
	)
	(segment
		(start 25.381458 -138.93546)
		(end 25.381458 -138.68908)
		(width 0.127)
		(layer "In5.Cu")
		(net "MEMA_0")
	)
	(segment
		(start 26.397458 -138.93546)
		(end 26.397458 -138.68908)
		(width 0.127)
		(layer "In5.Cu")
		(net "MEMA_0")
	)
	(segment
		(start 34.480246 -141.06652)
		(end 34.607246 -141.19352)
		(width 0.127)
		(layer "In5.Cu")
		(net "MEMA_0")
	)
	(segment
		(start 30.447996 -141.29766)
		(end 30.447996 -141.0716)
		(width 0.127)
		(layer "In5.Cu")
		(net "MEMA_0")
	)
	(segment
		(start 36.639246 -141.19352)
		(end 36.639246 -141.234414)
		(width 0.127)
		(layer "In5.Cu")
		(net "MEMA_0")
	)
	(segment
		(start 25.762458 -138.56208)
		(end 25.889458 -138.68908)
		(width 0.127)
		(layer "In5.Cu")
		(net "MEMA_0")
	)
	(segment
		(start 34.607246 -141.234414)
		(end 34.734246 -141.361414)
		(width 0.127)
		(layer "In5.Cu")
		(net "MEMA_0")
	)
	(segment
		(start 25.254458 -139.06246)
		(end 25.381458 -138.93546)
		(width 0.127)
		(layer "In5.Cu")
		(net "MEMA_0")
	)
	(segment
		(start 37.655246 -141.234414)
		(end 37.782246 -141.361414)
		(width 0.127)
		(layer "In5.Cu")
		(net "MEMA_0")
	)
	(segment
		(start 24.746458 -138.56208)
		(end 24.873458 -138.68908)
		(width 0.127)
		(layer "In5.Cu")
		(net "MEMA_0")
	)
	(segment
		(start 36.639246 -141.234414)
		(end 36.766246 -141.361414)
		(width 0.127)
		(layer "In5.Cu")
		(net "MEMA_0")
	)
	(segment
		(start 36.512246 -141.06652)
		(end 36.639246 -141.19352)
		(width 0.127)
		(layer "In5.Cu")
		(net "MEMA_0")
	)
	(segment
		(start 37.99078 -141.361414)
		(end 38.83533 -142.205964)
		(width 0.127)
		(layer "In5.Cu")
		(net "MEMA_0")
	)
	(segment
		(start 20.503134 -138.78814)
		(end 20.710398 -138.78814)
		(width 0.127)
		(layer "In5.Cu")
		(net "MEMA_0")
	)
	(segment
		(start 30.320996 -141.42466)
		(end 30.447996 -141.29766)
		(width 0.127)
		(layer "In5.Cu")
		(net "MEMA_0")
	)
	(segment
		(start 33.591246 -141.234414)
		(end 33.718246 -141.361414)
		(width 0.127)
		(layer "In5.Cu")
		(net "MEMA_0")
	)
	(segment
		(start 34.607246 -141.19352)
		(end 34.607246 -141.234414)
		(width 0.127)
		(layer "In5.Cu")
		(net "MEMA_0")
	)
	(segment
		(start 36.766246 -141.361414)
		(end 37.020246 -141.361414)
		(width 0.127)
		(layer "In5.Cu")
		(net "MEMA_0")
	)
	(segment
		(start 35.496246 -141.06652)
		(end 35.623246 -141.19352)
		(width 0.127)
		(layer "In5.Cu")
		(net "MEMA_0")
	)
	(segment
		(start 33.591246 -141.19352)
		(end 33.591246 -141.234414)
		(width 0.127)
		(layer "In5.Cu")
		(net "MEMA_0")
	)
	(segment
		(start 35.115246 -141.234414)
		(end 35.115246 -141.19352)
		(width 0.127)
		(layer "In5.Cu")
		(net "MEMA_0")
	)
	(segment
		(start 30.066996 -141.42466)
		(end 30.320996 -141.42466)
		(width 0.127)
		(layer "In5.Cu")
		(net "MEMA_0")
	)
	(arc
		(start 38.83533 -142.205964)
		(mid 39.523311 -142.751097)
		(end 40.34917 -143.048482)
		(width 0.127)
		(layer "In5.Cu")
		(net "MEMA_0")
	)
	(arc
		(start 40.34917 -143.048482)
		(mid 40.483466 -143.05329)
		(end 40.61333 -143.018764)
		(width 0.127)
		(layer "In5.Cu")
		(net "MEMA_0")
	)
	(arc
		(start 40.61333 -143.018764)
		(mid 40.673499 -142.999776)
		(end 40.736266 -142.993364)
		(width 0.127)
		(layer "In5.Cu")
		(net "MEMA_0")
	)
	(arc
		(start 41.271952 -142.993364)
		(mid 41.437875 -143.026368)
		(end 41.57853 -143.120364)
		(width 0.127)
		(layer "In5.Cu")
		(net "MEMA_0")
	)
	(arc
		(start 41.70553 -143.247364)
		(mid 41.886291 -143.365182)
		(end 42.09923 -143.400018)
		(width 0.127)
		(layer "In5.Cu")
		(net "MEMA_0")
	)
	(segment
		(start 193.5988 -51.061874)
		(end 193.49212 -51.168554)
		(width 0.127)
		(layer "F.Cu")
		(net "LSI_TN")
	)
	(segment
		(start 192.39992 -55.099966)
		(end 192.749678 -54.750208)
		(width 0.127)
		(layer "F.Cu")
		(net "LSI_TN")
	)
	(segment
		(start 193.49212 -51.435508)
		(end 193.49212 -51.168554)
		(width 0.127)
		(layer "F.Cu")
		(net "LSI_TN")
	)
	(segment
		(start 192.749678 -54.750208)
		(end 192.749678 -52.17795)
		(width 0.127)
		(layer "F.Cu")
		(net "LSI_TN")
	)
	(segment
		(start 193.5988 -48.8315)
		(end 193.5988 -51.061874)
		(width 0.127)
		(layer "F.Cu")
		(net "LSI_TN")
	)
	(segment
		(start 192.749678 -52.17795)
		(end 193.49212 -51.435508)
		(width 0.127)
		(layer "F.Cu")
		(net "LSI_TN")
	)
	(via
		(at 193.49212 -51.168554)
		(size 0.6604)
		(drill 0.3302)
		(layers "F.Cu" "B.Cu")
		(net "LSI_TN")
	)
	(segment
		(start 191.955166 -53.944774)
		(end 191.955166 -51.234848)
		(width 0.127)
		(layer "F.Cu")
		(net "LSI_SCAN_EN")
	)
	(segment
		(start 191.4906 -48.8061)
		(end 191.516 -48.8315)
		(width 0.127)
		(layer "F.Cu")
		(net "LSI_SCAN_EN")
	)
	(segment
		(start 191.600074 -54.299866)
		(end 191.955166 -53.944774)
		(width 0.127)
		(layer "F.Cu")
		(net "LSI_SCAN_EN")
	)
	(segment
		(start 191.955166 -49.270666)
		(end 191.955166 -51.234848)
		(width 0.127)
		(layer "F.Cu")
		(net "LSI_SCAN_EN")
	)
	(segment
		(start 191.516 -48.8315)
		(end 191.955166 -49.270666)
		(width 0.127)
		(layer "F.Cu")
		(net "LSI_SCAN_EN")
	)
	(segment
		(start 190.4746 -48.8061)
		(end 191.4906 -48.8061)
		(width 0.127)
		(layer "F.Cu")
		(net "LSI_SCAN_EN")
	)
	(via
		(at 191.955166 -51.234848)
		(size 0.6604)
		(drill 0.3302)
		(layers "F.Cu" "B.Cu")
		(net "LSI_SCAN_EN")
	)
	(segment
		(start 189.4078 -48.8823)
		(end 189.865 -49.3395)
		(width 0.127)
		(layer "F.Cu")
		(net "LSI_JTAG_EN_N")
	)
	(segment
		(start 192.39992 -54.299866)
		(end 191.981836 -54.71795)
		(width 0.127)
		(layer "F.Cu")
		(net "LSI_JTAG_EN_N")
	)
	(segment
		(start 191.1858 -53.005228)
		(end 189.710314 -51.529742)
		(width 0.127)
		(layer "F.Cu")
		(net "LSI_JTAG_EN_N")
	)
	(segment
		(start 189.865 -50.836068)
		(end 189.710314 -50.990754)
		(width 0.127)
		(layer "F.Cu")
		(net "LSI_JTAG_EN_N")
	)
	(segment
		(start 191.356234 -54.71795)
		(end 191.1858 -54.547516)
		(width 0.127)
		(layer "F.Cu")
		(net "LSI_JTAG_EN_N")
	)
	(segment
		(start 189.865 -49.3395)
		(end 189.865 -50.836068)
		(width 0.127)
		(layer "F.Cu")
		(net "LSI_JTAG_EN_N")
	)
	(segment
		(start 191.981836 -54.71795)
		(end 191.356234 -54.71795)
		(width 0.127)
		(layer "F.Cu")
		(net "LSI_JTAG_EN_N")
	)
	(segment
		(start 189.710314 -51.529742)
		(end 189.710314 -50.990754)
		(width 0.127)
		(layer "F.Cu")
		(net "LSI_JTAG_EN_N")
	)
	(segment
		(start 191.1858 -54.547516)
		(end 191.1858 -53.005228)
		(width 0.127)
		(layer "F.Cu")
		(net "LSI_JTAG_EN_N")
	)
	(via
		(at 189.710314 -50.990754)
		(size 0.6604)
		(drill 0.3302)
		(layers "F.Cu" "B.Cu")
		(net "LSI_JTAG_EN_N")
	)
	(segment
		(start 189.2808 -50.3936)
		(end 189.1538 -50.5206)
		(width 0.127)
		(layer "F.Cu")
		(net "LSI_IDDT")
	)
	(segment
		(start 188.2902 -48.8442)
		(end 189.3062 -49.8602)
		(width 0.127)
		(layer "F.Cu")
		(net "LSI_IDDT")
	)
	(segment
		(start 189.1538 -51.406552)
		(end 190.799974 -53.052726)
		(width 0.127)
		(layer "F.Cu")
		(net "LSI_IDDT")
	)
	(segment
		(start 189.1538 -50.5206)
		(end 189.1538 -51.406552)
		(width 0.127)
		(layer "F.Cu")
		(net "LSI_IDDT")
	)
	(segment
		(start 189.3062 -49.8602)
		(end 189.2808 -49.8856)
		(width 0.127)
		(layer "F.Cu")
		(net "LSI_IDDT")
	)
	(segment
		(start 190.799974 -53.052726)
		(end 190.799974 -53.50002)
		(width 0.127)
		(layer "F.Cu")
		(net "LSI_IDDT")
	)
	(segment
		(start 188.2902 -48.8315)
		(end 188.2902 -48.8442)
		(width 0.127)
		(layer "F.Cu")
		(net "LSI_IDDT")
	)
	(segment
		(start 189.2808 -49.8856)
		(end 189.2808 -50.3936)
		(width 0.127)
		(layer "F.Cu")
		(net "LSI_IDDT")
	)
	(via
		(at 189.3062 -49.8602)
		(size 0.6604)
		(drill 0.3302)
		(layers "F.Cu" "B.Cu")
		(net "LSI_IDDT")
	)
	(segment
		(start 50.2285 -134.709154)
		(end 50.2285 -133.79704)
		(width 0.127)
		(layer "F.Cu")
		(net "LPCRST0_N")
	)
	(segment
		(start 51.299872 -135.780526)
		(end 50.2285 -134.709154)
		(width 0.127)
		(layer "F.Cu")
		(net "LPCRST0_N")
	)
	(segment
		(start 50.673 -132.1943)
		(end 50.673 -133.223)
		(width 0.127)
		(layer "F.Cu")
		(net "LPCRST0_N")
	)
	(segment
		(start 51.299872 -136.59993)
		(end 51.299872 -135.780526)
		(width 0.127)
		(layer "F.Cu")
		(net "LPCRST0_N")
	)
	(segment
		(start 50.673 -133.223)
		(end 50.73777 -133.28777)
		(width 0.127)
		(layer "F.Cu")
		(net "LPCRST0_N")
	)
	(segment
		(start 50.2285 -133.79704)
		(end 50.73777 -133.28777)
		(width 0.127)
		(layer "F.Cu")
		(net "LPCRST0_N")
	)
	(via
		(at 50.73777 -133.28777)
		(size 0.6604)
		(drill 0.3302)
		(layers "F.Cu" "B.Cu")
		(net "LPCRST0_N")
	)
	(segment
		(start 188.1886 -49.9745)
		(end 188.47816 -50.26406)
		(width 0.127)
		(layer "F.Cu")
		(net "JTAG_IOC_TMS")
	)
	(segment
		(start 190.393066 -53.00853)
		(end 190.393066 -53.892958)
		(width 0.127)
		(layer "F.Cu")
		(net "JTAG_IOC_TMS")
	)
	(segment
		(start 188.47816 -50.26406)
		(end 188.47816 -50.50536)
		(width 0.127)
		(layer "F.Cu")
		(net "JTAG_IOC_TMS")
	)
	(segment
		(start 188.47816 -50.50536)
		(end 188.846968 -50.874168)
		(width 0.127)
		(layer "F.Cu")
		(net "JTAG_IOC_TMS")
	)
	(segment
		(start 188.846968 -50.874168)
		(end 188.846968 -50.950622)
		(width 0.127)
		(layer "F.Cu")
		(net "JTAG_IOC_TMS")
	)
	(segment
		(start 188.8617 -50.965354)
		(end 188.8617 -51.477164)
		(width 0.127)
		(layer "F.Cu")
		(net "JTAG_IOC_TMS")
	)
	(segment
		(start 188.846968 -50.950622)
		(end 188.8617 -50.965354)
		(width 0.127)
		(layer "F.Cu")
		(net "JTAG_IOC_TMS")
	)
	(segment
		(start 188.8617 -51.477164)
		(end 190.393066 -53.00853)
		(width 0.127)
		(layer "F.Cu")
		(net "JTAG_IOC_TMS")
	)
	(segment
		(start 190.393066 -53.892958)
		(end 190.799974 -54.299866)
		(width 0.127)
		(layer "F.Cu")
		(net "JTAG_IOC_TMS")
	)
	(segment
		(start 191.434466 -50.176684)
		(end 191.242188 -49.984406)
		(width 0.127)
		(layer "F.Cu")
		(net "JTAG_IOC_TDI")
	)
	(segment
		(start 191.434466 -53.334412)
		(end 191.434466 -50.176684)
		(width 0.127)
		(layer "F.Cu")
		(net "JTAG_IOC_TDI")
	)
	(segment
		(start 191.600074 -53.50002)
		(end 191.434466 -53.334412)
		(width 0.127)
		(layer "F.Cu")
		(net "JTAG_IOC_TDI")
	)
	(segment
		(start 191.600074 -55.101744)
		(end 191.600074 -55.099966)
		(width 0.127)
		(layer "F.Cu")
		(net "JTAG_IOC_TCK")
	)
	(segment
		(start 192.000886 -55.502556)
		(end 191.600074 -55.101744)
		(width 0.127)
		(layer "F.Cu")
		(net "JTAG_IOC_TCK")
	)
	(via
		(at 192.000886 -55.502556)
		(size 0.508)
		(drill 0.254)
		(layers "F.Cu" "B.Cu")
		(net "JTAG_IOC_TCK")
	)
	(segment
		(start 192.000886 -55.502556)
		(end 192.000886 -53.427376)
		(width 0.127)
		(layer "B.Cu")
		(net "JTAG_IOC_TCK")
	)
	(segment
		(start 192.000886 -53.427376)
		(end 191.383666 -52.810156)
		(width 0.127)
		(layer "B.Cu")
		(net "JTAG_IOC_TCK")
	)
	(segment
		(start 52.899818 -145.400014)
		(end 52.499768 -145.800064)
		(width 0.127)
		(layer "F.Cu")
		(net "JTAG_BMC_TRST_N")
	)
	(via
		(at 52.499768 -145.800064)
		(size 0.4572)
		(drill 0.2032)
		(layers "F.Cu" "B.Cu")
		(net "JTAG_BMC_TRST_N")
	)
	(segment
		(start 51.2445 -143.27632)
		(end 51.03114 -143.06296)
		(width 0.127)
		(layer "B.Cu")
		(net "JTAG_BMC_TRST_N")
	)
	(segment
		(start 50.685954 -143.06296)
		(end 51.03114 -143.06296)
		(width 0.127)
		(layer "B.Cu")
		(net "JTAG_BMC_TRST_N")
	)
	(segment
		(start 52.093368 -145.393664)
		(end 52.499768 -145.800064)
		(width 0.127)
		(layer "B.Cu")
		(net "JTAG_BMC_TRST_N")
	)
	(segment
		(start 51.40452 -144.26438)
		(end 52.093368 -144.953228)
		(width 0.127)
		(layer "B.Cu")
		(net "JTAG_BMC_TRST_N")
	)
	(segment
		(start 50.01006 -143.2179)
		(end 50.530506 -143.2179)
		(width 0.127)
		(layer "B.Cu")
		(net "JTAG_BMC_TRST_N")
	)
	(segment
		(start 51.40452 -144.26438)
		(end 51.2445 -144.10436)
		(width 0.127)
		(layer "B.Cu")
		(net "JTAG_BMC_TRST_N")
	)
	(segment
		(start 51.2445 -144.10436)
		(end 51.2445 -143.27632)
		(width 0.127)
		(layer "B.Cu")
		(net "JTAG_BMC_TRST_N")
	)
	(segment
		(start 50.530506 -143.2179)
		(end 50.6857 -143.062706)
		(width 0.127)
		(layer "B.Cu")
		(net "JTAG_BMC_TRST_N")
	)
	(segment
		(start 50.6857 -143.062706)
		(end 50.685954 -143.06296)
		(width 0.127)
		(layer "B.Cu")
		(net "JTAG_BMC_TRST_N")
	)
	(segment
		(start 49.8475 -143.05534)
		(end 50.01006 -143.2179)
		(width 0.127)
		(layer "B.Cu")
		(net "JTAG_BMC_TRST_N")
	)
	(segment
		(start 49.8475 -142.0495)
		(end 49.8475 -143.05534)
		(width 0.127)
		(layer "B.Cu")
		(net "JTAG_BMC_TRST_N")
	)
	(segment
		(start 52.093368 -144.953228)
		(end 52.093368 -145.393664)
		(width 0.127)
		(layer "B.Cu")
		(net "JTAG_BMC_TRST_N")
	)
	(segment
		(start 54.899814 -148.20011)
		(end 54.500018 -147.800314)
		(width 0.127)
		(layer "F.Cu")
		(net "JTAG_BMC_TMS")
	)
	(segment
		(start 54.500018 -147.800314)
		(end 54.500018 -147.80006)
		(width 0.127)
		(layer "F.Cu")
		(net "JTAG_BMC_TMS")
	)
	(via
		(at 54.899814 -148.20011)
		(size 0.4572)
		(drill 0.2032)
		(layers "F.Cu" "B.Cu")
		(net "JTAG_BMC_TMS")
	)
	(segment
		(start 54.899814 -148.399246)
		(end 54.899814 -148.20011)
		(width 0.127)
		(layer "B.Cu")
		(net "JTAG_BMC_TMS")
	)
	(segment
		(start 56.477916 -149.300184)
		(end 56.9595 -148.8186)
		(width 0.127)
		(layer "B.Cu")
		(net "JTAG_BMC_TMS")
	)
	(segment
		(start 55.800752 -149.300184)
		(end 56.477916 -149.300184)
		(width 0.127)
		(layer "B.Cu")
		(net "JTAG_BMC_TMS")
	)
	(segment
		(start 55.800752 -149.300184)
		(end 54.899814 -148.399246)
		(width 0.127)
		(layer "B.Cu")
		(net "JTAG_BMC_TMS")
	)
	(segment
		(start 53.699664 -145.400014)
		(end 53.699918 -145.400014)
		(width 0.127)
		(layer "F.Cu")
		(net "JTAG_BMC_TDO")
	)
	(segment
		(start 53.299614 -145.800064)
		(end 53.699664 -145.400014)
		(width 0.127)
		(layer "F.Cu")
		(net "JTAG_BMC_TDO")
	)
	(via
		(at 53.299614 -145.800064)
		(size 0.4572)
		(drill 0.2032)
		(layers "F.Cu" "B.Cu")
		(net "JTAG_BMC_TDO")
	)
	(segment
		(start 55.575454 -145.058384)
		(end 54.041294 -145.058384)
		(width 0.127)
		(layer "B.Cu")
		(net "JTAG_BMC_TDO")
	)
	(segment
		(start 56.4261 -145.2626)
		(end 56.221884 -145.058384)
		(width 0.127)
		(layer "B.Cu")
		(net "JTAG_BMC_TDO")
	)
	(segment
		(start 54.041294 -145.058384)
		(end 53.299614 -145.800064)
		(width 0.127)
		(layer "B.Cu")
		(net "JTAG_BMC_TDO")
	)
	(segment
		(start 56.8833 -145.2626)
		(end 56.4261 -145.2626)
		(width 0.127)
		(layer "B.Cu")
		(net "JTAG_BMC_TDO")
	)
	(segment
		(start 56.221884 -145.058384)
		(end 55.575454 -145.058384)
		(width 0.127)
		(layer "B.Cu")
		(net "JTAG_BMC_TDO")
	)
	(segment
		(start 54.099714 -144.200372)
		(end 54.09946 -144.200372)
		(width 0.127)
		(layer "F.Cu")
		(net "JTAG_BMC_TDI")
	)
	(segment
		(start 54.09946 -144.200372)
		(end 53.699918 -144.599914)
		(width 0.127)
		(layer "F.Cu")
		(net "JTAG_BMC_TDI")
	)
	(via
		(at 54.099714 -144.200372)
		(size 0.4572)
		(drill 0.2032)
		(layers "F.Cu" "B.Cu")
		(net "JTAG_BMC_TDI")
	)
	(segment
		(start 56.893968 -144.2212)
		(end 56.690768 -144.018)
		(width 0.127)
		(layer "B.Cu")
		(net "JTAG_BMC_TDI")
	)
	(segment
		(start 58.0136 -144.2212)
		(end 56.893968 -144.2212)
		(width 0.127)
		(layer "B.Cu")
		(net "JTAG_BMC_TDI")
	)
	(segment
		(start 54.099714 -144.200372)
		(end 54.493414 -144.594072)
		(width 0.127)
		(layer "B.Cu")
		(net "JTAG_BMC_TDI")
	)
	(segment
		(start 55.933086 -143.806418)
		(end 56.144668 -144.018)
		(width 0.127)
		(layer "B.Cu")
		(net "JTAG_BMC_TDI")
	)
	(segment
		(start 54.493414 -144.594072)
		(end 55.063136 -144.594072)
		(width 0.127)
		(layer "B.Cu")
		(net "JTAG_BMC_TDI")
	)
	(segment
		(start 56.144668 -144.018)
		(end 56.690768 -144.018)
		(width 0.127)
		(layer "B.Cu")
		(net "JTAG_BMC_TDI")
	)
	(segment
		(start 55.5371 -143.806418)
		(end 55.933086 -143.806418)
		(width 0.127)
		(layer "B.Cu")
		(net "JTAG_BMC_TDI")
	)
	(segment
		(start 55.063136 -144.594072)
		(end 55.306722 -144.350486)
		(width 0.127)
		(layer "B.Cu")
		(net "JTAG_BMC_TDI")
	)
	(segment
		(start 55.306722 -144.036796)
		(end 55.5371 -143.806418)
		(width 0.127)
		(layer "B.Cu")
		(net "JTAG_BMC_TDI")
	)
	(segment
		(start 55.306722 -144.350486)
		(end 55.306722 -144.036796)
		(width 0.127)
		(layer "B.Cu")
		(net "JTAG_BMC_TDI")
	)
	(segment
		(start 54.899814 -146.59991)
		(end 54.899814 -146.599656)
		(width 0.127)
		(layer "F.Cu")
		(net "JTAG_BMC_TCK")
	)
	(segment
		(start 54.899814 -146.599656)
		(end 54.500018 -146.19986)
		(width 0.127)
		(layer "F.Cu")
		(net "JTAG_BMC_TCK")
	)
	(via
		(at 54.899814 -146.59991)
		(size 0.4572)
		(drill 0.2032)
		(layers "F.Cu" "B.Cu")
		(net "JTAG_BMC_TCK")
	)
	(segment
		(start 54.899814 -146.59991)
		(end 54.99227 -146.507454)
		(width 0.127)
		(layer "B.Cu")
		(net "JTAG_BMC_TCK")
	)
	(segment
		(start 56.361584 -146.507454)
		(end 55.790592 -146.507454)
		(width 0.127)
		(layer "B.Cu")
		(net "JTAG_BMC_TCK")
	)
	(segment
		(start 56.365394 -146.511264)
		(end 56.361584 -146.507454)
		(width 0.127)
		(layer "B.Cu")
		(net "JTAG_BMC_TCK")
	)
	(segment
		(start 56.97855 -146.511264)
		(end 56.365394 -146.511264)
		(width 0.127)
		(layer "B.Cu")
		(net "JTAG_BMC_TCK")
	)
	(segment
		(start 54.99227 -146.507454)
		(end 55.790592 -146.507454)
		(width 0.127)
		(layer "B.Cu")
		(net "JTAG_BMC_TCK")
	)
	(via
		(at 167.031162 -74.81062)
		(size 0.6096)
		(drill 0.3048)
		(layers "F.Cu" "B.Cu")
		(net "IOC_WP_N")
	)
	(segment
		(start 166.6875 -74.466958)
		(end 167.031162 -74.81062)
		(width 0.127)
		(layer "B.Cu")
		(net "IOC_WP_N")
	)
	(segment
		(start 165.49497 -72.8853)
		(end 165.49497 -73.648062)
		(width 0.127)
		(layer "B.Cu")
		(net "IOC_WP_N")
	)
	(segment
		(start 166.79291 -75.797664)
		(end 167.031162 -75.559412)
		(width 0.127)
		(layer "B.Cu")
		(net "IOC_WP_N")
	)
	(segment
		(start 167.031162 -75.559412)
		(end 167.031162 -74.81062)
		(width 0.127)
		(layer "B.Cu")
		(net "IOC_WP_N")
	)
	(segment
		(start 166.313866 -74.466958)
		(end 166.6875 -74.466958)
		(width 0.127)
		(layer "B.Cu")
		(net "IOC_WP_N")
	)
	(segment
		(start 165.49497 -73.648062)
		(end 166.313866 -74.466958)
		(width 0.127)
		(layer "B.Cu")
		(net "IOC_WP_N")
	)
	(segment
		(start 197.544182 -53.348382)
		(end 197.343776 -53.147976)
		(width 0.127)
		(layer "F.Cu")
		(net "IOC_VREF_SET")
	)
	(segment
		(start 197.999858 -54.299866)
		(end 197.544182 -53.84419)
		(width 0.127)
		(layer "F.Cu")
		(net "IOC_VREF_SET")
	)
	(segment
		(start 196.31533 -48.14189)
		(end 196.07276 -47.89932)
		(width 0.127)
		(layer "F.Cu")
		(net "IOC_VREF_SET")
	)
	(segment
		(start 191.89573 -43.25747)
		(end 174.267876 -43.25747)
		(width 0.127)
		(layer "F.Cu")
		(net "IOC_VREF_SET")
	)
	(segment
		(start 152.136856 -89.948512)
		(end 152.136856 -83.194144)
		(width 0.127)
		(layer "F.Cu")
		(net "IOC_VREF_SET")
	)
	(segment
		(start 159.994854 -53.7845)
		(end 154.2796 -59.499754)
		(width 0.127)
		(layer "F.Cu")
		(net "IOC_VREF_SET")
	)
	(segment
		(start 197.343776 -53.147976)
		(end 197.343776 -51.326796)
		(width 0.127)
		(layer "F.Cu")
		(net "IOC_VREF_SET")
	)
	(segment
		(start 196.07276 -47.4345)
		(end 191.89573 -43.25747)
		(width 0.127)
		(layer "F.Cu")
		(net "IOC_VREF_SET")
	)
	(segment
		(start 197.544182 -53.84419)
		(end 197.544182 -53.348382)
		(width 0.127)
		(layer "F.Cu")
		(net "IOC_VREF_SET")
	)
	(segment
		(start 196.07276 -47.89932)
		(end 196.07276 -47.4345)
		(width 0.127)
		(layer "F.Cu")
		(net "IOC_VREF_SET")
	)
	(segment
		(start 163.740846 -53.7845)
		(end 159.994854 -53.7845)
		(width 0.127)
		(layer "F.Cu")
		(net "IOC_VREF_SET")
	)
	(segment
		(start 154.2796 -81.0514)
		(end 154.2796 -75.9714)
		(width 0.127)
		(layer "F.Cu")
		(net "IOC_VREF_SET")
	)
	(segment
		(start 152.136856 -83.194144)
		(end 154.2796 -81.0514)
		(width 0.127)
		(layer "F.Cu")
		(net "IOC_VREF_SET")
	)
	(segment
		(start 197.343776 -51.326796)
		(end 196.31533 -50.29835)
		(width 0.127)
		(layer "F.Cu")
		(net "IOC_VREF_SET")
	)
	(segment
		(start 196.31533 -50.29835)
		(end 196.31533 -48.14189)
		(width 0.127)
		(layer "F.Cu")
		(net "IOC_VREF_SET")
	)
	(segment
		(start 174.267876 -43.25747)
		(end 163.740846 -53.7845)
		(width 0.127)
		(layer "F.Cu")
		(net "IOC_VREF_SET")
	)
	(segment
		(start 154.2796 -59.499754)
		(end 154.2796 -75.9714)
		(width 0.127)
		(layer "F.Cu")
		(net "IOC_VREF_SET")
	)
	(via
		(at 154.2796 -75.9714)
		(size 0.6604)
		(drill 0.3302)
		(layers "F.Cu" "B.Cu")
		(net "IOC_VREF_SET")
	)
	(via
		(at 152.136856 -89.948512)
		(size 0.508)
		(drill 0.254)
		(layers "F.Cu" "B.Cu")
		(net "IOC_VREF_SET")
	)
	(segment
		(start 151.500586 -92.854272)
		(end 151.500586 -90.584782)
		(width 0.127)
		(layer "B.Cu")
		(net "IOC_VREF_SET")
	)
	(segment
		(start 152.131014 -93.4847)
		(end 151.500586 -92.854272)
		(width 0.127)
		(layer "B.Cu")
		(net "IOC_VREF_SET")
	)
	(segment
		(start 151.500586 -90.584782)
		(end 152.136856 -89.948512)
		(width 0.127)
		(layer "B.Cu")
		(net "IOC_VREF_SET")
	)
	(segment
		(start 155.335986 -93.373448)
		(end 155.566364 -93.603826)
		(width 0.127)
		(layer "F.Cu")
		(net "IOC_UART_R_TX")
	)
	(segment
		(start 155.758642 -94.609158)
		(end 155.566364 -94.41688)
		(width 0.127)
		(layer "F.Cu")
		(net "IOC_UART_R_TX")
	)
	(segment
		(start 155.566364 -94.41688)
		(end 155.566364 -93.603826)
		(width 0.127)
		(layer "F.Cu")
		(net "IOC_UART_R_TX")
	)
	(segment
		(start 155.724098 -91.747848)
		(end 155.335986 -92.13596)
		(width 0.127)
		(layer "F.Cu")
		(net "IOC_UART_R_TX")
	)
	(segment
		(start 155.335986 -92.13596)
		(end 155.335986 -93.373448)
		(width 0.127)
		(layer "F.Cu")
		(net "IOC_UART_R_TX")
	)
	(segment
		(start 155.724098 -91.190064)
		(end 155.724098 -91.747848)
		(width 0.127)
		(layer "F.Cu")
		(net "IOC_UART_R_TX")
	)
	(via
		(at 155.566364 -93.603826)
		(size 0.6604)
		(drill 0.3302)
		(layers "F.Cu" "B.Cu")
		(net "IOC_UART_R_TX")
	)
	(segment
		(start 154.559 -88.4428)
		(end 154.559 -87.1982)
		(width 0.127)
		(layer "F.Cu")
		(net "IOC_UART_R_RX")
	)
	(segment
		(start 154.969464 -88.853264)
		(end 154.559 -88.4428)
		(width 0.127)
		(layer "F.Cu")
		(net "IOC_UART_R_RX")
	)
	(segment
		(start 154.559 -87.1982)
		(end 154.559 -86.2203)
		(width 0.127)
		(layer "F.Cu")
		(net "IOC_UART_R_RX")
	)
	(segment
		(start 155.724098 -88.853264)
		(end 154.969464 -88.853264)
		(width 0.127)
		(layer "F.Cu")
		(net "IOC_UART_R_RX")
	)
	(via
		(at 154.559 -87.1982)
		(size 0.6604)
		(drill 0.3302)
		(layers "F.Cu" "B.Cu")
		(net "IOC_UART_R_RX")
	)
	(segment
		(start 188.399928 -75.099926)
		(end 188.799724 -75.499722)
		(width 0.127)
		(layer "F.Cu")
		(net "IOC_UART_1_TX")
	)
	(via
		(at 188.799724 -75.499722)
		(size 0.508)
		(drill 0.254)
		(layers "F.Cu" "B.Cu")
		(net "IOC_UART_1_TX")
	)
	(segment
		(start 188.799724 -76.048108)
		(end 188.799724 -75.499722)
		(width 0.127)
		(layer "B.Cu")
		(net "IOC_UART_1_TX")
	)
	(segment
		(start 189.171072 -76.419456)
		(end 188.799724 -76.048108)
		(width 0.127)
		(layer "B.Cu")
		(net "IOC_UART_1_TX")
	)
	(segment
		(start 184.399936 -75.099926)
		(end 184.799732 -75.499722)
		(width 0.127)
		(layer "F.Cu")
		(net "IOC_UART_1_RX")
	)
	(via
		(at 184.799732 -75.499722)
		(size 0.508)
		(drill 0.254)
		(layers "F.Cu" "B.Cu")
		(net "IOC_UART_1_RX")
	)
	(segment
		(start 184.799732 -75.499722)
		(end 184.799732 -77.028294)
		(width 0.127)
		(layer "B.Cu")
		(net "IOC_UART_1_RX")
	)
	(segment
		(start 185.98642 -78.186026)
		(end 185.957464 -78.186026)
		(width 0.127)
		(layer "B.Cu")
		(net "IOC_UART_1_RX")
	)
	(segment
		(start 184.799732 -77.028294)
		(end 184.910984 -77.139546)
		(width 0.127)
		(layer "B.Cu")
		(net "IOC_UART_1_RX")
	)
	(segment
		(start 185.957464 -78.186026)
		(end 184.910984 -77.139546)
		(width 0.127)
		(layer "B.Cu")
		(net "IOC_UART_1_RX")
	)
	(segment
		(start 157.688788 -93.632528)
		(end 157.508194 -93.451934)
		(width 0.127)
		(layer "F.Cu")
		(net "IOC_UART_0_TX_R")
	)
	(segment
		(start 157.643576 -91.426792)
		(end 157.406848 -91.190064)
		(width 0.127)
		(layer "F.Cu")
		(net "IOC_UART_0_TX_R")
	)
	(segment
		(start 157.688788 -94.593156)
		(end 157.688788 -93.632528)
		(width 0.127)
		(layer "F.Cu")
		(net "IOC_UART_0_TX_R")
	)
	(segment
		(start 157.508194 -93.451934)
		(end 157.643576 -93.316552)
		(width 0.127)
		(layer "F.Cu")
		(net "IOC_UART_0_TX_R")
	)
	(segment
		(start 157.406848 -91.190064)
		(end 157.225238 -91.190064)
		(width 0.127)
		(layer "F.Cu")
		(net "IOC_UART_0_TX_R")
	)
	(segment
		(start 157.643576 -93.316552)
		(end 157.643576 -91.426792)
		(width 0.127)
		(layer "F.Cu")
		(net "IOC_UART_0_TX_R")
	)
	(via
		(at 157.508194 -93.451934)
		(size 0.6604)
		(drill 0.3302)
		(layers "F.Cu" "B.Cu")
		(net "IOC_UART_0_TX_R")
	)
	(segment
		(start 157.515306 -96.6216)
		(end 157.515306 -96.39427)
		(width 0.127)
		(layer "F.Cu")
		(net "IOC_UART_0_TX")
	)
	(segment
		(start 183.492902 -77.975206)
		(end 183.492902 -77.445108)
		(width 0.127)
		(layer "F.Cu")
		(net "IOC_UART_0_TX")
	)
	(segment
		(start 157.515306 -97.551494)
		(end 157.5054 -97.5614)
		(width 0.127)
		(layer "F.Cu")
		(net "IOC_UART_0_TX")
	)
	(segment
		(start 183.60009 -77.33792)
		(end 183.60009 -76.699872)
		(width 0.127)
		(layer "F.Cu")
		(net "IOC_UART_0_TX")
	)
	(segment
		(start 183.506872 -77.989176)
		(end 183.492902 -77.975206)
		(width 0.127)
		(layer "F.Cu")
		(net "IOC_UART_0_TX")
	)
	(segment
		(start 183.506872 -78.476856)
		(end 183.506872 -77.989176)
		(width 0.127)
		(layer "F.Cu")
		(net "IOC_UART_0_TX")
	)
	(segment
		(start 157.515306 -96.6216)
		(end 157.515306 -97.551494)
		(width 0.127)
		(layer "F.Cu")
		(net "IOC_UART_0_TX")
	)
	(segment
		(start 157.515306 -96.39427)
		(end 157.688788 -96.220788)
		(width 0.127)
		(layer "F.Cu")
		(net "IOC_UART_0_TX")
	)
	(segment
		(start 183.492902 -77.445108)
		(end 183.60009 -77.33792)
		(width 0.127)
		(layer "F.Cu")
		(net "IOC_UART_0_TX")
	)
	(segment
		(start 157.688788 -96.220788)
		(end 157.688788 -95.482156)
		(width 0.127)
		(layer "F.Cu")
		(net "IOC_UART_0_TX")
	)
	(via
		(at 183.506872 -78.476856)
		(size 0.508)
		(drill 0.254)
		(layers "F.Cu" "B.Cu")
		(net "IOC_UART_0_TX")
	)
	(via
		(at 183.262016 -102.189534)
		(size 0.508)
		(drill 0.254)
		(layers "F.Cu" "B.Cu")
		(net "IOC_UART_0_TX")
	)
	(via
		(at 157.5054 -97.5614)
		(size 0.508)
		(drill 0.254)
		(layers "F.Cu" "B.Cu")
		(net "IOC_UART_0_TX")
	)
	(via
		(at 157.515306 -96.6216)
		(size 0.6604)
		(drill 0.3302)
		(layers "F.Cu" "B.Cu")
		(net "IOC_UART_0_TX")
	)
	(segment
		(start 183.262016 -98.881184)
		(end 186.2455 -95.8977)
		(width 0.127)
		(layer "In2.Cu")
		(net "IOC_UART_0_TX")
	)
	(segment
		(start 183.506872 -79.468472)
		(end 183.506872 -78.476856)
		(width 0.127)
		(layer "In2.Cu")
		(net "IOC_UART_0_TX")
	)
	(segment
		(start 186.2455 -82.2071)
		(end 183.506872 -79.468472)
		(width 0.127)
		(layer "In2.Cu")
		(net "IOC_UART_0_TX")
	)
	(segment
		(start 183.262016 -102.189534)
		(end 183.262016 -98.881184)
		(width 0.127)
		(layer "In2.Cu")
		(net "IOC_UART_0_TX")
	)
	(segment
		(start 186.2455 -95.8977)
		(end 186.2455 -82.2071)
		(width 0.127)
		(layer "In2.Cu")
		(net "IOC_UART_0_TX")
	)
	(segment
		(start 164.311584 -101.255068)
		(end 164.311838 -101.255322)
		(width 0.127)
		(layer "In5.Cu")
		(net "IOC_UART_0_TX")
	)
	(segment
		(start 157.5054 -97.5614)
		(end 157.894274 -97.950274)
		(width 0.127)
		(layer "In5.Cu")
		(net "IOC_UART_0_TX")
	)
	(segment
		(start 182.32755 -101.255068)
		(end 183.262016 -102.189534)
		(width 0.127)
		(layer "In5.Cu")
		(net "IOC_UART_0_TX")
	)
	(segment
		(start 164.311838 -101.255322)
		(end 164.837618 -101.255322)
		(width 0.127)
		(layer "In5.Cu")
		(net "IOC_UART_0_TX")
	)
	(segment
		(start 157.894274 -97.950274)
		(end 160.806892 -97.950274)
		(width 0.127)
		(layer "In5.Cu")
		(net "IOC_UART_0_TX")
	)
	(segment
		(start 160.806892 -97.950274)
		(end 164.111686 -101.255068)
		(width 0.127)
		(layer "In5.Cu")
		(net "IOC_UART_0_TX")
	)
	(segment
		(start 164.837618 -101.255322)
		(end 164.837872 -101.255068)
		(width 0.127)
		(layer "In5.Cu")
		(net "IOC_UART_0_TX")
	)
	(segment
		(start 164.111686 -101.255068)
		(end 164.311584 -101.255068)
		(width 0.127)
		(layer "In5.Cu")
		(net "IOC_UART_0_TX")
	)
	(segment
		(start 164.837872 -101.255068)
		(end 182.32755 -101.255068)
		(width 0.127)
		(layer "In5.Cu")
		(net "IOC_UART_0_TX")
	)
	(segment
		(start 157.352238 -85.706966)
		(end 157.225238 -85.833966)
		(width 0.127)
		(layer "F.Cu")
		(net "IOC_UART_0_RX_R")
	)
	(segment
		(start 157.448758 -86.71052)
		(end 157.2006 -86.462362)
		(width 0.127)
		(layer "F.Cu")
		(net "IOC_UART_0_RX_R")
	)
	(segment
		(start 157.225238 -87.897716)
		(end 157.448758 -87.674196)
		(width 0.127)
		(layer "F.Cu")
		(net "IOC_UART_0_RX_R")
	)
	(segment
		(start 157.225238 -88.853264)
		(end 157.225238 -87.897716)
		(width 0.127)
		(layer "F.Cu")
		(net "IOC_UART_0_RX_R")
	)
	(segment
		(start 157.225238 -85.9028)
		(end 157.2006 -85.9028)
		(width 0.127)
		(layer "F.Cu")
		(net "IOC_UART_0_RX_R")
	)
	(segment
		(start 157.225238 -85.833966)
		(end 157.225238 -85.9028)
		(width 0.127)
		(layer "F.Cu")
		(net "IOC_UART_0_RX_R")
	)
	(segment
		(start 158.302706 -85.706966)
		(end 157.352238 -85.706966)
		(width 0.127)
		(layer "F.Cu")
		(net "IOC_UART_0_RX_R")
	)
	(segment
		(start 157.2006 -86.462362)
		(end 157.2006 -85.9028)
		(width 0.127)
		(layer "F.Cu")
		(net "IOC_UART_0_RX_R")
	)
	(segment
		(start 157.448758 -87.674196)
		(end 157.448758 -86.71052)
		(width 0.127)
		(layer "F.Cu")
		(net "IOC_UART_0_RX_R")
	)
	(via
		(at 157.2006 -85.9028)
		(size 0.6604)
		(drill 0.3302)
		(layers "F.Cu" "B.Cu")
		(net "IOC_UART_0_RX_R")
	)
	(segment
		(start 186.022234 -79.587344)
		(end 186.108594 -79.500984)
		(width 0.127)
		(layer "F.Cu")
		(net "IOC_UART_0_RX")
	)
	(segment
		(start 158.365698 -93.36913)
		(end 158.278576 -93.282008)
		(width 0.127)
		(layer "F.Cu")
		(net "IOC_UART_0_RX")
	)
	(segment
		(start 186.342782 -76.242926)
		(end 185.999882 -75.900026)
		(width 0.127)
		(layer "F.Cu")
		(net "IOC_UART_0_RX")
	)
	(segment
		(start 186.342782 -78.07833)
		(end 186.342782 -76.242926)
		(width 0.127)
		(layer "F.Cu")
		(net "IOC_UART_0_RX")
	)
	(segment
		(start 181.5973 -90.0557)
		(end 182.480458 -90.938858)
		(width 0.127)
		(layer "F.Cu")
		(net "IOC_UART_0_RX")
	)
	(segment
		(start 158.278576 -93.282008)
		(end 158.278576 -87.024464)
		(width 0.127)
		(layer "F.Cu")
		(net "IOC_UART_0_RX")
	)
	(segment
		(start 182.029608 -88.011)
		(end 181.5973 -88.443308)
		(width 0.127)
		(layer "F.Cu")
		(net "IOC_UART_0_RX")
	)
	(segment
		(start 186.108594 -79.500984)
		(end 186.108594 -78.312518)
		(width 0.127)
		(layer "F.Cu")
		(net "IOC_UART_0_RX")
	)
	(segment
		(start 182.372 -87.9475)
		(end 182.3085 -88.011)
		(width 0.127)
		(layer "F.Cu")
		(net "IOC_UART_0_RX")
	)
	(segment
		(start 186.022234 -80.226662)
		(end 186.022234 -79.587344)
		(width 0.127)
		(layer "F.Cu")
		(net "IOC_UART_0_RX")
	)
	(segment
		(start 159.826706 -98.544126)
		(end 158.365698 -97.083118)
		(width 0.127)
		(layer "F.Cu")
		(net "IOC_UART_0_RX")
	)
	(segment
		(start 185.607452 -80.641444)
		(end 186.022234 -80.226662)
		(width 0.127)
		(layer "F.Cu")
		(net "IOC_UART_0_RX")
	)
	(segment
		(start 158.302706 -87.000334)
		(end 158.302706 -86.595966)
		(width 0.127)
		(layer "F.Cu")
		(net "IOC_UART_0_RX")
	)
	(segment
		(start 182.372 -87.9475)
		(end 182.372 -86.173564)
		(width 0.127)
		(layer "F.Cu")
		(net "IOC_UART_0_RX")
	)
	(segment
		(start 158.365698 -97.083118)
		(end 158.365698 -93.36913)
		(width 0.127)
		(layer "F.Cu")
		(net "IOC_UART_0_RX")
	)
	(segment
		(start 182.372 -86.173564)
		(end 185.607452 -82.938112)
		(width 0.127)
		(layer "F.Cu")
		(net "IOC_UART_0_RX")
	)
	(segment
		(start 181.5973 -88.443308)
		(end 181.5973 -90.0557)
		(width 0.127)
		(layer "F.Cu")
		(net "IOC_UART_0_RX")
	)
	(segment
		(start 182.3085 -88.011)
		(end 182.029608 -88.011)
		(width 0.127)
		(layer "F.Cu")
		(net "IOC_UART_0_RX")
	)
	(segment
		(start 182.480458 -92.144342)
		(end 182.480458 -91.18092)
		(width 0.127)
		(layer "F.Cu")
		(net "IOC_UART_0_RX")
	)
	(segment
		(start 182.480458 -90.938858)
		(end 182.480458 -91.18092)
		(width 0.127)
		(layer "F.Cu")
		(net "IOC_UART_0_RX")
	)
	(segment
		(start 158.278576 -87.024464)
		(end 158.302706 -87.000334)
		(width 0.127)
		(layer "F.Cu")
		(net "IOC_UART_0_RX")
	)
	(segment
		(start 186.108594 -78.312518)
		(end 186.342782 -78.07833)
		(width 0.127)
		(layer "F.Cu")
		(net "IOC_UART_0_RX")
	)
	(segment
		(start 185.607452 -82.938112)
		(end 185.607452 -80.641444)
		(width 0.127)
		(layer "F.Cu")
		(net "IOC_UART_0_RX")
	)
	(segment
		(start 182.4482 -92.1766)
		(end 182.480458 -92.144342)
		(width 0.127)
		(layer "F.Cu")
		(net "IOC_UART_0_RX")
	)
	(via
		(at 182.480458 -91.18092)
		(size 0.6604)
		(drill 0.3302)
		(layers "F.Cu" "B.Cu")
		(net "IOC_UART_0_RX")
	)
	(via
		(at 159.826706 -98.544126)
		(size 0.508)
		(drill 0.254)
		(layers "F.Cu" "B.Cu")
		(net "IOC_UART_0_RX")
	)
	(via
		(at 182.4482 -92.1766)
		(size 0.508)
		(drill 0.254)
		(layers "F.Cu" "B.Cu")
		(net "IOC_UART_0_RX")
	)
	(via
		(at 180.087524 -104.192324)
		(size 0.508)
		(drill 0.254)
		(layers "F.Cu" "B.Cu")
		(net "IOC_UART_0_RX")
	)
	(segment
		(start 182.4482 -92.38361)
		(end 180.087524 -94.744286)
		(width 0.127)
		(layer "In2.Cu")
		(net "IOC_UART_0_RX")
	)
	(segment
		(start 180.087524 -94.744286)
		(end 180.087524 -104.192324)
		(width 0.127)
		(layer "In2.Cu")
		(net "IOC_UART_0_RX")
	)
	(segment
		(start 182.4482 -92.1766)
		(end 182.4482 -92.38361)
		(width 0.127)
		(layer "In2.Cu")
		(net "IOC_UART_0_RX")
	)
	(segment
		(start 173.568614 -104.963214)
		(end 177.392076 -104.963214)
		(width 0.127)
		(layer "In5.Cu")
		(net "IOC_UART_0_RX")
	)
	(segment
		(start 159.826706 -98.544126)
		(end 159.826706 -99.148646)
		(width 0.127)
		(layer "In5.Cu")
		(net "IOC_UART_0_RX")
	)
	(segment
		(start 171.239688 -102.634288)
		(end 173.568614 -104.963214)
		(width 0.127)
		(layer "In5.Cu")
		(net "IOC_UART_0_RX")
	)
	(segment
		(start 163.312348 -102.634288)
		(end 171.239688 -102.634288)
		(width 0.127)
		(layer "In5.Cu")
		(net "IOC_UART_0_RX")
	)
	(segment
		(start 177.392076 -104.963214)
		(end 178.162966 -104.192324)
		(width 0.127)
		(layer "In5.Cu")
		(net "IOC_UART_0_RX")
	)
	(segment
		(start 159.826706 -99.148646)
		(end 163.312348 -102.634288)
		(width 0.127)
		(layer "In5.Cu")
		(net "IOC_UART_0_RX")
	)
	(segment
		(start 178.162966 -104.192324)
		(end 180.087524 -104.192324)
		(width 0.127)
		(layer "In5.Cu")
		(net "IOC_UART_0_RX")
	)
	(segment
		(start 192.39992 -53.50002)
		(end 192.39992 -51.526694)
		(width 0.127)
		(layer "F.Cu")
		(net "IOC_TRST_N")
	)
	(segment
		(start 192.772538 -51.154076)
		(end 192.772538 -49.977294)
		(width 0.127)
		(layer "F.Cu")
		(net "IOC_TRST_N")
	)
	(segment
		(start 192.5574 -49.762156)
		(end 192.772538 -49.977294)
		(width 0.127)
		(layer "F.Cu")
		(net "IOC_TRST_N")
	)
	(segment
		(start 192.39992 -51.526694)
		(end 192.772538 -51.154076)
		(width 0.127)
		(layer "F.Cu")
		(net "IOC_TRST_N")
	)
	(segment
		(start 192.5574 -48.7299)
		(end 192.5574 -49.762156)
		(width 0.127)
		(layer "F.Cu")
		(net "IOC_TRST_N")
	)
	(segment
		(start 191.200786 -55.498746)
		(end 190.802006 -55.099966)
		(width 0.127)
		(layer "F.Cu")
		(net "IOC_TDO")
	)
	(segment
		(start 190.802006 -55.099966)
		(end 190.799974 -55.099966)
		(width 0.127)
		(layer "F.Cu")
		(net "IOC_TDO")
	)
	(via
		(at 191.200786 -55.498746)
		(size 0.508)
		(drill 0.254)
		(layers "F.Cu" "B.Cu")
		(net "IOC_TDO")
	)
	(segment
		(start 191.1858 -54.3814)
		(end 191.200786 -54.396386)
		(width 0.127)
		(layer "B.Cu")
		(net "IOC_TDO")
	)
	(segment
		(start 191.200786 -54.396386)
		(end 191.200786 -55.498746)
		(width 0.127)
		(layer "B.Cu")
		(net "IOC_TDO")
	)
	(segment
		(start 201.5998 -65.090548)
		(end 201.209148 -64.699896)
		(width 0.127)
		(layer "F.Cu")
		(net "IOC_SIO_BLINK")
	)
	(segment
		(start 201.209148 -64.699896)
		(end 201.200004 -64.699896)
		(width 0.127)
		(layer "F.Cu")
		(net "IOC_SIO_BLINK")
	)
	(via
		(at 201.5998 -65.090548)
		(size 0.508)
		(drill 0.254)
		(layers "F.Cu" "B.Cu")
		(net "IOC_SIO_BLINK")
	)
	(segment
		(start 201.5998 -65.090548)
		(end 202.021948 -64.6684)
		(width 0.127)
		(layer "B.Cu")
		(net "IOC_SIO_BLINK")
	)
	(segment
		(start 205.31201 -63.9318)
		(end 205.810866 -64.430656)
		(width 0.127)
		(layer "B.Cu")
		(net "IOC_SIO_BLINK")
	)
	(segment
		(start 204.1017 -63.9318)
		(end 205.31201 -63.9318)
		(width 0.127)
		(layer "B.Cu")
		(net "IOC_SIO_BLINK")
	)
	(segment
		(start 202.021948 -64.6684)
		(end 203.3651 -64.6684)
		(width 0.127)
		(layer "B.Cu")
		(net "IOC_SIO_BLINK")
	)
	(segment
		(start 206.293212 -64.430656)
		(end 206.40802 -64.315848)
		(width 0.127)
		(layer "B.Cu")
		(net "IOC_SIO_BLINK")
	)
	(segment
		(start 206.40802 -64.315848)
		(end 206.40802 -63.304166)
		(width 0.127)
		(layer "B.Cu")
		(net "IOC_SIO_BLINK")
	)
	(segment
		(start 205.810866 -64.430656)
		(end 206.293212 -64.430656)
		(width 0.127)
		(layer "B.Cu")
		(net "IOC_SIO_BLINK")
	)
	(segment
		(start 203.3651 -64.6684)
		(end 204.1017 -63.9318)
		(width 0.127)
		(layer "B.Cu")
		(net "IOC_SIO_BLINK")
	)
	(segment
		(start 160.927796 -88.3412)
		(end 162.333178 -88.3412)
		(width 0.127)
		(layer "F.Cu")
		(net "IOC_SDA_4")
	)
	(segment
		(start 182.79999 -64.6938)
		(end 182.79999 -64.699896)
		(width 0.127)
		(layer "F.Cu")
		(net "IOC_SDA_4")
	)
	(segment
		(start 162.333178 -88.3412)
		(end 162.529012 -88.537034)
		(width 0.127)
		(layer "F.Cu")
		(net "IOC_SDA_4")
	)
	(segment
		(start 175.005238 -71.55942)
		(end 175.908208 -71.55942)
		(width 0.127)
		(layer "F.Cu")
		(net "IOC_SDA_4")
	)
	(segment
		(start 182.404766 -64.298576)
		(end 182.79999 -64.6938)
		(width 0.127)
		(layer "F.Cu")
		(net "IOC_SDA_4")
	)
	(segment
		(start 163.342828 -89.901014)
		(end 162.529012 -89.087198)
		(width 0.127)
		(layer "F.Cu")
		(net "IOC_SDA_4")
	)
	(segment
		(start 175.908208 -71.55942)
		(end 176.353978 -72.00519)
		(width 0.127)
		(layer "F.Cu")
		(net "IOC_SDA_4")
	)
	(segment
		(start 162.529012 -89.087198)
		(end 162.529012 -88.537034)
		(width 0.127)
		(layer "F.Cu")
		(net "IOC_SDA_4")
	)
	(via
		(at 182.404766 -64.298576)
		(size 0.508)
		(drill 0.254)
		(layers "F.Cu" "B.Cu")
		(net "IOC_SDA_4")
	)
	(via
		(at 163.342828 -89.901014)
		(size 0.508)
		(drill 0.254)
		(layers "F.Cu" "B.Cu")
		(net "IOC_SDA_4")
	)
	(via
		(at 162.167062 -74.155046)
		(size 0.508)
		(drill 0.254)
		(layers "F.Cu" "B.Cu")
		(net "IOC_SDA_4")
	)
	(via
		(at 176.353978 -72.00519)
		(size 0.508)
		(drill 0.254)
		(layers "F.Cu" "B.Cu")
		(net "IOC_SDA_4")
	)
	(via
		(at 162.529012 -88.537034)
		(size 0.6604)
		(drill 0.3302)
		(layers "F.Cu" "B.Cu")
		(net "IOC_SDA_4")
	)
	(segment
		(start 163.342828 -82.177636)
		(end 163.342828 -89.901014)
		(width 0.127)
		(layer "In2.Cu")
		(net "IOC_SDA_4")
	)
	(segment
		(start 162.167062 -74.155046)
		(end 161.544 -74.778108)
		(width 0.127)
		(layer "In2.Cu")
		(net "IOC_SDA_4")
	)
	(segment
		(start 161.544 -80.378808)
		(end 163.342828 -82.177636)
		(width 0.127)
		(layer "In2.Cu")
		(net "IOC_SDA_4")
	)
	(segment
		(start 161.544 -74.778108)
		(end 161.544 -80.378808)
		(width 0.127)
		(layer "In2.Cu")
		(net "IOC_SDA_4")
	)
	(segment
		(start 171.16171 -75.273408)
		(end 171.161202 -75.2729)
		(width 0.127)
		(layer "In5.Cu")
		(net "IOC_SDA_4")
	)
	(segment
		(start 166.852854 -74.701654)
		(end 165.354 -73.2028)
		(width 0.127)
		(layer "In5.Cu")
		(net "IOC_SDA_4")
	)
	(segment
		(start 169.053002 -74.7268)
		(end 167.607234 -74.7268)
		(width 0.127)
		(layer "In5.Cu")
		(net "IOC_SDA_4")
	)
	(segment
		(start 167.607234 -74.7268)
		(end 167.582088 -74.701654)
		(width 0.127)
		(layer "In5.Cu")
		(net "IOC_SDA_4")
	)
	(segment
		(start 172.424598 -75.2729)
		(end 172.42409 -75.273408)
		(width 0.127)
		(layer "In5.Cu")
		(net "IOC_SDA_4")
	)
	(segment
		(start 179.236624 -70.23735)
		(end 179.236624 -70.237096)
		(width 0.127)
		(layer "In5.Cu")
		(net "IOC_SDA_4")
	)
	(segment
		(start 175.7934 -73.8251)
		(end 174.916846 -74.701654)
		(width 0.127)
		(layer "In5.Cu")
		(net "IOC_SDA_4")
	)
	(segment
		(start 176.131982 -72.227186)
		(end 176.131982 -73.000616)
		(width 0.127)
		(layer "In5.Cu")
		(net "IOC_SDA_4")
	)
	(segment
		(start 182.802784 -64.696594)
		(end 182.404766 -64.298576)
		(width 0.0889)
		(layer "In5.Cu")
		(net "IOC_SDA_4")
	)
	(segment
		(start 179.236624 -70.237096)
		(end 179.68722 -69.7865)
		(width 0.127)
		(layer "In5.Cu")
		(net "IOC_SDA_4")
	)
	(segment
		(start 174.916846 -74.701654)
		(end 174.430944 -74.701654)
		(width 0.127)
		(layer "In5.Cu")
		(net "IOC_SDA_4")
	)
	(segment
		(start 173.017434 -75.2729)
		(end 172.424598 -75.2729)
		(width 0.127)
		(layer "In5.Cu")
		(net "IOC_SDA_4")
	)
	(segment
		(start 177.68316 -70.650354)
		(end 178.823366 -70.650354)
		(width 0.127)
		(layer "In5.Cu")
		(net "IOC_SDA_4")
	)
	(segment
		(start 179.10302 -70.370954)
		(end 179.236624 -70.23735)
		(width 0.127)
		(layer "In5.Cu")
		(net "IOC_SDA_4")
	)
	(segment
		(start 179.102766 -70.370954)
		(end 179.10302 -70.370954)
		(width 0.127)
		(layer "In5.Cu")
		(net "IOC_SDA_4")
	)
	(segment
		(start 179.68722 -69.7865)
		(end 179.687474 -69.7865)
		(width 0.127)
		(layer "In5.Cu")
		(net "IOC_SDA_4")
	)
	(segment
		(start 176.353978 -72.00519)
		(end 176.131982 -72.227186)
		(width 0.127)
		(layer "In5.Cu")
		(net "IOC_SDA_4")
	)
	(segment
		(start 179.821078 -69.652642)
		(end 181.572662 -67.901058)
		(width 0.127)
		(layer "In5.Cu")
		(net "IOC_SDA_4")
	)
	(segment
		(start 167.582088 -74.701654)
		(end 166.852854 -74.701654)
		(width 0.127)
		(layer "In5.Cu")
		(net "IOC_SDA_4")
	)
	(segment
		(start 179.687474 -69.7865)
		(end 179.821078 -69.652896)
		(width 0.127)
		(layer "In5.Cu")
		(net "IOC_SDA_4")
	)
	(segment
		(start 176.353978 -72.00519)
		(end 176.353978 -71.979536)
		(width 0.127)
		(layer "In5.Cu")
		(net "IOC_SDA_4")
	)
	(segment
		(start 182.796942 -65.278508)
		(end 182.802784 -65.272666)
		(width 0.0889)
		(layer "In5.Cu")
		(net "IOC_SDA_4")
	)
	(segment
		(start 169.599102 -75.2729)
		(end 169.053002 -74.7268)
		(width 0.127)
		(layer "In5.Cu")
		(net "IOC_SDA_4")
	)
	(segment
		(start 162.167062 -74.103738)
		(end 162.167062 -74.155046)
		(width 0.127)
		(layer "In5.Cu")
		(net "IOC_SDA_4")
	)
	(segment
		(start 171.161202 -75.2729)
		(end 169.599102 -75.2729)
		(width 0.127)
		(layer "In5.Cu")
		(net "IOC_SDA_4")
	)
	(segment
		(start 179.821078 -69.652896)
		(end 179.821078 -69.652642)
		(width 0.127)
		(layer "In5.Cu")
		(net "IOC_SDA_4")
	)
	(segment
		(start 165.354 -73.2028)
		(end 163.068 -73.2028)
		(width 0.127)
		(layer "In5.Cu")
		(net "IOC_SDA_4")
	)
	(segment
		(start 173.859444 -75.273154)
		(end 173.017688 -75.273154)
		(width 0.127)
		(layer "In5.Cu")
		(net "IOC_SDA_4")
	)
	(segment
		(start 163.068 -73.2028)
		(end 162.167062 -74.103738)
		(width 0.127)
		(layer "In5.Cu")
		(net "IOC_SDA_4")
	)
	(segment
		(start 175.7934 -73.339198)
		(end 175.7934 -73.8251)
		(width 0.127)
		(layer "In5.Cu")
		(net "IOC_SDA_4")
	)
	(segment
		(start 178.823366 -70.650354)
		(end 179.102766 -70.370954)
		(width 0.127)
		(layer "In5.Cu")
		(net "IOC_SDA_4")
	)
	(segment
		(start 181.572662 -67.901058)
		(end 181.572662 -67.702938)
		(width 0.127)
		(layer "In5.Cu")
		(net "IOC_SDA_4")
	)
	(segment
		(start 181.572662 -67.702938)
		(end 182.79618 -66.47942)
		(width 0.127)
		(layer "In5.Cu")
		(net "IOC_SDA_4")
	)
	(segment
		(start 176.131982 -73.000616)
		(end 175.7934 -73.339198)
		(width 0.127)
		(layer "In5.Cu")
		(net "IOC_SDA_4")
	)
	(segment
		(start 182.802784 -65.272666)
		(end 182.802784 -64.696594)
		(width 0.0889)
		(layer "In5.Cu")
		(net "IOC_SDA_4")
	)
	(segment
		(start 176.353978 -71.979536)
		(end 177.68316 -70.650354)
		(width 0.127)
		(layer "In5.Cu")
		(net "IOC_SDA_4")
	)
	(segment
		(start 172.42409 -75.273408)
		(end 171.16171 -75.273408)
		(width 0.127)
		(layer "In5.Cu")
		(net "IOC_SDA_4")
	)
	(segment
		(start 173.017688 -75.273154)
		(end 173.017434 -75.2729)
		(width 0.127)
		(layer "In5.Cu")
		(net "IOC_SDA_4")
	)
	(segment
		(start 182.79618 -66.47942)
		(end 182.796942 -66.478658)
		(width 0.0889)
		(layer "In5.Cu")
		(net "IOC_SDA_4")
	)
	(segment
		(start 182.796942 -66.478658)
		(end 182.796942 -65.278508)
		(width 0.0889)
		(layer "In5.Cu")
		(net "IOC_SDA_4")
	)
	(segment
		(start 174.430944 -74.701654)
		(end 173.859444 -75.273154)
		(width 0.127)
		(layer "In5.Cu")
		(net "IOC_SDA_4")
	)
	(segment
		(start 179.949602 -66.67754)
		(end 178.999642 -67.6275)
		(width 0.127)
		(layer "F.Cu")
		(net "IOC_SDA_3")
	)
	(segment
		(start 181.622192 -66.67754)
		(end 179.949602 -66.67754)
		(width 0.127)
		(layer "F.Cu")
		(net "IOC_SDA_3")
	)
	(segment
		(start 181.99989 -66.299842)
		(end 181.622192 -66.67754)
		(width 0.127)
		(layer "F.Cu")
		(net "IOC_SDA_3")
	)
	(segment
		(start 177.650902 -67.9704)
		(end 176.279302 -69.342)
		(width 0.127)
		(layer "F.Cu")
		(net "IOC_SDA_3")
	)
	(segment
		(start 178.0286 -67.9704)
		(end 177.650902 -67.9704)
		(width 0.127)
		(layer "F.Cu")
		(net "IOC_SDA_3")
	)
	(segment
		(start 175.005238 -68.38442)
		(end 175.005238 -68.503038)
		(width 0.127)
		(layer "F.Cu")
		(net "IOC_SDA_3")
	)
	(segment
		(start 175.8442 -69.342)
		(end 176.0982 -69.342)
		(width 0.127)
		(layer "F.Cu")
		(net "IOC_SDA_3")
	)
	(segment
		(start 178.999642 -67.6275)
		(end 178.3715 -67.6275)
		(width 0.127)
		(layer "F.Cu")
		(net "IOC_SDA_3")
	)
	(segment
		(start 175.005238 -68.503038)
		(end 175.8442 -69.342)
		(width 0.127)
		(layer "F.Cu")
		(net "IOC_SDA_3")
	)
	(segment
		(start 178.3715 -67.6275)
		(end 178.0286 -67.9704)
		(width 0.127)
		(layer "F.Cu")
		(net "IOC_SDA_3")
	)
	(segment
		(start 176.279302 -69.342)
		(end 176.0982 -69.342)
		(width 0.127)
		(layer "F.Cu")
		(net "IOC_SDA_3")
	)
	(via
		(at 176.0982 -69.342)
		(size 0.6604)
		(drill 0.3302)
		(layers "F.Cu" "B.Cu")
		(net "IOC_SDA_3")
	)
	(segment
		(start 182.399686 -69.096636)
		(end 182.796434 -68.699888)
		(width 0.127)
		(layer "F.Cu")
		(net "IOC_SDA_2")
	)
	(segment
		(start 182.796434 -68.699888)
		(end 182.79999 -68.699888)
		(width 0.127)
		(layer "F.Cu")
		(net "IOC_SDA_2")
	)
	(via
		(at 178.220116 -67.8434)
		(size 0.6096)
		(drill 0.3048)
		(layers "F.Cu" "B.Cu")
		(net "IOC_SDA_2")
	)
	(via
		(at 182.399686 -69.096636)
		(size 0.508)
		(drill 0.254)
		(layers "F.Cu" "B.Cu")
		(net "IOC_SDA_2")
	)
	(segment
		(start 182.79999 -67.297808)
		(end 182.57774 -67.075558)
		(width 0.0889)
		(layer "B.Cu")
		(net "IOC_SDA_2")
	)
	(segment
		(start 182.399686 -69.096636)
		(end 182.79999 -68.696332)
		(width 0.0889)
		(layer "B.Cu")
		(net "IOC_SDA_2")
	)
	(segment
		(start 175.5267 -67.8434)
		(end 178.220116 -67.8434)
		(width 0.127)
		(layer "B.Cu")
		(net "IOC_SDA_2")
	)
	(segment
		(start 182.79999 -68.696332)
		(end 182.79999 -67.297808)
		(width 0.0889)
		(layer "B.Cu")
		(net "IOC_SDA_2")
	)
	(segment
		(start 178.395122 -67.8434)
		(end 178.220116 -67.8434)
		(width 0.127)
		(layer "B.Cu")
		(net "IOC_SDA_2")
	)
	(segment
		(start 175.0187 -67.3354)
		(end 175.5267 -67.8434)
		(width 0.127)
		(layer "B.Cu")
		(net "IOC_SDA_2")
	)
	(segment
		(start 179.162964 -67.075558)
		(end 178.395122 -67.8434)
		(width 0.127)
		(layer "B.Cu")
		(net "IOC_SDA_2")
	)
	(segment
		(start 182.57774 -67.075558)
		(end 179.162964 -67.075558)
		(width 0.127)
		(layer "B.Cu")
		(net "IOC_SDA_2")
	)
	(segment
		(start 175.005238 -69.45122)
		(end 175.565054 -70.011036)
		(width 0.127)
		(layer "F.Cu")
		(net "IOC_SDA_1")
	)
	(segment
		(start 180.060092 -67.099942)
		(end 178.86172 -68.298314)
		(width 0.127)
		(layer "F.Cu")
		(net "IOC_SDA_1")
	)
	(segment
		(start 176.328832 -70.011036)
		(end 177.861468 -68.4784)
		(width 0.127)
		(layer "F.Cu")
		(net "IOC_SDA_1")
	)
	(segment
		(start 177.861468 -68.4784)
		(end 178.414934 -68.4784)
		(width 0.127)
		(layer "F.Cu")
		(net "IOC_SDA_1")
	)
	(segment
		(start 178.414934 -68.4784)
		(end 178.59502 -68.298314)
		(width 0.127)
		(layer "F.Cu")
		(net "IOC_SDA_1")
	)
	(segment
		(start 178.86172 -68.298314)
		(end 178.59502 -68.298314)
		(width 0.127)
		(layer "F.Cu")
		(net "IOC_SDA_1")
	)
	(segment
		(start 181.200044 -67.099942)
		(end 180.060092 -67.099942)
		(width 0.127)
		(layer "F.Cu")
		(net "IOC_SDA_1")
	)
	(segment
		(start 175.565054 -70.011036)
		(end 176.328832 -70.011036)
		(width 0.127)
		(layer "F.Cu")
		(net "IOC_SDA_1")
	)
	(via
		(at 178.59502 -68.298314)
		(size 0.6604)
		(drill 0.3302)
		(layers "F.Cu" "B.Cu")
		(net "IOC_SDA_1")
	)
	(segment
		(start 181.99989 -64.699896)
		(end 181.65699 -65.042796)
		(width 0.127)
		(layer "F.Cu")
		(net "IOC_SDA_0")
	)
	(segment
		(start 178.174396 -65.208404)
		(end 177.961544 -65.208404)
		(width 0.127)
		(layer "F.Cu")
		(net "IOC_SDA_0")
	)
	(segment
		(start 177.961544 -65.208404)
		(end 177.58283 -65.587118)
		(width 0.127)
		(layer "F.Cu")
		(net "IOC_SDA_0")
	)
	(segment
		(start 181.65699 -65.042796)
		(end 180.05425 -65.042796)
		(width 0.127)
		(layer "F.Cu")
		(net "IOC_SDA_0")
	)
	(segment
		(start 174.8917 -64.8716)
		(end 175.641 -64.8716)
		(width 0.127)
		(layer "F.Cu")
		(net "IOC_SDA_0")
	)
	(segment
		(start 175.641 -64.8716)
		(end 176.356518 -65.587118)
		(width 0.127)
		(layer "F.Cu")
		(net "IOC_SDA_0")
	)
	(segment
		(start 179.781454 -64.77)
		(end 178.6128 -64.77)
		(width 0.127)
		(layer "F.Cu")
		(net "IOC_SDA_0")
	)
	(segment
		(start 178.6128 -64.77)
		(end 178.174396 -65.208404)
		(width 0.127)
		(layer "F.Cu")
		(net "IOC_SDA_0")
	)
	(segment
		(start 176.356518 -65.587118)
		(end 177.58283 -65.587118)
		(width 0.127)
		(layer "F.Cu")
		(net "IOC_SDA_0")
	)
	(segment
		(start 180.05425 -65.042796)
		(end 179.781454 -64.77)
		(width 0.127)
		(layer "F.Cu")
		(net "IOC_SDA_0")
	)
	(via
		(at 177.58283 -65.587118)
		(size 0.6604)
		(drill 0.3302)
		(layers "F.Cu" "B.Cu")
		(net "IOC_SDA_0")
	)
	(segment
		(start 176.8475 -71.780146)
		(end 176.862232 -71.794878)
		(width 0.127)
		(layer "F.Cu")
		(net "IOC_SCL_4")
	)
	(segment
		(start 179.635658 -68.471034)
		(end 178.586892 -69.5198)
		(width 0.127)
		(layer "F.Cu")
		(net "IOC_SCL_4")
	)
	(segment
		(start 162.386772 -89.916762)
		(end 160.833562 -89.916762)
		(width 0.127)
		(layer "F.Cu")
		(net "IOC_SCL_4")
	)
	(segment
		(start 176.862232 -71.794878)
		(end 176.862232 -72.215502)
		(width 0.127)
		(layer "F.Cu")
		(net "IOC_SCL_4")
	)
	(segment
		(start 181.576726 -68.323206)
		(end 181.091586 -68.323206)
		(width 0.127)
		(layer "F.Cu")
		(net "IOC_SCL_4")
	)
	(segment
		(start 176.8475 -70.9295)
		(end 176.8475 -71.780146)
		(width 0.127)
		(layer "F.Cu")
		(net "IOC_SCL_4")
	)
	(segment
		(start 175.0187 -72.5678)
		(end 174.9679 -72.6186)
		(width 0.127)
		(layer "F.Cu")
		(net "IOC_SCL_4")
	)
	(segment
		(start 174.9679 -73.4822)
		(end 174.9679 -72.6186)
		(width 0.127)
		(layer "F.Cu")
		(net "IOC_SCL_4")
	)
	(segment
		(start 176.862232 -72.215502)
		(end 176.56429 -72.513444)
		(width 0.127)
		(layer "F.Cu")
		(net "IOC_SCL_4")
	)
	(segment
		(start 175.90389 -74.4728)
		(end 175.211486 -73.780396)
		(width 0.127)
		(layer "F.Cu")
		(net "IOC_SCL_4")
	)
	(segment
		(start 175.9585 -74.4728)
		(end 175.90389 -74.4728)
		(width 0.127)
		(layer "F.Cu")
		(net "IOC_SCL_4")
	)
	(segment
		(start 175.211486 -73.725786)
		(end 174.9679 -73.4822)
		(width 0.127)
		(layer "F.Cu")
		(net "IOC_SCL_4")
	)
	(segment
		(start 178.2572 -69.5198)
		(end 176.8475 -70.9295)
		(width 0.127)
		(layer "F.Cu")
		(net "IOC_SCL_4")
	)
	(segment
		(start 181.99989 -67.900042)
		(end 181.576726 -68.323206)
		(width 0.127)
		(layer "F.Cu")
		(net "IOC_SCL_4")
	)
	(segment
		(start 176.114456 -72.5678)
		(end 175.0187 -72.5678)
		(width 0.127)
		(layer "F.Cu")
		(net "IOC_SCL_4")
	)
	(segment
		(start 178.586892 -69.5198)
		(end 178.2572 -69.5198)
		(width 0.127)
		(layer "F.Cu")
		(net "IOC_SCL_4")
	)
	(segment
		(start 160.833562 -89.916762)
		(end 160.277556 -89.360756)
		(width 0.127)
		(layer "F.Cu")
		(net "IOC_SCL_4")
	)
	(segment
		(start 176.56429 -72.513444)
		(end 176.168812 -72.513444)
		(width 0.127)
		(layer "F.Cu")
		(net "IOC_SCL_4")
	)
	(segment
		(start 180.943758 -68.471034)
		(end 179.635658 -68.471034)
		(width 0.127)
		(layer "F.Cu")
		(net "IOC_SCL_4")
	)
	(segment
		(start 181.091586 -68.323206)
		(end 180.943758 -68.471034)
		(width 0.127)
		(layer "F.Cu")
		(net "IOC_SCL_4")
	)
	(segment
		(start 175.211486 -73.780396)
		(end 175.211486 -73.725786)
		(width 0.127)
		(layer "F.Cu")
		(net "IOC_SCL_4")
	)
	(segment
		(start 176.168812 -72.513444)
		(end 176.114456 -72.5678)
		(width 0.127)
		(layer "F.Cu")
		(net "IOC_SCL_4")
	)
	(segment
		(start 160.277556 -89.360756)
		(end 160.277556 -88.3412)
		(width 0.127)
		(layer "F.Cu")
		(net "IOC_SCL_4")
	)
	(via
		(at 175.211486 -73.780396)
		(size 0.6604)
		(drill 0.3302)
		(layers "F.Cu" "B.Cu")
		(net "IOC_SCL_4")
	)
	(via
		(at 162.386772 -89.916762)
		(size 0.508)
		(drill 0.254)
		(layers "F.Cu" "B.Cu")
		(net "IOC_SCL_4")
	)
	(via
		(at 175.9585 -74.4728)
		(size 0.508)
		(drill 0.254)
		(layers "F.Cu" "B.Cu")
		(net "IOC_SCL_4")
	)
	(via
		(at 161.24682 -74.19213)
		(size 0.508)
		(drill 0.254)
		(layers "F.Cu" "B.Cu")
		(net "IOC_SCL_4")
	)
	(segment
		(start 162.386772 -89.916762)
		(end 162.386772 -81.940146)
		(width 0.127)
		(layer "In2.Cu")
		(net "IOC_SCL_4")
	)
	(segment
		(start 161.245804 -74.193146)
		(end 161.24682 -74.19213)
		(width 0.127)
		(layer "In2.Cu")
		(net "IOC_SCL_4")
	)
	(segment
		(start 162.386772 -81.940146)
		(end 161.036 -80.589374)
		(width 0.127)
		(layer "In2.Cu")
		(net "IOC_SCL_4")
	)
	(segment
		(start 161.036 -74.567542)
		(end 161.245804 -74.357738)
		(width 0.127)
		(layer "In2.Cu")
		(net "IOC_SCL_4")
	)
	(segment
		(start 161.245804 -74.357738)
		(end 161.245804 -74.193146)
		(width 0.127)
		(layer "In2.Cu")
		(net "IOC_SCL_4")
	)
	(segment
		(start 161.036 -80.589374)
		(end 161.036 -74.567542)
		(width 0.127)
		(layer "In2.Cu")
		(net "IOC_SCL_4")
	)
	(segment
		(start 162.934396 -74.663046)
		(end 161.717736 -74.663046)
		(width 0.127)
		(layer "In5.Cu")
		(net "IOC_SCL_4")
	)
	(segment
		(start 172.635164 -75.7809)
		(end 172.634656 -75.781408)
		(width 0.127)
		(layer "In5.Cu")
		(net "IOC_SCL_4")
	)
	(segment
		(start 170.950636 -75.7809)
		(end 169.388536 -75.7809)
		(width 0.127)
		(layer "In5.Cu")
		(net "IOC_SCL_4")
	)
	(segment
		(start 168.842436 -75.2348)
		(end 167.396668 -75.2348)
		(width 0.127)
		(layer "In5.Cu")
		(net "IOC_SCL_4")
	)
	(segment
		(start 170.951144 -75.781408)
		(end 170.950636 -75.7809)
		(width 0.127)
		(layer "In5.Cu")
		(net "IOC_SCL_4")
	)
	(segment
		(start 161.717736 -74.663046)
		(end 161.24682 -74.19213)
		(width 0.127)
		(layer "In5.Cu")
		(net "IOC_SCL_4")
	)
	(segment
		(start 169.388536 -75.7809)
		(end 168.842436 -75.2348)
		(width 0.127)
		(layer "In5.Cu")
		(net "IOC_SCL_4")
	)
	(segment
		(start 174.07001 -75.781154)
		(end 172.807122 -75.781154)
		(width 0.127)
		(layer "In5.Cu")
		(net "IOC_SCL_4")
	)
	(segment
		(start 172.807122 -75.781154)
		(end 172.806868 -75.7809)
		(width 0.127)
		(layer "In5.Cu")
		(net "IOC_SCL_4")
	)
	(segment
		(start 165.206934 -73.7743)
		(end 163.823142 -73.7743)
		(width 0.127)
		(layer "In5.Cu")
		(net "IOC_SCL_4")
	)
	(segment
		(start 167.396668 -75.2348)
		(end 167.371522 -75.209654)
		(width 0.127)
		(layer "In5.Cu")
		(net "IOC_SCL_4")
	)
	(segment
		(start 163.823142 -73.7743)
		(end 162.934396 -74.663046)
		(width 0.127)
		(layer "In5.Cu")
		(net "IOC_SCL_4")
	)
	(segment
		(start 172.634656 -75.781408)
		(end 170.951144 -75.781408)
		(width 0.127)
		(layer "In5.Cu")
		(net "IOC_SCL_4")
	)
	(segment
		(start 175.9585 -74.4728)
		(end 175.221646 -75.209654)
		(width 0.127)
		(layer "In5.Cu")
		(net "IOC_SCL_4")
	)
	(segment
		(start 174.64151 -75.209654)
		(end 174.07001 -75.781154)
		(width 0.127)
		(layer "In5.Cu")
		(net "IOC_SCL_4")
	)
	(segment
		(start 175.221646 -75.209654)
		(end 174.64151 -75.209654)
		(width 0.127)
		(layer "In5.Cu")
		(net "IOC_SCL_4")
	)
	(segment
		(start 167.371522 -75.209654)
		(end 166.642288 -75.209654)
		(width 0.127)
		(layer "In5.Cu")
		(net "IOC_SCL_4")
	)
	(segment
		(start 166.642288 -75.209654)
		(end 165.206934 -73.7743)
		(width 0.127)
		(layer "In5.Cu")
		(net "IOC_SCL_4")
	)
	(segment
		(start 172.806868 -75.7809)
		(end 172.635164 -75.7809)
		(width 0.127)
		(layer "In5.Cu")
		(net "IOC_SCL_4")
	)
	(segment
		(start 182.395876 -63.495936)
		(end 182.79999 -63.90005)
		(width 0.127)
		(layer "F.Cu")
		(net "IOC_SCL_3")
	)
	(segment
		(start 182.394606 -63.495936)
		(end 182.395876 -63.495936)
		(width 0.127)
		(layer "F.Cu")
		(net "IOC_SCL_3")
	)
	(via
		(at 181.413404 -63.41491)
		(size 0.6096)
		(drill 0.3048)
		(layers "F.Cu" "B.Cu")
		(net "IOC_SCL_3")
	)
	(via
		(at 182.394606 -63.495936)
		(size 0.508)
		(drill 0.254)
		(layers "F.Cu" "B.Cu")
		(net "IOC_SCL_3")
	)
	(segment
		(start 182.394606 -63.495936)
		(end 182.31358 -63.41491)
		(width 0.127)
		(layer "B.Cu")
		(net "IOC_SCL_3")
	)
	(segment
		(start 181.311042 -63.517272)
		(end 181.413404 -63.41491)
		(width 0.127)
		(layer "B.Cu")
		(net "IOC_SCL_3")
	)
	(segment
		(start 181.311042 -64.486282)
		(end 181.311042 -63.517272)
		(width 0.127)
		(layer "B.Cu")
		(net "IOC_SCL_3")
	)
	(segment
		(start 182.31358 -63.41491)
		(end 181.413404 -63.41491)
		(width 0.127)
		(layer "B.Cu")
		(net "IOC_SCL_3")
	)
	(segment
		(start 182.395622 -67.494658)
		(end 182.405274 -67.494658)
		(width 0.127)
		(layer "F.Cu")
		(net "IOC_SCL_2")
	)
	(segment
		(start 182.405274 -67.494658)
		(end 182.79999 -67.099942)
		(width 0.127)
		(layer "F.Cu")
		(net "IOC_SCL_2")
	)
	(segment
		(start 182.390288 -67.499992)
		(end 182.395622 -67.494658)
		(width 0.127)
		(layer "F.Cu")
		(net "IOC_SCL_2")
	)
	(via
		(at 182.390288 -67.499992)
		(size 0.508)
		(drill 0.254)
		(layers "F.Cu" "B.Cu")
		(net "IOC_SCL_2")
	)
	(via
		(at 176.707038 -68.3768)
		(size 0.6096)
		(drill 0.3048)
		(layers "F.Cu" "B.Cu")
		(net "IOC_SCL_2")
	)
	(segment
		(start 176.707038 -68.3768)
		(end 175.0187 -68.3768)
		(width 0.127)
		(layer "B.Cu")
		(net "IOC_SCL_2")
	)
	(segment
		(start 182.374032 -67.499992)
		(end 182.368698 -67.494658)
		(width 0.127)
		(layer "B.Cu")
		(net "IOC_SCL_2")
	)
	(segment
		(start 179.1462 -68.3768)
		(end 176.707038 -68.3768)
		(width 0.127)
		(layer "B.Cu")
		(net "IOC_SCL_2")
	)
	(segment
		(start 180.028342 -67.494658)
		(end 179.1462 -68.3768)
		(width 0.127)
		(layer "B.Cu")
		(net "IOC_SCL_2")
	)
	(segment
		(start 182.390288 -67.499992)
		(end 182.374032 -67.499992)
		(width 0.127)
		(layer "B.Cu")
		(net "IOC_SCL_2")
	)
	(segment
		(start 182.368698 -67.494658)
		(end 180.028342 -67.494658)
		(width 0.127)
		(layer "B.Cu")
		(net "IOC_SCL_2")
	)
	(segment
		(start 176.312576 -62.7634)
		(end 179.35575 -62.7634)
		(width 0.127)
		(layer "F.Cu")
		(net "IOC_SCL_1")
	)
	(segment
		(start 175.283876 -61.7347)
		(end 176.312576 -62.7634)
		(width 0.127)
		(layer "F.Cu")
		(net "IOC_SCL_1")
	)
	(segment
		(start 179.35575 -62.7634)
		(end 180.4924 -63.90005)
		(width 0.127)
		(layer "F.Cu")
		(net "IOC_SCL_1")
	)
	(segment
		(start 180.4924 -63.90005)
		(end 181.200044 -63.90005)
		(width 0.127)
		(layer "F.Cu")
		(net "IOC_SCL_1")
	)
	(segment
		(start 174.618396 -61.06922)
		(end 175.283876 -61.7347)
		(width 0.127)
		(layer "F.Cu")
		(net "IOC_SCL_1")
	)
	(segment
		(start 173.963838 -61.06922)
		(end 174.618396 -61.06922)
		(width 0.127)
		(layer "F.Cu")
		(net "IOC_SCL_1")
	)
	(via
		(at 175.283876 -61.7347)
		(size 0.6604)
		(drill 0.3302)
		(layers "F.Cu" "B.Cu")
		(net "IOC_SCL_1")
	)
	(segment
		(start 181.99989 -67.099942)
		(end 181.65699 -67.442842)
		(width 0.127)
		(layer "F.Cu")
		(net "IOC_SCL_0")
	)
	(segment
		(start 181.65699 -67.442842)
		(end 180.255672 -67.442842)
		(width 0.127)
		(layer "F.Cu")
		(net "IOC_SCL_0")
	)
	(segment
		(start 175.22063 -70.708012)
		(end 176.191672 -70.708012)
		(width 0.127)
		(layer "F.Cu")
		(net "IOC_SCL_0")
	)
	(segment
		(start 178.069494 -68.98894)
		(end 176.350422 -70.708012)
		(width 0.127)
		(layer "F.Cu")
		(net "IOC_SCL_0")
	)
	(segment
		(start 178.709574 -68.98894)
		(end 178.069494 -68.98894)
		(width 0.127)
		(layer "F.Cu")
		(net "IOC_SCL_0")
	)
	(segment
		(start 176.350422 -70.708012)
		(end 176.191672 -70.708012)
		(width 0.127)
		(layer "F.Cu")
		(net "IOC_SCL_0")
	)
	(segment
		(start 175.005238 -70.49262)
		(end 175.22063 -70.708012)
		(width 0.127)
		(layer "F.Cu")
		(net "IOC_SCL_0")
	)
	(segment
		(start 180.255672 -67.442842)
		(end 178.709574 -68.98894)
		(width 0.127)
		(layer "F.Cu")
		(net "IOC_SCL_0")
	)
	(via
		(at 176.191672 -70.708012)
		(size 0.6604)
		(drill 0.3302)
		(layers "F.Cu" "B.Cu")
		(net "IOC_SCL_0")
	)
	(segment
		(start 188.768228 -77.497178)
		(end 188.768228 -76.268326)
		(width 0.127)
		(layer "F.Cu")
		(net "IOC_RESET#")
	)
	(segment
		(start 188.768228 -76.268326)
		(end 188.399928 -75.900026)
		(width 0.127)
		(layer "F.Cu")
		(net "IOC_RESET#")
	)
	(segment
		(start 189.199774 -78.486)
		(end 189.199774 -77.928724)
		(width 0.127)
		(layer "F.Cu")
		(net "IOC_RESET#")
	)
	(segment
		(start 182.396892 -65.896744)
		(end 182.79999 -66.299842)
		(width 0.127)
		(layer "F.Cu")
		(net "IOC_RESET#")
	)
	(segment
		(start 182.396892 -65.893442)
		(end 182.396892 -65.896744)
		(width 0.127)
		(layer "F.Cu")
		(net "IOC_RESET#")
	)
	(segment
		(start 189.199774 -77.928724)
		(end 188.768228 -77.497178)
		(width 0.127)
		(layer "F.Cu")
		(net "IOC_RESET#")
	)
	(via
		(at 167.8178 -74.2188)
		(size 0.508)
		(drill 0.254)
		(layers "F.Cu" "B.Cu")
		(net "IOC_RESET#")
	)
	(via
		(at 166.2684 -93.3704)
		(size 0.508)
		(drill 0.254)
		(layers "F.Cu" "B.Cu")
		(net "IOC_RESET#")
	)
	(via
		(at 182.396892 -65.893442)
		(size 0.508)
		(drill 0.254)
		(layers "F.Cu" "B.Cu")
		(net "IOC_RESET#")
	)
	(via
		(at 189.199774 -78.486)
		(size 0.508)
		(drill 0.254)
		(layers "F.Cu" "B.Cu")
		(net "IOC_RESET#")
	)
	(via
		(at 159.254952 -93.38564)
		(size 0.6096)
		(drill 0.3048)
		(layers "F.Cu" "B.Cu")
		(net "IOC_RESET#")
	)
	(segment
		(start 155.761944 -93.582744)
		(end 155.761944 -93.286834)
		(width 0.127)
		(layer "B.Cu")
		(net "IOC_RESET#")
	)
	(segment
		(start 156.164534 -93.985334)
		(end 155.761944 -93.582744)
		(width 0.127)
		(layer "B.Cu")
		(net "IOC_RESET#")
	)
	(segment
		(start 158.655258 -93.985334)
		(end 156.164534 -93.985334)
		(width 0.127)
		(layer "B.Cu")
		(net "IOC_RESET#")
	)
	(segment
		(start 159.254952 -93.38564)
		(end 158.655258 -93.985334)
		(width 0.127)
		(layer "B.Cu")
		(net "IOC_RESET#")
	)
	(segment
		(start 153.430986 -93.4847)
		(end 155.564078 -93.4847)
		(width 0.127)
		(layer "B.Cu")
		(net "IOC_RESET#")
	)
	(segment
		(start 155.564078 -93.4847)
		(end 155.761944 -93.286834)
		(width 0.127)
		(layer "B.Cu")
		(net "IOC_RESET#")
	)
	(segment
		(start 166.2684 -93.3704)
		(end 166.25316 -93.38564)
		(width 0.127)
		(layer "B.Cu")
		(net "IOC_RESET#")
	)
	(segment
		(start 166.25316 -93.38564)
		(end 159.254952 -93.38564)
		(width 0.127)
		(layer "B.Cu")
		(net "IOC_RESET#")
	)
	(segment
		(start 187.52312 -65.97904)
		(end 188.09462 -66.55054)
		(width 0.127)
		(layer "In2.Cu")
		(net "IOC_RESET#")
	)
	(segment
		(start 183.026304 -66.319146)
		(end 183.574182 -66.319146)
		(width 0.127)
		(layer "In2.Cu")
		(net "IOC_RESET#")
	)
	(segment
		(start 188.400182 -72.134222)
		(end 188.400182 -72.465946)
		(width 0.0889)
		(layer "In2.Cu")
		(net "IOC_RESET#")
	)
	(segment
		(start 167.8178 -82.169)
		(end 167.8178 -74.2188)
		(width 0.127)
		(layer "In2.Cu")
		(net "IOC_RESET#")
	)
	(segment
		(start 183.693816 -66.43878)
		(end 185.79592 -66.43878)
		(width 0.127)
		(layer "In2.Cu")
		(net "IOC_RESET#")
	)
	(segment
		(start 186.25566 -65.97904)
		(end 187.52312 -65.97904)
		(width 0.127)
		(layer "In2.Cu")
		(net "IOC_RESET#")
	)
	(segment
		(start 189.199774 -72.933814)
		(end 189.199774 -78.486)
		(width 0.0889)
		(layer "In2.Cu")
		(net "IOC_RESET#")
	)
	(segment
		(start 188.63437 -72.700134)
		(end 188.966094 -72.700134)
		(width 0.0889)
		(layer "In2.Cu")
		(net "IOC_RESET#")
	)
	(segment
		(start 166.2684 -93.3704)
		(end 166.325296 -93.313504)
		(width 0.127)
		(layer "In2.Cu")
		(net "IOC_RESET#")
	)
	(segment
		(start 166.325296 -93.313504)
		(end 166.325296 -83.661504)
		(width 0.127)
		(layer "In2.Cu")
		(net "IOC_RESET#")
	)
	(segment
		(start 182.6006 -65.893442)
		(end 183.026304 -66.319146)
		(width 0.127)
		(layer "In2.Cu")
		(net "IOC_RESET#")
	)
	(segment
		(start 166.325296 -83.661504)
		(end 167.8178 -82.169)
		(width 0.127)
		(layer "In2.Cu")
		(net "IOC_RESET#")
	)
	(segment
		(start 188.412628 -70.050406)
		(end 188.412628 -72.121776)
		(width 0.0889)
		(layer "In2.Cu")
		(net "IOC_RESET#")
	)
	(segment
		(start 188.966094 -72.700134)
		(end 189.199774 -72.933814)
		(width 0.0889)
		(layer "In2.Cu")
		(net "IOC_RESET#")
	)
	(segment
		(start 188.95949 -67.103244)
		(end 189.193932 -67.337686)
		(width 0.0889)
		(layer "In2.Cu")
		(net "IOC_RESET#")
	)
	(segment
		(start 189.193932 -69.269102)
		(end 188.412628 -70.050406)
		(width 0.0889)
		(layer "In2.Cu")
		(net "IOC_RESET#")
	)
	(segment
		(start 188.09462 -66.55054)
		(end 188.647324 -67.103244)
		(width 0.0889)
		(layer "In2.Cu")
		(net "IOC_RESET#")
	)
	(segment
		(start 188.400182 -72.465946)
		(end 188.63437 -72.700134)
		(width 0.0889)
		(layer "In2.Cu")
		(net "IOC_RESET#")
	)
	(segment
		(start 188.647324 -67.103244)
		(end 188.95949 -67.103244)
		(width 0.0889)
		(layer "In2.Cu")
		(net "IOC_RESET#")
	)
	(segment
		(start 188.412628 -72.121776)
		(end 188.400182 -72.134222)
		(width 0.0889)
		(layer "In2.Cu")
		(net "IOC_RESET#")
	)
	(segment
		(start 182.396892 -65.893442)
		(end 182.6006 -65.893442)
		(width 0.127)
		(layer "In2.Cu")
		(net "IOC_RESET#")
	)
	(segment
		(start 183.574182 -66.319146)
		(end 183.693816 -66.43878)
		(width 0.127)
		(layer "In2.Cu")
		(net "IOC_RESET#")
	)
	(segment
		(start 185.79592 -66.43878)
		(end 186.25566 -65.97904)
		(width 0.127)
		(layer "In2.Cu")
		(net "IOC_RESET#")
	)
	(segment
		(start 189.193932 -67.337686)
		(end 189.193932 -69.269102)
		(width 0.0889)
		(layer "In2.Cu")
		(net "IOC_RESET#")
	)
	(segment
		(start 182.396892 -65.893442)
		(end 181.3433 -66.947034)
		(width 0.127)
		(layer "In5.Cu")
		(net "IOC_RESET#")
	)
	(segment
		(start 171.372022 -74.765154)
		(end 171.371768 -74.7649)
		(width 0.127)
		(layer "In5.Cu")
		(net "IOC_RESET#")
	)
	(segment
		(start 177.472594 -70.142354)
		(end 175.623982 -71.990966)
		(width 0.127)
		(layer "In5.Cu")
		(net "IOC_RESET#")
	)
	(segment
		(start 173.648878 -74.765154)
		(end 173.228254 -74.765154)
		(width 0.127)
		(layer "In5.Cu")
		(net "IOC_RESET#")
	)
	(segment
		(start 173.228254 -74.765154)
		(end 173.228 -74.7649)
		(width 0.127)
		(layer "In5.Cu")
		(net "IOC_RESET#")
	)
	(segment
		(start 169.809668 -74.7649)
		(end 169.263568 -74.2188)
		(width 0.127)
		(layer "In5.Cu")
		(net "IOC_RESET#")
	)
	(segment
		(start 171.792646 -74.765154)
		(end 171.372022 -74.765154)
		(width 0.127)
		(layer "In5.Cu")
		(net "IOC_RESET#")
	)
	(segment
		(start 171.371768 -74.7649)
		(end 169.809668 -74.7649)
		(width 0.127)
		(layer "In5.Cu")
		(net "IOC_RESET#")
	)
	(segment
		(start 175.623982 -71.990966)
		(end 175.623982 -72.79005)
		(width 0.127)
		(layer "In5.Cu")
		(net "IOC_RESET#")
	)
	(segment
		(start 172.213524 -74.765408)
		(end 171.7929 -74.765408)
		(width 0.127)
		(layer "In5.Cu")
		(net "IOC_RESET#")
	)
	(segment
		(start 171.7929 -74.765408)
		(end 171.792646 -74.765154)
		(width 0.127)
		(layer "In5.Cu")
		(net "IOC_RESET#")
	)
	(segment
		(start 181.3433 -67.807078)
		(end 179.008024 -70.142354)
		(width 0.127)
		(layer "In5.Cu")
		(net "IOC_RESET#")
	)
	(segment
		(start 175.623982 -72.79005)
		(end 173.648878 -74.765154)
		(width 0.127)
		(layer "In5.Cu")
		(net "IOC_RESET#")
	)
	(segment
		(start 181.3433 -66.947034)
		(end 181.3433 -67.807078)
		(width 0.127)
		(layer "In5.Cu")
		(net "IOC_RESET#")
	)
	(segment
		(start 169.263568 -74.2188)
		(end 167.8178 -74.2188)
		(width 0.127)
		(layer "In5.Cu")
		(net "IOC_RESET#")
	)
	(segment
		(start 179.008024 -70.142354)
		(end 177.472594 -70.142354)
		(width 0.127)
		(layer "In5.Cu")
		(net "IOC_RESET#")
	)
	(segment
		(start 172.214032 -74.7649)
		(end 172.213524 -74.765408)
		(width 0.127)
		(layer "In5.Cu")
		(net "IOC_RESET#")
	)
	(segment
		(start 173.228 -74.7649)
		(end 172.214032 -74.7649)
		(width 0.127)
		(layer "In5.Cu")
		(net "IOC_RESET#")
	)
	(segment
		(start 210.308952 -60.649866)
		(end 205.369668 -63.90005)
		(width 0.127)
		(layer "F.Cu")
		(net "IOC_REF_CLK_P")
	)
	(segment
		(start 223.61398 -59.73318)
		(end 223.891348 -60.010548)
		(width 0.127)
		(layer "F.Cu")
		(net "IOC_REF_CLK_P")
	)
	(segment
		(start 225.49739 -60.010548)
		(end 224.249234 -60.010548)
		(width 0.127)
		(layer "F.Cu")
		(net "IOC_REF_CLK_P")
	)
	(segment
		(start 205.369668 -63.90005)
		(end 204.399896 -63.90005)
		(width 0.127)
		(layer "F.Cu")
		(net "IOC_REF_CLK_P")
	)
	(segment
		(start 225.691954 -60.205112)
		(end 225.49739 -60.010548)
		(width 0.127)
		(layer "F.Cu")
		(net "IOC_REF_CLK_P")
	)
	(segment
		(start 210.308952 -60.649866)
		(end 211.702142 -59.73318)
		(width 0.127)
		(layer "F.Cu")
		(net "IOC_REF_CLK_P")
	)
	(segment
		(start 223.891348 -60.010548)
		(end 224.249234 -60.010548)
		(width 0.127)
		(layer "F.Cu")
		(net "IOC_REF_CLK_P")
	)
	(segment
		(start 211.702142 -59.73318)
		(end 223.61398 -59.73318)
		(width 0.127)
		(layer "F.Cu")
		(net "IOC_REF_CLK_P")
	)
	(via
		(at 210.308952 -60.649866)
		(size 0.6604)
		(drill 0.3302)
		(layers "F.Cu" "B.Cu")
		(net "IOC_REF_CLK_P")
	)
	(segment
		(start 204.240892 -63.5381)
		(end 203.878942 -63.90005)
		(width 0.127)
		(layer "F.Cu")
		(net "IOC_REF_CLK_N")
	)
	(segment
		(start 223.761808 -58.990992)
		(end 224.259902 -58.990992)
		(width 0.127)
		(layer "F.Cu")
		(net "IOC_REF_CLK_N")
	)
	(segment
		(start 211.482432 -59.176666)
		(end 204.853794 -63.5381)
		(width 0.127)
		(layer "F.Cu")
		(net "IOC_REF_CLK_N")
	)
	(segment
		(start 204.853794 -63.5381)
		(end 204.240892 -63.5381)
		(width 0.127)
		(layer "F.Cu")
		(net "IOC_REF_CLK_N")
	)
	(segment
		(start 203.878942 -63.90005)
		(end 203.60005 -63.90005)
		(width 0.127)
		(layer "F.Cu")
		(net "IOC_REF_CLK_N")
	)
	(segment
		(start 218.14028 -59.176666)
		(end 211.482432 -59.176666)
		(width 0.127)
		(layer "F.Cu")
		(net "IOC_REF_CLK_N")
	)
	(segment
		(start 223.576134 -59.176666)
		(end 223.761808 -58.990992)
		(width 0.127)
		(layer "F.Cu")
		(net "IOC_REF_CLK_N")
	)
	(segment
		(start 218.14028 -59.176666)
		(end 223.576134 -59.176666)
		(width 0.127)
		(layer "F.Cu")
		(net "IOC_REF_CLK_N")
	)
	(via
		(at 218.14028 -59.176666)
		(size 0.6604)
		(drill 0.3302)
		(layers "F.Cu" "B.Cu")
		(net "IOC_REF_CLK_N")
	)
	(segment
		(start 181.99989 -76.699872)
		(end 181.513226 -77.186536)
		(width 0.0889)
		(layer "F.Cu")
		(net "IOC_GPIO_9")
	)
	(via
		(at 181.513226 -77.186536)
		(size 0.508)
		(drill 0.254)
		(layers "F.Cu" "B.Cu")
		(net "IOC_GPIO_9")
	)
	(segment
		(start 181.513226 -77.186536)
		(end 181.61889 -77.2922)
		(width 0.127)
		(layer "B.Cu")
		(net "IOC_GPIO_9")
	)
	(segment
		(start 181.61889 -77.2922)
		(end 182.5244 -77.2922)
		(width 0.127)
		(layer "B.Cu")
		(net "IOC_GPIO_9")
	)
	(segment
		(start 177.688494 -73.6854)
		(end 177.546 -73.6854)
		(width 0.127)
		(layer "F.Cu")
		(net "IOC_GPIO_8")
	)
	(segment
		(start 180.27396 -71.099934)
		(end 177.688494 -73.6854)
		(width 0.127)
		(layer "F.Cu")
		(net "IOC_GPIO_8")
	)
	(segment
		(start 181.200044 -71.099934)
		(end 180.27396 -71.099934)
		(width 0.127)
		(layer "F.Cu")
		(net "IOC_GPIO_8")
	)
	(segment
		(start 188.399928 -72.69988)
		(end 188.000132 -72.300084)
		(width 0.127)
		(layer "F.Cu")
		(net "IOC_GPIO_7")
	)
	(via
		(at 188.000132 -72.300084)
		(size 0.508)
		(drill 0.254)
		(layers "F.Cu" "B.Cu")
		(net "IOC_GPIO_7")
	)
	(segment
		(start 188.000132 -72.300084)
		(end 188.000132 -72.06615)
		(width 0.0889)
		(layer "B.Cu")
		(net "IOC_GPIO_7")
	)
	(segment
		(start 188.400436 -71.213726)
		(end 188.849762 -70.7644)
		(width 0.0889)
		(layer "B.Cu")
		(net "IOC_GPIO_7")
	)
	(segment
		(start 188.400436 -71.665846)
		(end 188.400436 -71.213726)
		(width 0.0889)
		(layer "B.Cu")
		(net "IOC_GPIO_7")
	)
	(segment
		(start 188.849762 -70.7644)
		(end 188.9252 -70.7644)
		(width 0.0889)
		(layer "B.Cu")
		(net "IOC_GPIO_7")
	)
	(segment
		(start 188.000132 -72.06615)
		(end 188.400436 -71.665846)
		(width 0.0889)
		(layer "B.Cu")
		(net "IOC_GPIO_7")
	)
	(segment
		(start 185.200036 -75.099926)
		(end 185.599832 -75.499722)
		(width 0.127)
		(layer "F.Cu")
		(net "IOC_GPIO_6")
	)
	(via
		(at 185.599832 -75.499722)
		(size 0.508)
		(drill 0.254)
		(layers "F.Cu" "B.Cu")
		(net "IOC_GPIO_6")
	)
	(segment
		(start 185.599832 -76.65847)
		(end 185.599832 -75.499722)
		(width 0.127)
		(layer "B.Cu")
		(net "IOC_GPIO_6")
	)
	(segment
		(start 187.185808 -79.093314)
		(end 187.185808 -78.244446)
		(width 0.127)
		(layer "B.Cu")
		(net "IOC_GPIO_6")
	)
	(segment
		(start 187.185808 -78.244446)
		(end 185.599832 -76.65847)
		(width 0.127)
		(layer "B.Cu")
		(net "IOC_GPIO_6")
	)
	(segment
		(start 186.40044 -75.500484)
		(end 185.999882 -75.099926)
		(width 0.127)
		(layer "F.Cu")
		(net "IOC_GPIO_5")
	)
	(segment
		(start 186.408568 -75.500484)
		(end 186.40044 -75.500484)
		(width 0.127)
		(layer "F.Cu")
		(net "IOC_GPIO_5")
	)
	(via
		(at 186.408568 -75.500484)
		(size 0.508)
		(drill 0.254)
		(layers "F.Cu" "B.Cu")
		(net "IOC_GPIO_5")
	)
	(segment
		(start 186.358784 -75.550268)
		(end 186.358784 -76.451714)
		(width 0.127)
		(layer "B.Cu")
		(net "IOC_GPIO_5")
	)
	(segment
		(start 186.408568 -75.500484)
		(end 186.358784 -75.550268)
		(width 0.127)
		(layer "B.Cu")
		(net "IOC_GPIO_5")
	)
	(segment
		(start 181.200044 -75.900026)
		(end 178.08067 -79.0194)
		(width 0.127)
		(layer "F.Cu")
		(net "IOC_GPIO_4")
	)
	(segment
		(start 178.08067 -79.0194)
		(end 176.784 -79.0194)
		(width 0.127)
		(layer "F.Cu")
		(net "IOC_GPIO_4")
	)
	(segment
		(start 179.935886 -70.299834)
		(end 181.200044 -70.299834)
		(width 0.127)
		(layer "F.Cu")
		(net "IOC_GPIO_35")
	)
	(via
		(at 179.935886 -70.299834)
		(size 0.508)
		(drill 0.254)
		(layers "F.Cu" "B.Cu")
		(net "IOC_GPIO_35")
	)
	(segment
		(start 179.731416 -70.095364)
		(end 179.731416 -69.10578)
		(width 0.127)
		(layer "B.Cu")
		(net "IOC_GPIO_35")
	)
	(segment
		(start 179.935886 -70.299834)
		(end 179.731416 -70.095364)
		(width 0.127)
		(layer "B.Cu")
		(net "IOC_GPIO_35")
	)
	(segment
		(start 182.390288 -70.699884)
		(end 182.790338 -70.299834)
		(width 0.127)
		(layer "F.Cu")
		(net "IOC_GPIO_34")
	)
	(segment
		(start 182.790338 -70.299834)
		(end 182.79999 -70.299834)
		(width 0.127)
		(layer "F.Cu")
		(net "IOC_GPIO_34")
	)
	(via
		(at 182.390288 -70.699884)
		(size 0.508)
		(drill 0.254)
		(layers "F.Cu" "B.Cu")
		(net "IOC_GPIO_34")
	)
	(segment
		(start 182.308754 -70.699884)
		(end 182.390288 -70.699884)
		(width 0.127)
		(layer "B.Cu")
		(net "IOC_GPIO_34")
	)
	(segment
		(start 181.487826 -69.878956)
		(end 182.308754 -70.699884)
		(width 0.127)
		(layer "B.Cu")
		(net "IOC_GPIO_34")
	)
	(segment
		(start 181.624478 -69.8754)
		(end 181.99989 -69.499988)
		(width 0.127)
		(layer "F.Cu")
		(net "IOC_GPIO_33")
	)
	(segment
		(start 179.758594 -69.8754)
		(end 181.624478 -69.8754)
		(width 0.127)
		(layer "F.Cu")
		(net "IOC_GPIO_33")
	)
	(segment
		(start 179.394358 -70.907148)
		(end 179.394358 -70.239636)
		(width 0.127)
		(layer "F.Cu")
		(net "IOC_GPIO_33")
	)
	(segment
		(start 179.394358 -70.239636)
		(end 179.758594 -69.8754)
		(width 0.127)
		(layer "F.Cu")
		(net "IOC_GPIO_33")
	)
	(via
		(at 179.394358 -70.907148)
		(size 0.508)
		(drill 0.254)
		(layers "F.Cu" "B.Cu")
		(net "IOC_GPIO_33")
	)
	(segment
		(start 179.394358 -70.907148)
		(end 179.394358 -70.78726)
		(width 0.127)
		(layer "B.Cu")
		(net "IOC_GPIO_33")
	)
	(segment
		(start 179.394358 -70.78726)
		(end 178.695604 -70.088506)
		(width 0.127)
		(layer "B.Cu")
		(net "IOC_GPIO_33")
	)
	(segment
		(start 182.395876 -62.695836)
		(end 182.79999 -63.09995)
		(width 0.127)
		(layer "F.Cu")
		(net "IOC_GPIO_32")
	)
	(segment
		(start 182.394606 -62.695836)
		(end 182.395876 -62.695836)
		(width 0.127)
		(layer "F.Cu")
		(net "IOC_GPIO_32")
	)
	(via
		(at 182.394606 -62.695836)
		(size 0.508)
		(drill 0.254)
		(layers "F.Cu" "B.Cu")
		(net "IOC_GPIO_32")
	)
	(segment
		(start 180.8226 -62.7761)
		(end 180.2511 -63.3476)
		(width 0.127)
		(layer "B.Cu")
		(net "IOC_GPIO_32")
	)
	(segment
		(start 182.314342 -62.7761)
		(end 180.8226 -62.7761)
		(width 0.127)
		(layer "B.Cu")
		(net "IOC_GPIO_32")
	)
	(segment
		(start 182.394606 -62.695836)
		(end 182.314342 -62.7761)
		(width 0.127)
		(layer "B.Cu")
		(net "IOC_GPIO_32")
	)
	(segment
		(start 180.87594 -72.69988)
		(end 178.13782 -75.438)
		(width 0.127)
		(layer "F.Cu")
		(net "IOC_GPIO_31")
	)
	(segment
		(start 178.13782 -75.438)
		(end 176.0982 -75.438)
		(width 0.127)
		(layer "F.Cu")
		(net "IOC_GPIO_31")
	)
	(segment
		(start 181.200044 -72.69988)
		(end 180.87594 -72.69988)
		(width 0.127)
		(layer "F.Cu")
		(net "IOC_GPIO_31")
	)
	(segment
		(start 181.649624 -71.4502)
		(end 181.99989 -71.099934)
		(width 0.127)
		(layer "F.Cu")
		(net "IOC_GPIO_30")
	)
	(segment
		(start 179.00142 -72.780906)
		(end 180.332126 -71.4502)
		(width 0.127)
		(layer "F.Cu")
		(net "IOC_GPIO_30")
	)
	(segment
		(start 180.332126 -71.4502)
		(end 181.649624 -71.4502)
		(width 0.127)
		(layer "F.Cu")
		(net "IOC_GPIO_30")
	)
	(segment
		(start 178.233832 -74.260456)
		(end 179.00142 -73.492868)
		(width 0.127)
		(layer "F.Cu")
		(net "IOC_GPIO_30")
	)
	(segment
		(start 179.00142 -73.492868)
		(end 179.00142 -72.780906)
		(width 0.127)
		(layer "F.Cu")
		(net "IOC_GPIO_30")
	)
	(via
		(at 178.233832 -74.260456)
		(size 0.508)
		(drill 0.254)
		(layers "F.Cu" "B.Cu")
		(net "IOC_GPIO_30")
	)
	(segment
		(start 178.224688 -74.2696)
		(end 178.233832 -74.260456)
		(width 0.127)
		(layer "B.Cu")
		(net "IOC_GPIO_30")
	)
	(segment
		(start 177.28184 -74.2696)
		(end 178.224688 -74.2696)
		(width 0.127)
		(layer "B.Cu")
		(net "IOC_GPIO_30")
	)
	(segment
		(start 186.799982 -75.099926)
		(end 187.200032 -75.499976)
		(width 0.127)
		(layer "F.Cu")
		(net "IOC_GPIO_3")
	)
	(via
		(at 187.200032 -75.499976)
		(size 0.508)
		(drill 0.254)
		(layers "F.Cu" "B.Cu")
		(net "IOC_GPIO_3")
	)
	(segment
		(start 187.7314 -76.031344)
		(end 187.200032 -75.499976)
		(width 0.127)
		(layer "B.Cu")
		(net "IOC_GPIO_3")
	)
	(segment
		(start 187.7314 -76.740004)
		(end 187.7314 -76.031344)
		(width 0.127)
		(layer "B.Cu")
		(net "IOC_GPIO_3")
	)
	(segment
		(start 182.794148 -71.900034)
		(end 182.79999 -71.900034)
		(width 0.127)
		(layer "F.Cu")
		(net "IOC_GPIO_29")
	)
	(segment
		(start 182.39232 -72.301862)
		(end 182.794148 -71.900034)
		(width 0.127)
		(layer "F.Cu")
		(net "IOC_GPIO_29")
	)
	(via
		(at 182.39232 -72.301862)
		(size 0.508)
		(drill 0.254)
		(layers "F.Cu" "B.Cu")
		(net "IOC_GPIO_29")
	)
	(segment
		(start 182.39232 -72.301862)
		(end 182.260748 -72.17029)
		(width 0.127)
		(layer "B.Cu")
		(net "IOC_GPIO_29")
	)
	(segment
		(start 182.260748 -72.17029)
		(end 181.302406 -72.17029)
		(width 0.127)
		(layer "B.Cu")
		(net "IOC_GPIO_29")
	)
	(segment
		(start 182.793894 -71.099934)
		(end 182.79999 -71.099934)
		(width 0.127)
		(layer "F.Cu")
		(net "IOC_GPIO_28")
	)
	(segment
		(start 182.401718 -71.49211)
		(end 182.793894 -71.099934)
		(width 0.127)
		(layer "F.Cu")
		(net "IOC_GPIO_28")
	)
	(via
		(at 182.401718 -71.49211)
		(size 0.508)
		(drill 0.254)
		(layers "F.Cu" "B.Cu")
		(net "IOC_GPIO_28")
	)
	(segment
		(start 181.804564 -70.894956)
		(end 182.401718 -71.49211)
		(width 0.127)
		(layer "B.Cu")
		(net "IOC_GPIO_28")
	)
	(segment
		(start 180.601366 -70.894956)
		(end 181.804564 -70.894956)
		(width 0.127)
		(layer "B.Cu")
		(net "IOC_GPIO_28")
	)
	(segment
		(start 181.617112 -72.282812)
		(end 181.99989 -71.900034)
		(width 0.127)
		(layer "F.Cu")
		(net "IOC_GPIO_27")
	)
	(segment
		(start 180.423566 -72.444356)
		(end 180.58511 -72.282812)
		(width 0.127)
		(layer "F.Cu")
		(net "IOC_GPIO_27")
	)
	(segment
		(start 180.58511 -72.282812)
		(end 181.617112 -72.282812)
		(width 0.127)
		(layer "F.Cu")
		(net "IOC_GPIO_27")
	)
	(via
		(at 180.423566 -72.444356)
		(size 0.508)
		(drill 0.254)
		(layers "F.Cu" "B.Cu")
		(net "IOC_GPIO_27")
	)
	(segment
		(start 179.577238 -71.92137)
		(end 180.100224 -72.444356)
		(width 0.127)
		(layer "B.Cu")
		(net "IOC_GPIO_27")
	)
	(segment
		(start 180.100224 -72.444356)
		(end 180.423566 -72.444356)
		(width 0.127)
		(layer "B.Cu")
		(net "IOC_GPIO_27")
	)
	(segment
		(start 182.397146 -73.902824)
		(end 182.79999 -73.49998)
		(width 0.127)
		(layer "F.Cu")
		(net "IOC_GPIO_26")
	)
	(segment
		(start 182.397146 -73.904856)
		(end 182.397146 -73.902824)
		(width 0.127)
		(layer "F.Cu")
		(net "IOC_GPIO_26")
	)
	(via
		(at 182.397146 -73.904856)
		(size 0.508)
		(drill 0.254)
		(layers "F.Cu" "B.Cu")
		(net "IOC_GPIO_26")
	)
	(segment
		(start 180.675788 -74.726546)
		(end 181.497478 -73.904856)
		(width 0.127)
		(layer "B.Cu")
		(net "IOC_GPIO_26")
	)
	(segment
		(start 181.497478 -73.904856)
		(end 182.397146 -73.904856)
		(width 0.127)
		(layer "B.Cu")
		(net "IOC_GPIO_26")
	)
	(segment
		(start 183.195722 -73.904094)
		(end 182.79999 -74.299826)
		(width 0.127)
		(layer "F.Cu")
		(net "IOC_GPIO_25")
	)
	(segment
		(start 183.195722 -72.305164)
		(end 183.195722 -73.904094)
		(width 0.127)
		(layer "F.Cu")
		(net "IOC_GPIO_25")
	)
	(segment
		(start 183.19242 -72.301862)
		(end 183.195722 -72.305164)
		(width 0.127)
		(layer "F.Cu")
		(net "IOC_GPIO_25")
	)
	(via
		(at 183.19242 -72.301862)
		(size 0.508)
		(drill 0.254)
		(layers "F.Cu" "B.Cu")
		(net "IOC_GPIO_25")
	)
	(segment
		(start 183.19242 -74.163174)
		(end 182.43804 -74.917554)
		(width 0.127)
		(layer "B.Cu")
		(net "IOC_GPIO_25")
	)
	(segment
		(start 183.19242 -72.301862)
		(end 183.19242 -74.163174)
		(width 0.127)
		(layer "B.Cu")
		(net "IOC_GPIO_25")
	)
	(segment
		(start 180.6575 -67.900042)
		(end 181.200044 -67.900042)
		(width 0.127)
		(layer "F.Cu")
		(net "IOC_GPIO_24")
	)
	(segment
		(start 180.512466 -68.045076)
		(end 180.6575 -67.900042)
		(width 0.127)
		(layer "F.Cu")
		(net "IOC_GPIO_24")
	)
	(via
		(at 180.512466 -68.045076)
		(size 0.508)
		(drill 0.254)
		(layers "F.Cu" "B.Cu")
		(net "IOC_GPIO_24")
	)
	(segment
		(start 180.512466 -68.045076)
		(end 181.278276 -68.045076)
		(width 0.127)
		(layer "B.Cu")
		(net "IOC_GPIO_24")
	)
	(segment
		(start 181.278276 -68.045076)
		(end 181.4576 -68.2244)
		(width 0.127)
		(layer "B.Cu")
		(net "IOC_GPIO_24")
	)
	(segment
		(start 176.956212 -73.099676)
		(end 177.61712 -73.099676)
		(width 0.127)
		(layer "F.Cu")
		(net "IOC_GPIO_23")
	)
	(segment
		(start 178.443128 -72.458072)
		(end 180.07457 -70.82663)
		(width 0.127)
		(layer "F.Cu")
		(net "IOC_GPIO_23")
	)
	(segment
		(start 180.6956 -70.718934)
		(end 181.58079 -70.718934)
		(width 0.127)
		(layer "F.Cu")
		(net "IOC_GPIO_23")
	)
	(segment
		(start 180.587904 -70.82663)
		(end 180.6956 -70.718934)
		(width 0.127)
		(layer "F.Cu")
		(net "IOC_GPIO_23")
	)
	(segment
		(start 180.07457 -70.82663)
		(end 180.587904 -70.82663)
		(width 0.127)
		(layer "F.Cu")
		(net "IOC_GPIO_23")
	)
	(segment
		(start 177.61712 -73.099676)
		(end 178.258724 -72.458072)
		(width 0.127)
		(layer "F.Cu")
		(net "IOC_GPIO_23")
	)
	(segment
		(start 176.659032 -73.396856)
		(end 176.956212 -73.099676)
		(width 0.127)
		(layer "F.Cu")
		(net "IOC_GPIO_23")
	)
	(segment
		(start 181.58079 -70.718934)
		(end 181.99989 -70.299834)
		(width 0.127)
		(layer "F.Cu")
		(net "IOC_GPIO_23")
	)
	(segment
		(start 178.258724 -72.458072)
		(end 178.443128 -72.458072)
		(width 0.127)
		(layer "F.Cu")
		(net "IOC_GPIO_23")
	)
	(via
		(at 176.659032 -73.396856)
		(size 0.508)
		(drill 0.254)
		(layers "F.Cu" "B.Cu")
		(net "IOC_GPIO_23")
	)
	(segment
		(start 176.65827 -73.397618)
		(end 175.710596 -73.397618)
		(width 0.127)
		(layer "B.Cu")
		(net "IOC_GPIO_23")
	)
	(segment
		(start 176.659032 -73.396856)
		(end 176.65827 -73.397618)
		(width 0.127)
		(layer "B.Cu")
		(net "IOC_GPIO_23")
	)
	(segment
		(start 181.099968 -75.468226)
		(end 178.615594 -77.9526)
		(width 0.127)
		(layer "F.Cu")
		(net "IOC_GPIO_22")
	)
	(segment
		(start 181.466998 -75.468226)
		(end 181.099968 -75.468226)
		(width 0.127)
		(layer "F.Cu")
		(net "IOC_GPIO_22")
	)
	(segment
		(start 178.615594 -77.9526)
		(end 177.6222 -77.9526)
		(width 0.127)
		(layer "F.Cu")
		(net "IOC_GPIO_22")
	)
	(segment
		(start 181.99989 -75.099926)
		(end 181.835298 -75.099926)
		(width 0.127)
		(layer "F.Cu")
		(net "IOC_GPIO_22")
	)
	(segment
		(start 181.835298 -75.099926)
		(end 181.466998 -75.468226)
		(width 0.127)
		(layer "F.Cu")
		(net "IOC_GPIO_22")
	)
	(segment
		(start 180.962808 -74.299826)
		(end 181.200044 -74.299826)
		(width 0.127)
		(layer "F.Cu")
		(net "IOC_GPIO_21")
	)
	(segment
		(start 179.217066 -75.809856)
		(end 179.452778 -75.809856)
		(width 0.127)
		(layer "F.Cu")
		(net "IOC_GPIO_21")
	)
	(segment
		(start 179.452778 -75.809856)
		(end 180.962808 -74.299826)
		(width 0.127)
		(layer "F.Cu")
		(net "IOC_GPIO_21")
	)
	(via
		(at 179.217066 -75.809856)
		(size 0.508)
		(drill 0.254)
		(layers "F.Cu" "B.Cu")
		(net "IOC_GPIO_21")
	)
	(segment
		(start 179.4764 -77.1652)
		(end 179.4764 -76.06919)
		(width 0.127)
		(layer "B.Cu")
		(net "IOC_GPIO_21")
	)
	(segment
		(start 179.4764 -76.06919)
		(end 179.217066 -75.809856)
		(width 0.127)
		(layer "B.Cu")
		(net "IOC_GPIO_21")
	)
	(segment
		(start 182.841392 -78.4987)
		(end 181.2036 -80.136492)
		(width 0.127)
		(layer "F.Cu")
		(net "IOC_GPIO_20")
	)
	(segment
		(start 181.2036 -80.136492)
		(end 181.2036 -80.4672)
		(width 0.127)
		(layer "F.Cu")
		(net "IOC_GPIO_20")
	)
	(segment
		(start 183.16829 -76.268326)
		(end 183.16829 -78.180946)
		(width 0.127)
		(layer "F.Cu")
		(net "IOC_GPIO_20")
	)
	(segment
		(start 182.79999 -75.900026)
		(end 183.16829 -76.268326)
		(width 0.127)
		(layer "F.Cu")
		(net "IOC_GPIO_20")
	)
	(segment
		(start 182.850536 -78.4987)
		(end 182.841392 -78.4987)
		(width 0.127)
		(layer "F.Cu")
		(net "IOC_GPIO_20")
	)
	(segment
		(start 183.16829 -78.180946)
		(end 182.850536 -78.4987)
		(width 0.127)
		(layer "F.Cu")
		(net "IOC_GPIO_20")
	)
	(segment
		(start 187.600082 -75.099926)
		(end 187.999878 -75.499722)
		(width 0.127)
		(layer "F.Cu")
		(net "IOC_GPIO_2")
	)
	(via
		(at 187.999878 -75.499722)
		(size 0.508)
		(drill 0.254)
		(layers "F.Cu" "B.Cu")
		(net "IOC_GPIO_2")
	)
	(segment
		(start 188.341 -75.840844)
		(end 187.999878 -75.499722)
		(width 0.127)
		(layer "B.Cu")
		(net "IOC_GPIO_2")
	)
	(segment
		(start 188.2394 -78.0796)
		(end 188.341 -77.978)
		(width 0.127)
		(layer "B.Cu")
		(net "IOC_GPIO_2")
	)
	(segment
		(start 188.341 -77.978)
		(end 188.341 -75.840844)
		(width 0.127)
		(layer "B.Cu")
		(net "IOC_GPIO_2")
	)
	(segment
		(start 182.79999 -77.079094)
		(end 182.79999 -76.699872)
		(width 0.127)
		(layer "F.Cu")
		(net "IOC_GPIO_19")
	)
	(segment
		(start 182.6768 -77.202284)
		(end 182.79999 -77.079094)
		(width 0.127)
		(layer "F.Cu")
		(net "IOC_GPIO_19")
	)
	(segment
		(start 182.6768 -78.0796)
		(end 182.6768 -77.202284)
		(width 0.127)
		(layer "F.Cu")
		(net "IOC_GPIO_19")
	)
	(via
		(at 182.6768 -78.0796)
		(size 0.508)
		(drill 0.254)
		(layers "F.Cu" "B.Cu")
		(net "IOC_GPIO_19")
	)
	(segment
		(start 181.87924 -78.56728)
		(end 182.18912 -78.56728)
		(width 0.127)
		(layer "B.Cu")
		(net "IOC_GPIO_19")
	)
	(segment
		(start 182.18912 -78.56728)
		(end 182.6768 -78.0796)
		(width 0.127)
		(layer "B.Cu")
		(net "IOC_GPIO_19")
	)
	(segment
		(start 179.193698 -76.444856)
		(end 180.971698 -74.666856)
		(width 0.127)
		(layer "F.Cu")
		(net "IOC_GPIO_18")
	)
	(segment
		(start 181.63286 -74.666856)
		(end 181.99989 -74.299826)
		(width 0.127)
		(layer "F.Cu")
		(net "IOC_GPIO_18")
	)
	(segment
		(start 178.836066 -76.444856)
		(end 179.193698 -76.444856)
		(width 0.127)
		(layer "F.Cu")
		(net "IOC_GPIO_18")
	)
	(segment
		(start 180.971698 -74.666856)
		(end 181.63286 -74.666856)
		(width 0.127)
		(layer "F.Cu")
		(net "IOC_GPIO_18")
	)
	(via
		(at 178.836066 -76.444856)
		(size 0.508)
		(drill 0.254)
		(layers "F.Cu" "B.Cu")
		(net "IOC_GPIO_18")
	)
	(segment
		(start 177.9778 -77.4954)
		(end 178.836066 -76.637134)
		(width 0.127)
		(layer "B.Cu")
		(net "IOC_GPIO_18")
	)
	(segment
		(start 178.836066 -76.637134)
		(end 178.836066 -76.444856)
		(width 0.127)
		(layer "B.Cu")
		(net "IOC_GPIO_18")
	)
	(segment
		(start 179.598066 -72.888856)
		(end 179.598066 -72.657716)
		(width 0.127)
		(layer "F.Cu")
		(net "IOC_GPIO_17")
	)
	(segment
		(start 179.598066 -72.657716)
		(end 180.355748 -71.900034)
		(width 0.127)
		(layer "F.Cu")
		(net "IOC_GPIO_17")
	)
	(segment
		(start 180.355748 -71.900034)
		(end 181.200044 -71.900034)
		(width 0.127)
		(layer "F.Cu")
		(net "IOC_GPIO_17")
	)
	(via
		(at 179.598066 -72.888856)
		(size 0.508)
		(drill 0.254)
		(layers "F.Cu" "B.Cu")
		(net "IOC_GPIO_17")
	)
	(segment
		(start 179.53101 -72.8218)
		(end 178.4096 -72.8218)
		(width 0.127)
		(layer "B.Cu")
		(net "IOC_GPIO_17")
	)
	(segment
		(start 179.598066 -72.888856)
		(end 179.53101 -72.8218)
		(width 0.127)
		(layer "B.Cu")
		(net "IOC_GPIO_17")
	)
	(segment
		(start 179.789836 -74.43724)
		(end 180.727096 -73.49998)
		(width 0.127)
		(layer "F.Cu")
		(net "IOC_GPIO_16")
	)
	(segment
		(start 180.727096 -73.49998)
		(end 181.200044 -73.49998)
		(width 0.127)
		(layer "F.Cu")
		(net "IOC_GPIO_16")
	)
	(via
		(at 179.789836 -74.43724)
		(size 0.508)
		(drill 0.254)
		(layers "F.Cu" "B.Cu")
		(net "IOC_GPIO_16")
	)
	(segment
		(start 179.565808 -74.43724)
		(end 178.335686 -75.667362)
		(width 0.127)
		(layer "B.Cu")
		(net "IOC_GPIO_16")
	)
	(segment
		(start 179.789836 -74.43724)
		(end 179.565808 -74.43724)
		(width 0.127)
		(layer "B.Cu")
		(net "IOC_GPIO_16")
	)
	(segment
		(start 177.370232 -72.426068)
		(end 177.370232 -71.584312)
		(width 0.127)
		(layer "F.Cu")
		(net "IOC_GPIO_15")
	)
	(segment
		(start 177.370232 -71.584312)
		(end 177.3555 -71.56958)
		(width 0.127)
		(layer "F.Cu")
		(net "IOC_GPIO_15")
	)
	(segment
		(start 177.301906 -72.606916)
		(end 177.301906 -72.494394)
		(width 0.127)
		(layer "F.Cu")
		(net "IOC_GPIO_15")
	)
	(segment
		(start 177.3555 -71.15937)
		(end 179.814982 -68.699888)
		(width 0.127)
		(layer "F.Cu")
		(net "IOC_GPIO_15")
	)
	(segment
		(start 177.3555 -71.56958)
		(end 177.3555 -71.15937)
		(width 0.127)
		(layer "F.Cu")
		(net "IOC_GPIO_15")
	)
	(segment
		(start 177.301906 -72.494394)
		(end 177.370232 -72.426068)
		(width 0.127)
		(layer "F.Cu")
		(net "IOC_GPIO_15")
	)
	(segment
		(start 179.814982 -68.699888)
		(end 181.200044 -68.699888)
		(width 0.127)
		(layer "F.Cu")
		(net "IOC_GPIO_15")
	)
	(via
		(at 177.301906 -72.606916)
		(size 0.508)
		(drill 0.254)
		(layers "F.Cu" "B.Cu")
		(net "IOC_GPIO_15")
	)
	(segment
		(start 177.301906 -72.234806)
		(end 177.301906 -72.606916)
		(width 0.127)
		(layer "B.Cu")
		(net "IOC_GPIO_15")
	)
	(segment
		(start 176.0728 -71.0057)
		(end 177.301906 -72.234806)
		(width 0.127)
		(layer "B.Cu")
		(net "IOC_GPIO_15")
	)
	(segment
		(start 183.912002 -77.80147)
		(end 183.971184 -77.742288)
		(width 0.127)
		(layer "F.Cu")
		(net "IOC_GPIO_14")
	)
	(segment
		(start 183.971184 -77.742288)
		(end 183.971184 -76.27112)
		(width 0.127)
		(layer "F.Cu")
		(net "IOC_GPIO_14")
	)
	(segment
		(start 183.971184 -76.27112)
		(end 183.60009 -75.900026)
		(width 0.127)
		(layer "F.Cu")
		(net "IOC_GPIO_14")
	)
	(via
		(at 183.912002 -77.80147)
		(size 0.508)
		(drill 0.254)
		(layers "F.Cu" "B.Cu")
		(net "IOC_GPIO_14")
	)
	(segment
		(start 183.912002 -77.80147)
		(end 184.53227 -77.80147)
		(width 0.127)
		(layer "B.Cu")
		(net "IOC_GPIO_14")
	)
	(segment
		(start 185.1152 -79.0194)
		(end 184.6072 -79.5274)
		(width 0.127)
		(layer "B.Cu")
		(net "IOC_GPIO_14")
	)
	(segment
		(start 184.6072 -79.5274)
		(end 184.6072 -79.530702)
		(width 0.127)
		(layer "B.Cu")
		(net "IOC_GPIO_14")
	)
	(segment
		(start 185.1152 -78.3844)
		(end 185.1152 -79.0194)
		(width 0.127)
		(layer "B.Cu")
		(net "IOC_GPIO_14")
	)
	(segment
		(start 184.53227 -77.80147)
		(end 185.1152 -78.3844)
		(width 0.127)
		(layer "B.Cu")
		(net "IOC_GPIO_14")
	)
	(segment
		(start 184.55132 -81.64068)
		(end 184.55132 -79.658464)
		(width 0.127)
		(layer "F.Cu")
		(net "IOC_GPIO_13")
	)
	(segment
		(start 185.542936 -78.666848)
		(end 185.542936 -76.242926)
		(width 0.127)
		(layer "F.Cu")
		(net "IOC_GPIO_13")
	)
	(segment
		(start 184.404 -81.788)
		(end 184.55132 -81.64068)
		(width 0.127)
		(layer "F.Cu")
		(net "IOC_GPIO_13")
	)
	(segment
		(start 184.55132 -79.658464)
		(end 185.542936 -78.666848)
		(width 0.127)
		(layer "F.Cu")
		(net "IOC_GPIO_13")
	)
	(segment
		(start 185.542936 -76.242926)
		(end 185.200036 -75.900026)
		(width 0.127)
		(layer "F.Cu")
		(net "IOC_GPIO_13")
	)
	(segment
		(start 182.36819 -76.268326)
		(end 181.99989 -75.900026)
		(width 0.127)
		(layer "F.Cu")
		(net "IOC_GPIO_12")
	)
	(segment
		(start 182.36819 -77.096874)
		(end 182.36819 -76.268326)
		(width 0.127)
		(layer "F.Cu")
		(net "IOC_GPIO_12")
	)
	(segment
		(start 181.188106 -77.966316)
		(end 181.498748 -77.966316)
		(width 0.127)
		(layer "F.Cu")
		(net "IOC_GPIO_12")
	)
	(segment
		(start 181.498748 -77.966316)
		(end 182.36819 -77.096874)
		(width 0.127)
		(layer "F.Cu")
		(net "IOC_GPIO_12")
	)
	(via
		(at 181.188106 -77.966316)
		(size 0.508)
		(drill 0.254)
		(layers "F.Cu" "B.Cu")
		(net "IOC_GPIO_12")
	)
	(segment
		(start 181.188106 -77.966316)
		(end 180.820822 -78.3336)
		(width 0.127)
		(layer "B.Cu")
		(net "IOC_GPIO_12")
	)
	(segment
		(start 180.820822 -78.3336)
		(end 180.213 -78.3336)
		(width 0.127)
		(layer "B.Cu")
		(net "IOC_GPIO_12")
	)
	(segment
		(start 179.009802 -76.863956)
		(end 177.066956 -76.863956)
		(width 0.127)
		(layer "F.Cu")
		(net "IOC_GPIO_11")
	)
	(segment
		(start 180.890672 -75.099926)
		(end 179.138072 -76.852526)
		(width 0.127)
		(layer "F.Cu")
		(net "IOC_GPIO_11")
	)
	(segment
		(start 179.138072 -76.852526)
		(end 179.021232 -76.852526)
		(width 0.127)
		(layer "F.Cu")
		(net "IOC_GPIO_11")
	)
	(segment
		(start 179.021232 -76.852526)
		(end 179.009802 -76.863956)
		(width 0.127)
		(layer "F.Cu")
		(net "IOC_GPIO_11")
	)
	(segment
		(start 181.200044 -75.099926)
		(end 180.890672 -75.099926)
		(width 0.127)
		(layer "F.Cu")
		(net "IOC_GPIO_11")
	)
	(segment
		(start 177.066956 -76.863956)
		(end 176.8348 -76.6318)
		(width 0.127)
		(layer "F.Cu")
		(net "IOC_GPIO_11")
	)
	(segment
		(start 182.406036 -75.49388)
		(end 182.79999 -75.099926)
		(width 0.127)
		(layer "F.Cu")
		(net "IOC_GPIO_10")
	)
	(segment
		(start 181.606698 -75.772264)
		(end 181.885082 -75.49388)
		(width 0.127)
		(layer "F.Cu")
		(net "IOC_GPIO_10")
	)
	(segment
		(start 181.606698 -76.465684)
		(end 181.606698 -75.772264)
		(width 0.127)
		(layer "F.Cu")
		(net "IOC_GPIO_10")
	)
	(segment
		(start 180.796946 -77.275436)
		(end 181.606698 -76.465684)
		(width 0.127)
		(layer "F.Cu")
		(net "IOC_GPIO_10")
	)
	(segment
		(start 181.885082 -75.49388)
		(end 182.406036 -75.49388)
		(width 0.127)
		(layer "F.Cu")
		(net "IOC_GPIO_10")
	)
	(via
		(at 180.796946 -77.275436)
		(size 0.508)
		(drill 0.254)
		(layers "F.Cu" "B.Cu")
		(net "IOC_GPIO_10")
	)
	(segment
		(start 181.6608 -76.2)
		(end 180.796946 -77.063854)
		(width 0.127)
		(layer "B.Cu")
		(net "IOC_GPIO_10")
	)
	(segment
		(start 180.796946 -77.063854)
		(end 180.796946 -77.275436)
		(width 0.127)
		(layer "B.Cu")
		(net "IOC_GPIO_10")
	)
	(segment
		(start 184.742836 -76.242926)
		(end 184.399936 -75.900026)
		(width 0.127)
		(layer "F.Cu")
		(net "IOC_GPIO_1")
	)
	(segment
		(start 184.63133 -78.208124)
		(end 184.742836 -78.096618)
		(width 0.127)
		(layer "F.Cu")
		(net "IOC_GPIO_1")
	)
	(segment
		(start 184.63133 -78.515718)
		(end 184.63133 -78.208124)
		(width 0.127)
		(layer "F.Cu")
		(net "IOC_GPIO_1")
	)
	(segment
		(start 184.742836 -78.096618)
		(end 184.742836 -76.242926)
		(width 0.127)
		(layer "F.Cu")
		(net "IOC_GPIO_1")
	)
	(via
		(at 184.63133 -78.515718)
		(size 0.508)
		(drill 0.254)
		(layers "F.Cu" "B.Cu")
		(net "IOC_GPIO_1")
	)
	(segment
		(start 183.845708 -79.30134)
		(end 184.63133 -78.515718)
		(width 0.127)
		(layer "B.Cu")
		(net "IOC_GPIO_1")
	)
	(segment
		(start 183.01462 -79.30134)
		(end 183.845708 -79.30134)
		(width 0.127)
		(layer "B.Cu")
		(net "IOC_GPIO_1")
	)
	(segment
		(start 179.526184 -75.140566)
		(end 179.68976 -75.140566)
		(width 0.127)
		(layer "F.Cu")
		(net "IOC_GPIO_0")
	)
	(segment
		(start 179.68976 -75.140566)
		(end 180.967126 -73.8632)
		(width 0.127)
		(layer "F.Cu")
		(net "IOC_GPIO_0")
	)
	(segment
		(start 180.967126 -73.8632)
		(end 181.63667 -73.8632)
		(width 0.127)
		(layer "F.Cu")
		(net "IOC_GPIO_0")
	)
	(segment
		(start 181.63667 -73.8632)
		(end 181.99989 -73.49998)
		(width 0.127)
		(layer "F.Cu")
		(net "IOC_GPIO_0")
	)
	(via
		(at 179.526184 -75.140566)
		(size 0.508)
		(drill 0.254)
		(layers "F.Cu" "B.Cu")
		(net "IOC_GPIO_0")
	)
	(segment
		(start 179.526184 -75.335384)
		(end 179.526184 -75.140566)
		(width 0.127)
		(layer "B.Cu")
		(net "IOC_GPIO_0")
	)
	(segment
		(start 180.2384 -76.0476)
		(end 179.526184 -75.335384)
		(width 0.127)
		(layer "B.Cu")
		(net "IOC_GPIO_0")
	)
	(segment
		(start 210.8962 -100.0252)
		(end 209.031332 -100.0252)
		(width 0.127)
		(layer "F.Cu")
		(net "IOC_EEPROM_WP")
	)
	(segment
		(start 207.818482 -100.0252)
		(end 209.031332 -100.0252)
		(width 0.127)
		(layer "F.Cu")
		(net "IOC_EEPROM_WP")
	)
	(segment
		(start 207.777588 -99.984306)
		(end 207.818482 -100.0252)
		(width 0.127)
		(layer "F.Cu")
		(net "IOC_EEPROM_WP")
	)
	(via
		(at 209.031332 -100.0252)
		(size 0.6604)
		(drill 0.3302)
		(layers "F.Cu" "B.Cu")
		(net "IOC_EEPROM_WP")
	)
	(segment
		(start 209.758534 -102.5652)
		(end 209.107024 -103.21671)
		(width 0.127)
		(layer "F.Cu")
		(net "IOC_EEPROM_SDA")
	)
	(segment
		(start 207.946752 -103.30307)
		(end 209.020664 -103.30307)
		(width 0.127)
		(layer "F.Cu")
		(net "IOC_EEPROM_SDA")
	)
	(segment
		(start 210.8962 -102.5652)
		(end 209.758534 -102.5652)
		(width 0.127)
		(layer "F.Cu")
		(net "IOC_EEPROM_SDA")
	)
	(segment
		(start 209.020664 -103.30307)
		(end 209.107024 -103.21671)
		(width 0.127)
		(layer "F.Cu")
		(net "IOC_EEPROM_SDA")
	)
	(via
		(at 209.107024 -103.21671)
		(size 0.6604)
		(drill 0.3302)
		(layers "F.Cu" "B.Cu")
		(net "IOC_EEPROM_SDA")
	)
	(segment
		(start 209.0166 -101.4476)
		(end 208.623662 -101.4476)
		(width 0.127)
		(layer "F.Cu")
		(net "IOC_EEPROM_SCL")
	)
	(segment
		(start 209.478118 -101.4476)
		(end 209.0166 -101.4476)
		(width 0.127)
		(layer "F.Cu")
		(net "IOC_EEPROM_SCL")
	)
	(segment
		(start 208.623662 -101.4476)
		(end 208.513934 -101.337872)
		(width 0.127)
		(layer "F.Cu")
		(net "IOC_EEPROM_SCL")
	)
	(segment
		(start 210.8962 -101.2952)
		(end 209.630518 -101.2952)
		(width 0.127)
		(layer "F.Cu")
		(net "IOC_EEPROM_SCL")
	)
	(segment
		(start 208.513934 -101.337872)
		(end 207.852518 -101.337872)
		(width 0.127)
		(layer "F.Cu")
		(net "IOC_EEPROM_SCL")
	)
	(segment
		(start 209.630518 -101.2952)
		(end 209.478118 -101.4476)
		(width 0.127)
		(layer "F.Cu")
		(net "IOC_EEPROM_SCL")
	)
	(via
		(at 209.0166 -101.4476)
		(size 0.6604)
		(drill 0.3302)
		(layers "F.Cu" "B.Cu")
		(net "IOC_EEPROM_SCL")
	)
	(segment
		(start 218.694 -102.4509)
		(end 217.678 -102.4509)
		(width 0.127)
		(layer "F.Cu")
		(net "IOC_EEPROM_A2")
	)
	(segment
		(start 217.678 -102.4509)
		(end 217.678 -101.5238)
		(width 0.127)
		(layer "F.Cu")
		(net "IOC_EEPROM_A2")
	)
	(segment
		(start 217.4494 -101.2952)
		(end 217.541602 -101.387402)
		(width 0.127)
		(layer "F.Cu")
		(net "IOC_EEPROM_A2")
	)
	(segment
		(start 215.9762 -101.2952)
		(end 217.4494 -101.2952)
		(width 0.127)
		(layer "F.Cu")
		(net "IOC_EEPROM_A2")
	)
	(segment
		(start 217.678 -101.5238)
		(end 217.541602 -101.387402)
		(width 0.127)
		(layer "F.Cu")
		(net "IOC_EEPROM_A2")
	)
	(via
		(at 217.541602 -101.387402)
		(size 0.6604)
		(drill 0.3302)
		(layers "F.Cu" "B.Cu")
		(net "IOC_EEPROM_A2")
	)
	(segment
		(start 217.506804 -100.0252)
		(end 217.846656 -100.365052)
		(width 0.127)
		(layer "F.Cu")
		(net "IOC_EEPROM_A1")
	)
	(segment
		(start 215.9762 -100.0252)
		(end 217.506804 -100.0252)
		(width 0.127)
		(layer "F.Cu")
		(net "IOC_EEPROM_A1")
	)
	(segment
		(start 219.837 -102.355396)
		(end 217.846656 -100.365052)
		(width 0.127)
		(layer "F.Cu")
		(net "IOC_EEPROM_A1")
	)
	(segment
		(start 219.837 -102.4636)
		(end 219.837 -102.355396)
		(width 0.127)
		(layer "F.Cu")
		(net "IOC_EEPROM_A1")
	)
	(via
		(at 217.846656 -100.365052)
		(size 0.6604)
		(drill 0.3302)
		(layers "F.Cu" "B.Cu")
		(net "IOC_EEPROM_A1")
	)
	(segment
		(start 216.3318 -97.2566)
		(end 217.318844 -97.2566)
		(width 0.127)
		(layer "F.Cu")
		(net "IOC_EEPROM_A0")
	)
	(segment
		(start 217.318844 -97.2566)
		(end 217.822526 -97.760282)
		(width 0.127)
		(layer "F.Cu")
		(net "IOC_EEPROM_A0")
	)
	(segment
		(start 215.9762 -97.6122)
		(end 216.3318 -97.2566)
		(width 0.127)
		(layer "F.Cu")
		(net "IOC_EEPROM_A0")
	)
	(segment
		(start 215.9762 -98.7552)
		(end 215.9762 -97.6122)
		(width 0.127)
		(layer "F.Cu")
		(net "IOC_EEPROM_A0")
	)
	(via
		(at 216.3318 -97.2566)
		(size 0.6604)
		(drill 0.3302)
		(layers "F.Cu" "B.Cu")
		(net "IOC_EEPROM_A0")
	)
	(segment
		(start 182.406798 -65.106804)
		(end 182.79999 -65.499996)
		(width 0.127)
		(layer "F.Cu")
		(net "IOC_CLK_SEL1")
	)
	(segment
		(start 182.402734 -65.106804)
		(end 182.406798 -65.106804)
		(width 0.127)
		(layer "F.Cu")
		(net "IOC_CLK_SEL1")
	)
	(via
		(at 182.402734 -65.106804)
		(size 0.508)
		(drill 0.254)
		(layers "F.Cu" "B.Cu")
		(net "IOC_CLK_SEL1")
	)
	(via
		(at 181.80685 -66.532506)
		(size 0.6096)
		(drill 0.3048)
		(layers "F.Cu" "B.Cu")
		(net "IOC_CLK_SEL1")
	)
	(segment
		(start 181.79161 -66.547746)
		(end 180.619908 -66.547746)
		(width 0.127)
		(layer "B.Cu")
		(net "IOC_CLK_SEL1")
	)
	(segment
		(start 181.80685 -66.532506)
		(end 181.80685 -66.37274)
		(width 0.127)
		(layer "B.Cu")
		(net "IOC_CLK_SEL1")
	)
	(segment
		(start 181.80685 -66.532506)
		(end 181.79161 -66.547746)
		(width 0.127)
		(layer "B.Cu")
		(net "IOC_CLK_SEL1")
	)
	(segment
		(start 181.373018 -65.106804)
		(end 180.956966 -65.522856)
		(width 0.127)
		(layer "B.Cu")
		(net "IOC_CLK_SEL1")
	)
	(segment
		(start 181.80685 -66.37274)
		(end 180.956966 -65.522856)
		(width 0.127)
		(layer "B.Cu")
		(net "IOC_CLK_SEL1")
	)
	(segment
		(start 182.402734 -65.106804)
		(end 181.373018 -65.106804)
		(width 0.127)
		(layer "B.Cu")
		(net "IOC_CLK_SEL1")
	)
	(segment
		(start 174.013368 -62.126368)
		(end 175.26 -63.373)
		(width 0.127)
		(layer "F.Cu")
		(net "IOC_CLK_SEL0")
	)
	(segment
		(start 178.3334 -64.135)
		(end 177.2793 -64.135)
		(width 0.127)
		(layer "F.Cu")
		(net "IOC_CLK_SEL0")
	)
	(segment
		(start 181.99989 -63.90005)
		(end 181.589934 -64.310006)
		(width 0.127)
		(layer "F.Cu")
		(net "IOC_CLK_SEL0")
	)
	(segment
		(start 177.2793 -64.135)
		(end 176.4919 -63.3476)
		(width 0.127)
		(layer "F.Cu")
		(net "IOC_CLK_SEL0")
	)
	(segment
		(start 178.460146 -64.008254)
		(end 178.3334 -64.135)
		(width 0.127)
		(layer "F.Cu")
		(net "IOC_CLK_SEL0")
	)
	(segment
		(start 180.405024 -64.310006)
		(end 180.103272 -64.008254)
		(width 0.127)
		(layer "F.Cu")
		(net "IOC_CLK_SEL0")
	)
	(segment
		(start 174.013368 -62.114938)
		(end 174.013368 -62.126368)
		(width 0.127)
		(layer "F.Cu")
		(net "IOC_CLK_SEL0")
	)
	(segment
		(start 176.4919 -63.3476)
		(end 176.4665 -63.373)
		(width 0.127)
		(layer "F.Cu")
		(net "IOC_CLK_SEL0")
	)
	(segment
		(start 181.589934 -64.310006)
		(end 180.405024 -64.310006)
		(width 0.127)
		(layer "F.Cu")
		(net "IOC_CLK_SEL0")
	)
	(segment
		(start 180.103272 -64.008254)
		(end 178.460146 -64.008254)
		(width 0.127)
		(layer "F.Cu")
		(net "IOC_CLK_SEL0")
	)
	(segment
		(start 176.4665 -63.373)
		(end 175.26 -63.373)
		(width 0.127)
		(layer "F.Cu")
		(net "IOC_CLK_SEL0")
	)
	(via
		(at 175.26 -63.373)
		(size 0.6604)
		(drill 0.3302)
		(layers "F.Cu" "B.Cu")
		(net "IOC_CLK_SEL0")
	)
	(segment
		(start 200.399904 -62.29985)
		(end 200.000108 -61.900054)
		(width 0.0889)
		(layer "F.Cu")
		(net "ICE_SEL")
	)
	(via
		(at 200.000108 -61.900054)
		(size 0.508)
		(drill 0.254)
		(layers "F.Cu" "B.Cu")
		(net "ICE_SEL")
	)
	(segment
		(start 202.832208 -63.911988)
		(end 201.84618 -62.92596)
		(width 0.127)
		(layer "B.Cu")
		(net "ICE_SEL")
	)
	(segment
		(start 201.84618 -62.92596)
		(end 200.94956 -62.92596)
		(width 0.127)
		(layer "B.Cu")
		(net "ICE_SEL")
	)
	(segment
		(start 200.94956 -62.849506)
		(end 200.000108 -61.900054)
		(width 0.127)
		(layer "B.Cu")
		(net "ICE_SEL")
	)
	(segment
		(start 206.213964 -62.32398)
		(end 205.215744 -63.3222)
		(width 0.127)
		(layer "B.Cu")
		(net "ICE_SEL")
	)
	(segment
		(start 200.94956 -62.92596)
		(end 200.94956 -62.849506)
		(width 0.127)
		(layer "B.Cu")
		(net "ICE_SEL")
	)
	(segment
		(start 208.30032 -62.32398)
		(end 206.213964 -62.32398)
		(width 0.127)
		(layer "B.Cu")
		(net "ICE_SEL")
	)
	(segment
		(start 204.009752 -63.3222)
		(end 203.419964 -63.911988)
		(width 0.127)
		(layer "B.Cu")
		(net "ICE_SEL")
	)
	(segment
		(start 205.215744 -63.3222)
		(end 204.009752 -63.3222)
		(width 0.127)
		(layer "B.Cu")
		(net "ICE_SEL")
	)
	(segment
		(start 203.419964 -63.911988)
		(end 202.832208 -63.911988)
		(width 0.127)
		(layer "B.Cu")
		(net "ICE_SEL")
	)
	(segment
		(start 208.5975 -62.0268)
		(end 208.30032 -62.32398)
		(width 0.127)
		(layer "B.Cu")
		(net "ICE_SEL")
	)
	(segment
		(start 201.31913 -51.938428)
		(end 202.482958 -50.7746)
		(width 0.127)
		(layer "F.Cu")
		(net "ICE1_TRST#")
	)
	(segment
		(start 200.399904 -54.908196)
		(end 200.813924 -54.494176)
		(width 0.127)
		(layer "F.Cu")
		(net "ICE1_TRST#")
	)
	(segment
		(start 204.6224 -49.7078)
		(end 204.3684 -49.9618)
		(width 0.127)
		(layer "F.Cu")
		(net "ICE1_TRST#")
	)
	(segment
		(start 202.482958 -50.7746)
		(end 203.18603 -50.7746)
		(width 0.127)
		(layer "F.Cu")
		(net "ICE1_TRST#")
	)
	(segment
		(start 200.813924 -54.494176)
		(end 200.813924 -53.146706)
		(width 0.127)
		(layer "F.Cu")
		(net "ICE1_TRST#")
	)
	(segment
		(start 203.18603 -50.7746)
		(end 203.99883 -49.9618)
		(width 0.127)
		(layer "F.Cu")
		(net "ICE1_TRST#")
	)
	(segment
		(start 201.31913 -52.6415)
		(end 201.31913 -51.938428)
		(width 0.127)
		(layer "F.Cu")
		(net "ICE1_TRST#")
	)
	(segment
		(start 203.99883 -49.9618)
		(end 204.3684 -49.9618)
		(width 0.127)
		(layer "F.Cu")
		(net "ICE1_TRST#")
	)
	(segment
		(start 200.813924 -53.146706)
		(end 201.31913 -52.6415)
		(width 0.127)
		(layer "F.Cu")
		(net "ICE1_TRST#")
	)
	(segment
		(start 204.6224 -48.7299)
		(end 204.6224 -49.7078)
		(width 0.127)
		(layer "F.Cu")
		(net "ICE1_TRST#")
	)
	(segment
		(start 200.399904 -55.099966)
		(end 200.399904 -54.908196)
		(width 0.127)
		(layer "F.Cu")
		(net "ICE1_TRST#")
	)
	(segment
		(start 200.399904 -52.431442)
		(end 200.399904 -53.50002)
		(width 0.127)
		(layer "F.Cu")
		(net "ICE1_TMS")
	)
	(segment
		(start 200.527158 -52.304442)
		(end 200.526904 -52.304442)
		(width 0.127)
		(layer "F.Cu")
		(net "ICE1_TMS")
	)
	(segment
		(start 200.526904 -52.304442)
		(end 200.399904 -52.431442)
		(width 0.127)
		(layer "F.Cu")
		(net "ICE1_TMS")
	)
	(segment
		(start 203.3524 -49.4792)
		(end 202.8698 -49.9618)
		(width 0.127)
		(layer "F.Cu")
		(net "ICE1_TMS")
	)
	(segment
		(start 203.3524 -48.7299)
		(end 203.3524 -49.4792)
		(width 0.127)
		(layer "F.Cu")
		(net "ICE1_TMS")
	)
	(segment
		(start 202.8698 -49.9618)
		(end 200.527158 -52.304442)
		(width 0.127)
		(layer "F.Cu")
		(net "ICE1_TMS")
	)
	(segment
		(start 195.6562 -51.481228)
		(end 196.990208 -52.815236)
		(width 0.127)
		(layer "F.Cu")
		(net "ICE1_TDO")
	)
	(segment
		(start 195.6562 -49.9618)
		(end 195.6562 -51.481228)
		(width 0.127)
		(layer "F.Cu")
		(net "ICE1_TDO")
	)
	(segment
		(start 196.990208 -52.815236)
		(end 196.990208 -53.290216)
		(width 0.127)
		(layer "F.Cu")
		(net "ICE1_TDO")
	)
	(segment
		(start 196.990208 -53.290216)
		(end 197.200012 -53.50002)
		(width 0.127)
		(layer "F.Cu")
		(net "ICE1_TDO")
	)
	(segment
		(start 200.399904 -61.500004)
		(end 200.000108 -61.100208)
		(width 0.127)
		(layer "F.Cu")
		(net "ICE1_TDI")
	)
	(via
		(at 207.4926 -58.8518)
		(size 0.508)
		(drill 0.254)
		(layers "F.Cu" "B.Cu")
		(net "ICE1_TDI")
	)
	(via
		(at 200.000108 -61.100208)
		(size 0.508)
		(drill 0.254)
		(layers "F.Cu" "B.Cu")
		(net "ICE1_TDI")
	)
	(segment
		(start 210.5152 -58.69432)
		(end 210.510374 -58.689494)
		(width 0.127)
		(layer "B.Cu")
		(net "ICE1_TDI")
	)
	(segment
		(start 209.495898 -58.689494)
		(end 209.333592 -58.8518)
		(width 0.127)
		(layer "B.Cu")
		(net "ICE1_TDI")
	)
	(segment
		(start 210.510374 -58.689494)
		(end 209.495898 -58.689494)
		(width 0.127)
		(layer "B.Cu")
		(net "ICE1_TDI")
	)
	(segment
		(start 209.333592 -58.8518)
		(end 207.4926 -58.8518)
		(width 0.127)
		(layer "B.Cu")
		(net "ICE1_TDI")
	)
	(segment
		(start 210.5152 -59.9059)
		(end 210.5152 -58.69432)
		(width 0.127)
		(layer "B.Cu")
		(net "ICE1_TDI")
	)
	(segment
		(start 201.22134 -62.321186)
		(end 201.965814 -62.321186)
		(width 0.127)
		(layer "In5.Cu")
		(net "ICE1_TDI")
	)
	(segment
		(start 202.592432 -60.660534)
		(end 204.401166 -58.8518)
		(width 0.127)
		(layer "In5.Cu")
		(net "ICE1_TDI")
	)
	(segment
		(start 204.401166 -58.8518)
		(end 207.4926 -58.8518)
		(width 0.127)
		(layer "In5.Cu")
		(net "ICE1_TDI")
	)
	(segment
		(start 200.000108 -61.100208)
		(end 200.000362 -61.100208)
		(width 0.127)
		(layer "In5.Cu")
		(net "ICE1_TDI")
	)
	(segment
		(start 201.965814 -62.321186)
		(end 202.592432 -61.694568)
		(width 0.127)
		(layer "In5.Cu")
		(net "ICE1_TDI")
	)
	(segment
		(start 200.000362 -61.100208)
		(end 201.22134 -62.321186)
		(width 0.127)
		(layer "In5.Cu")
		(net "ICE1_TDI")
	)
	(segment
		(start 202.592432 -61.694568)
		(end 202.592432 -60.660534)
		(width 0.127)
		(layer "In5.Cu")
		(net "ICE1_TDI")
	)
	(segment
		(start 201.4728 -49.9618)
		(end 199.97674 -51.45786)
		(width 0.127)
		(layer "F.Cu")
		(net "ICE1_TCK")
	)
	(segment
		(start 199.97674 -51.45786)
		(end 199.97674 -53.96611)
		(width 0.127)
		(layer "F.Cu")
		(net "ICE1_TCK")
	)
	(segment
		(start 201.4728 -49.3395)
		(end 202.0824 -48.7299)
		(width 0.127)
		(layer "F.Cu")
		(net "ICE1_TCK")
	)
	(segment
		(start 199.97674 -53.96611)
		(end 199.642984 -54.299866)
		(width 0.127)
		(layer "F.Cu")
		(net "ICE1_TCK")
	)
	(segment
		(start 199.642984 -54.299866)
		(end 199.600058 -54.299866)
		(width 0.127)
		(layer "F.Cu")
		(net "ICE1_TCK")
	)
	(segment
		(start 201.4728 -49.9618)
		(end 201.4728 -49.3395)
		(width 0.127)
		(layer "F.Cu")
		(net "ICE1_TCK")
	)
	(segment
		(start 198.961248 -53.33873)
		(end 198.799958 -53.50002)
		(width 0.127)
		(layer "F.Cu")
		(net "ICE0_TRST#")
	)
	(segment
		(start 198.961248 -50.193448)
		(end 198.961248 -53.33873)
		(width 0.127)
		(layer "F.Cu")
		(net "ICE0_TRST#")
	)
	(segment
		(start 198.755 -49.5173)
		(end 199.5424 -48.7299)
		(width 0.127)
		(layer "F.Cu")
		(net "ICE0_TRST#")
	)
	(segment
		(start 198.755 -49.9872)
		(end 198.961248 -50.193448)
		(width 0.127)
		(layer "F.Cu")
		(net "ICE0_TRST#")
	)
	(segment
		(start 198.755 -49.9872)
		(end 198.755 -49.5173)
		(width 0.127)
		(layer "F.Cu")
		(net "ICE0_TRST#")
	)
	(segment
		(start 205.867 -49.9618)
		(end 205.867 -48.7553)
		(width 0.127)
		(layer "F.Cu")
		(net "ICE0_TMS")
	)
	(segment
		(start 204.8256 -51.0032)
		(end 202.5777 -51.0032)
		(width 0.127)
		(layer "F.Cu")
		(net "ICE0_TMS")
	)
	(segment
		(start 199.947784 -55.447692)
		(end 199.600058 -55.099966)
		(width 0.127)
		(layer "F.Cu")
		(net "ICE0_TMS")
	)
	(segment
		(start 200.584308 -55.447692)
		(end 199.947784 -55.447692)
		(width 0.127)
		(layer "F.Cu")
		(net "ICE0_TMS")
	)
	(segment
		(start 205.867 -49.9618)
		(end 204.8256 -51.0032)
		(width 0.127)
		(layer "F.Cu")
		(net "ICE0_TMS")
	)
	(segment
		(start 200.857104 -54.957726)
		(end 200.857104 -55.174896)
		(width 0.127)
		(layer "F.Cu")
		(net "ICE0_TMS")
	)
	(segment
		(start 201.057764 -54.757066)
		(end 200.857104 -54.957726)
		(width 0.127)
		(layer "F.Cu")
		(net "ICE0_TMS")
	)
	(segment
		(start 201.274934 -54.757066)
		(end 201.057764 -54.757066)
		(width 0.127)
		(layer "F.Cu")
		(net "ICE0_TMS")
	)
	(segment
		(start 202.5777 -51.0032)
		(end 201.54773 -52.03317)
		(width 0.127)
		(layer "F.Cu")
		(net "ICE0_TMS")
	)
	(segment
		(start 201.54773 -52.03317)
		(end 201.54773 -54.48427)
		(width 0.127)
		(layer "F.Cu")
		(net "ICE0_TMS")
	)
	(segment
		(start 201.54773 -54.48427)
		(end 201.274934 -54.757066)
		(width 0.127)
		(layer "F.Cu")
		(net "ICE0_TMS")
	)
	(segment
		(start 200.857104 -55.174896)
		(end 200.584308 -55.447692)
		(width 0.127)
		(layer "F.Cu")
		(net "ICE0_TMS")
	)
	(segment
		(start 205.867 -48.7553)
		(end 205.8924 -48.7299)
		(width 0.127)
		(layer "F.Cu")
		(net "ICE0_TMS")
	)
	(segment
		(start 197.975982 -48.658018)
		(end 197.975982 -52.971954)
		(width 0.127)
		(layer "F.Cu")
		(net "ICE0_TDO")
	)
	(segment
		(start 197.975982 -52.971954)
		(end 198.41972 -53.415692)
		(width 0.127)
		(layer "F.Cu")
		(net "ICE0_TDO")
	)
	(segment
		(start 198.41972 -53.415692)
		(end 198.41972 -54.719728)
		(width 0.127)
		(layer "F.Cu")
		(net "ICE0_TDO")
	)
	(segment
		(start 198.247 -48.387)
		(end 197.975982 -48.658018)
		(width 0.127)
		(layer "F.Cu")
		(net "ICE0_TDO")
	)
	(segment
		(start 198.41972 -54.719728)
		(end 198.799958 -55.099966)
		(width 0.127)
		(layer "F.Cu")
		(net "ICE0_TDO")
	)
	(segment
		(start 199.2376 -50.8508)
		(end 199.2376 -53.862224)
		(width 0.127)
		(layer "F.Cu")
		(net "ICE0_TDI")
	)
	(segment
		(start 200.1266 -49.9618)
		(end 200.1266 -49.4157)
		(width 0.127)
		(layer "F.Cu")
		(net "ICE0_TDI")
	)
	(segment
		(start 200.1266 -49.9618)
		(end 199.2376 -50.8508)
		(width 0.127)
		(layer "F.Cu")
		(net "ICE0_TDI")
	)
	(segment
		(start 200.1266 -49.4157)
		(end 200.8124 -48.7299)
		(width 0.127)
		(layer "F.Cu")
		(net "ICE0_TDI")
	)
	(segment
		(start 199.2376 -53.862224)
		(end 198.799958 -54.299866)
		(width 0.127)
		(layer "F.Cu")
		(net "ICE0_TDI")
	)
	(segment
		(start 197.0024 -50.484278)
		(end 197.594982 -51.07686)
		(width 0.127)
		(layer "F.Cu")
		(net "ICE0_TCK")
	)
	(segment
		(start 197.0024 -48.7299)
		(end 196.977 -48.7045)
		(width 0.127)
		(layer "F.Cu")
		(net "ICE0_TCK")
	)
	(segment
		(start 197.594982 -53.00853)
		(end 197.999858 -53.413406)
		(width 0.127)
		(layer "F.Cu")
		(net "ICE0_TCK")
	)
	(segment
		(start 197.999858 -53.413406)
		(end 197.999858 -53.50002)
		(width 0.127)
		(layer "F.Cu")
		(net "ICE0_TCK")
	)
	(segment
		(start 197.594982 -51.07686)
		(end 197.594982 -53.00853)
		(width 0.127)
		(layer "F.Cu")
		(net "ICE0_TCK")
	)
	(segment
		(start 197.0024 -49.9618)
		(end 197.0024 -50.484278)
		(width 0.127)
		(layer "F.Cu")
		(net "ICE0_TCK")
	)
	(segment
		(start 197.0024 -49.9618)
		(end 197.0024 -48.7299)
		(width 0.127)
		(layer "F.Cu")
		(net "ICE0_TCK")
	)
	(segment
		(start 193.4464 -52.6542)
		(end 193.821558 -53.029358)
		(width 0.3556)
		(layer "F.Cu")
		(net "HM40ADC_VDDA")
	)
	(segment
		(start 193.821558 -53.029358)
		(end 193.821558 -53.321712)
		(width 0.3556)
		(layer "F.Cu")
		(net "HM40ADC_VDDA")
	)
	(segment
		(start 193.821558 -53.321712)
		(end 193.999866 -53.50002)
		(width 0.3556)
		(layer "F.Cu")
		(net "HM40ADC_VDDA")
	)
	(via
		(at 195.2498 -45.9486)
		(size 0.6096)
		(drill 0.3048)
		(layers "F.Cu" "B.Cu")
		(net "HM40ADC_VDDA")
	)
	(via
		(at 193.4464 -52.6542)
		(size 0.508)
		(drill 0.254)
		(layers "F.Cu" "B.Cu")
		(net "HM40ADC_VDDA")
	)
	(segment
		(start 194.40017 -64.3001)
		(end 194.799966 -64.699896)
		(width 0.254)
		(layer "F.Cu")
		(net "GND")
	)
	(segment
		(start 52.099972 -153.399998)
		(end 51.71567 -153.7843)
		(width 0.3556)
		(layer "F.Cu")
		(net "GND")
	)
	(segment
		(start 31.1531 -159.8549)
		(end 30.988 -159.6898)
		(width 0.254)
		(layer "F.Cu")
		(net "GND")
	)
	(segment
		(start 77.020166 -75.350116)
		(end 77.283818 -75.613768)
		(width 0.508)
		(layer "F.Cu")
		(net "GND")
	)
	(segment
		(start 74.4728 -148.7805)
		(end 74.3839 -148.8694)
		(width 0.508)
		(layer "F.Cu")
		(net "GND")
	)
	(segment
		(start 197.200012 -70.299834)
		(end 197.20052 -70.299834)
		(width 0.254)
		(layer "F.Cu")
		(net "GND")
	)
	(segment
		(start 76.740258 -78.550008)
		(end 77.283818 -79.093568)
		(width 0.508)
		(layer "F.Cu")
		(net "GND")
	)
	(segment
		(start 75.475084 -88.149938)
		(end 77.018388 -88.149938)
		(width 0.508)
		(layer "F.Cu")
		(net "GND")
	)
	(segment
		(start 201.200004 -55.099966)
		(end 201.200004 -55.900066)
		(width 0.254)
		(layer "F.Cu")
		(net "GND")
	)
	(segment
		(start 91.948 -31.496)
		(end 91.05392 -32.39008)
		(width 0.508)
		(layer "F.Cu")
		(net "GND")
	)
	(segment
		(start 192.39992 -62.29985)
		(end 192.800224 -62.700154)
		(width 0.254)
		(layer "F.Cu")
		(net "GND")
	)
	(segment
		(start 73.8505 -137.922)
		(end 72.770492 -137.922)
		(width 0.508)
		(layer "F.Cu")
		(net "GND")
	)
	(segment
		(start 48.09998 -144.599914)
		(end 47.69993 -144.999964)
		(width 0.3556)
		(layer "F.Cu")
		(net "GND")
	)
	(segment
		(start 205.583536 -123.185936)
		(end 205.14437 -123.625102)
		(width 0.254)
		(layer "F.Cu")
		(net "GND")
	)
	(segment
		(start 194.00012 -68.699888)
		(end 194.400424 -69.100192)
		(width 0.254)
		(layer "F.Cu")
		(net "GND")
	)
	(segment
		(start 186.000136 -63.90005)
		(end 186.399932 -64.299846)
		(width 0.254)
		(layer "F.Cu")
		(net "GND")
	)
	(segment
		(start 190.799974 -59.900058)
		(end 190.800228 -59.900058)
		(width 0.254)
		(layer "F.Cu")
		(net "GND")
	)
	(segment
		(start 202.36434 -52.99964)
		(end 201.99985 -53.36413)
		(width 0.254)
		(layer "F.Cu")
		(net "GND")
	)
	(segment
		(start 79.925164 -92.95003)
		(end 81.304892 -92.95003)
		(width 0.508)
		(layer "F.Cu")
		(net "GND")
	)
	(segment
		(start 206.878936 -98.984308)
		(end 206.870808 -98.992436)
		(width 0.508)
		(layer "F.Cu")
		(net "GND")
	)
	(segment
		(start 47.69993 -144.199864)
		(end 47.300134 -143.800068)
		(width 0.3556)
		(layer "F.Cu")
		(net "GND")
	)
	(segment
		(start 189.399926 -71.817484)
		(end 189.80023 -71.817484)
		(width 0.254)
		(layer "F.Cu")
		(net "GND")
	)
	(segment
		(start 208.5467 -133.922516)
		(end 208.5467 -135.4709)
		(width 0.508)
		(layer "F.Cu")
		(net "GND")
	)
	(segment
		(start 190.393066 -75.502516)
		(end 190.793624 -75.101958)
		(width 0.3048)
		(layer "F.Cu")
		(net "GND")
	)
	(segment
		(start 200.40092 -9.46658)
		(end 199.98944 -9.0551)
		(width 0.254)
		(layer "F.Cu")
		(net "GND")
	)
	(segment
		(start 90.247978 -129.567178)
		(end 90.2462 -129.5654)
		(width 0.254)
		(layer "F.Cu")
		(net "GND")
	)
	(segment
		(start 16.04137 -165.789102)
		(end 16.04137 -166.651178)
		(width 0.254)
		(layer "F.Cu")
		(net "GND")
	)
	(segment
		(start 203.193396 -69.102732)
		(end 203.59624 -68.699888)
		(width 0.3048)
		(layer "F.Cu")
		(net "GND")
	)
	(segment
		(start 31.4706 -166.497)
		(end 31.7754 -166.8018)
		(width 0.254)
		(layer "F.Cu")
		(net "GND")
	)
	(segment
		(start 193.20002 -69.497194)
		(end 193.593974 -69.10324)
		(width 0.254)
		(layer "F.Cu")
		(net "GND")
	)
	(segment
		(start 61.834776 -136.530842)
		(end 62.5094 -136.530842)
		(width 0.254)
		(layer "F.Cu")
		(net "GND")
	)
	(segment
		(start 197.200012 -68.699888)
		(end 197.999858 -68.699888)
		(width 0.254)
		(layer "F.Cu")
		(net "GND")
	)
	(segment
		(start 62.3824 -161.4678)
		(end 62.8396 -161.925)
		(width 0.254)
		(layer "F.Cu")
		(net "GND")
	)
	(segment
		(start 47.29988 -146.19986)
		(end 47.300134 -146.19986)
		(width 0.3556)
		(layer "F.Cu")
		(net "GND")
	)
	(segment
		(start 183.60009 -65.499996)
		(end 183.20004 -65.900046)
		(width 0.254)
		(layer "F.Cu")
		(net "GND")
	)
	(segment
		(start 184.399936 -58.299858)
		(end 184.399936 -58.300112)
		(width 0.254)
		(layer "F.Cu")
		(net "GND")
	)
	(segment
		(start 201.99985 -61.500004)
		(end 201.99477 -61.500004)
		(width 0.254)
		(layer "F.Cu")
		(net "GND")
	)
	(segment
		(start 180.35524 -83.39074)
		(end 180.35524 -83.41106)
		(width 0.254)
		(layer "F.Cu")
		(net "GND")
	)
	(segment
		(start 157.3276 -144.0815)
		(end 157.3276 -144.894554)
		(width 0.508)
		(layer "F.Cu")
		(net "GND")
	)
	(segment
		(start 194.799966 -57.500012)
		(end 194.40017 -57.100216)
		(width 0.254)
		(layer "F.Cu")
		(net "GND")
	)
	(segment
		(start 179.2351 -47.7012)
		(end 179.2351 -46.8757)
		(width 0.508)
		(layer "F.Cu")
		(net "GND")
	)
	(segment
		(start 197.999858 -58.299858)
		(end 198.00062 -58.299858)
		(width 0.254)
		(layer "F.Cu")
		(net "GND")
	)
	(segment
		(start 188.000132 -65.099946)
		(end 187.600082 -64.699896)
		(width 0.254)
		(layer "F.Cu")
		(net "GND")
	)
	(segment
		(start 196.399912 -65.499996)
		(end 196.399912 -65.50025)
		(width 0.254)
		(layer "F.Cu")
		(net "GND")
	)
	(segment
		(start 199.600058 -69.490336)
		(end 199.20966 -69.099938)
		(width 0.254)
		(layer "F.Cu")
		(net "GND")
	)
	(segment
		(start 206.046832 -99.984306)
		(end 206.022448 -100.00869)
		(width 0.508)
		(layer "F.Cu")
		(net "GND")
	)
	(segment
		(start 92.44965 -55.352442)
		(end 92.44965 -55.95366)
		(width 0.254)
		(layer "F.Cu")
		(net "GND")
	)
	(segment
		(start 81.182464 -93.75013)
		(end 81.643728 -93.288866)
		(width 0.508)
		(layer "F.Cu")
		(net "GND")
	)
	(segment
		(start 185.999882 -71.099934)
		(end 186.000136 -71.099934)
		(width 0.254)
		(layer "F.Cu")
		(net "GND")
	)
	(segment
		(start 197.819772 -75.207622)
		(end 197.927468 -75.099926)
		(width 0.3048)
		(layer "F.Cu")
		(net "GND")
	)
	(segment
		(start 199.600058 -62.296802)
		(end 199.206358 -61.903102)
		(width 0.254)
		(layer "F.Cu")
		(net "GND")
	)
	(segment
		(start 201.941938 -63.042038)
		(end 201.897488 -63.036958)
		(width 0.254)
		(layer "F.Cu")
		(net "GND")
	)
	(segment
		(start 184.399936 -71.099934)
		(end 184.399936 -71.100188)
		(width 0.254)
		(layer "F.Cu")
		(net "GND")
	)
	(segment
		(start 205.3336 -53.5432)
		(end 205.17612 -53.70068)
		(width 0.254)
		(layer "F.Cu")
		(net "GND")
	)
	(segment
		(start 192.39992 -59.099958)
		(end 192.000124 -58.700162)
		(width 0.254)
		(layer "F.Cu")
		(net "GND")
	)
	(segment
		(start 190.000128 -59.099958)
		(end 190.399924 -58.700162)
		(width 0.254)
		(layer "F.Cu")
		(net "GND")
	)
	(segment
		(start 93.853 -180.32476)
		(end 94.76994 -180.32476)
		(width 0.4318)
		(layer "F.Cu")
		(net "GND")
	)
	(segment
		(start 49.699926 -137.40003)
		(end 50.099722 -137.000234)
		(width 0.3556)
		(layer "F.Cu")
		(net "GND")
	)
	(segment
		(start 189.200536 -58.299858)
		(end 189.600078 -57.900316)
		(width 0.254)
		(layer "F.Cu")
		(net "GND")
	)
	(segment
		(start 28.64993 -179.57673)
		(end 28.2702 -179.197)
		(width 0.508)
		(layer "F.Cu")
		(net "GND")
	)
	(segment
		(start 196.3928 -24.7904)
		(end 195.9102 -24.3078)
		(width 0.4064)
		(layer "F.Cu")
		(net "GND")
	)
	(segment
		(start 224.889822 -61.277246)
		(end 226.682046 -61.277246)
		(width 0.254)
		(layer "F.Cu")
		(net "GND")
	)
	(segment
		(start 200.399904 -75.899518)
		(end 200.000108 -75.499722)
		(width 0.3048)
		(layer "F.Cu")
		(net "GND")
	)
	(segment
		(start 77.58938 -158.428436)
		(end 77.150214 -158.867602)
		(width 0.254)
		(layer "F.Cu")
		(net "GND")
	)
	(segment
		(start 196.402198 -69.499988)
		(end 196.796406 -69.894196)
		(width 0.254)
		(layer "F.Cu")
		(net "GND")
	)
	(segment
		(start 189.600078 -65.900046)
		(end 189.200028 -65.499996)
		(width 0.254)
		(layer "F.Cu")
		(net "GND")
	)
	(segment
		(start 200.40092 -11.953748)
		(end 200.40092 -9.46658)
		(width 0.254)
		(layer "F.Cu")
		(net "GND")
	)
	(segment
		(start 29.692346 -133.603746)
		(end 28.9052 -132.8166)
		(width 0.381)
		(layer "F.Cu")
		(net "GND")
	)
	(segment
		(start 195.599812 -62.29985)
		(end 195.20027 -61.900308)
		(width 0.254)
		(layer "F.Cu")
		(net "GND")
	)
	(segment
		(start 203.298552 -132.881624)
		(end 203.298552 -133.727952)
		(width 0.508)
		(layer "F.Cu")
		(net "GND")
	)
	(segment
		(start 198.799958 -70.299834)
		(end 198.804784 -70.299834)
		(width 0.254)
		(layer "F.Cu")
		(net "GND")
	)
	(segment
		(start 206.1845 -81.915)
		(end 206.1845 -82.55)
		(width 0.254)
		(layer "F.Cu")
		(net "GND")
	)
	(segment
		(start 198.799958 -69.499988)
		(end 198.80961 -69.499988)
		(width 0.254)
		(layer "F.Cu")
		(net "GND")
	)
	(segment
		(start 72.770492 -137.922)
		(end 72.644 -137.795508)
		(width 0.508)
		(layer "F.Cu")
		(net "GND")
	)
	(segment
		(start 184.399936 -63.09995)
		(end 184.400444 -63.09995)
		(width 0.254)
		(layer "F.Cu")
		(net "GND")
	)
	(segment
		(start 203.705714 -52.99964)
		(end 202.36434 -52.99964)
		(width 0.254)
		(layer "F.Cu")
		(net "GND")
	)
	(segment
		(start 94.35084 -123.7107)
		(end 94.35084 -123.14682)
		(width 0.254)
		(layer "F.Cu")
		(net "GND")
	)
	(segment
		(start 69.1769 -162.306)
		(end 69.1769 -161.9123)
		(width 0.508)
		(layer "F.Cu")
		(net "GND")
	)
	(segment
		(start 204.309218 -64.699896)
		(end 204.399896 -64.699896)
		(width 0.3048)
		(layer "F.Cu")
		(net "GND")
	)
	(segment
		(start 197.999858 -69.500496)
		(end 197.600062 -69.900292)
		(width 0.254)
		(layer "F.Cu")
		(net "GND")
	)
	(segment
		(start 193.999866 -69.500496)
		(end 193.600324 -69.900038)
		(width 0.254)
		(layer "F.Cu")
		(net "GND")
	)
	(segment
		(start 185.200036 -68.699888)
		(end 185.60034 -69.100192)
		(width 0.254)
		(layer "F.Cu")
		(net "GND")
	)
	(segment
		(start 188.399928 -67.900042)
		(end 188.000132 -68.299838)
		(width 0.254)
		(layer "F.Cu")
		(net "GND")
	)
	(segment
		(start 190.800482 -70.299834)
		(end 191.200278 -69.900038)
		(width 0.254)
		(layer "F.Cu")
		(net "GND")
	)
	(segment
		(start 196.399912 -65.50025)
		(end 196.000116 -65.900046)
		(width 0.254)
		(layer "F.Cu")
		(net "GND")
	)
	(segment
		(start 194.799966 -68.70065)
		(end 194.400424 -69.100192)
		(width 0.254)
		(layer "F.Cu")
		(net "GND")
	)
	(segment
		(start 184.399936 -74.299826)
		(end 183.999886 -73.899776)
		(width 0.3048)
		(layer "F.Cu")
		(net "GND")
	)
	(segment
		(start 122.604022 -10.7188)
		(end 122.4026 -10.7188)
		(width 0.254)
		(layer "F.Cu")
		(net "GND")
	)
	(segment
		(start 194.00012 -63.90005)
		(end 194.40017 -64.3001)
		(width 0.254)
		(layer "F.Cu")
		(net "GND")
	)
	(segment
		(start 64.0715 -166.71925)
		(end 62.92215 -166.71925)
		(width 0.508)
		(layer "F.Cu")
		(net "GND")
	)
	(segment
		(start 50.935128 -167.292528)
		(end 51.5112 -167.8686)
		(width 0.508)
		(layer "F.Cu")
		(net "GND")
	)
	(segment
		(start 203.59624 -68.699888)
		(end 203.60005 -68.699888)
		(width 0.3048)
		(layer "F.Cu")
		(net "GND")
	)
	(segment
		(start 23.234396 -142.961614)
		(end 23.234142 -142.961614)
		(width 0.3048)
		(layer "F.Cu")
		(net "GND")
	)
	(segment
		(start 196.399912 -57.500012)
		(end 196.800216 -57.900316)
		(width 0.254)
		(layer "F.Cu")
		(net "GND")
	)
	(segment
		(start 66.2432 -149.9108)
		(end 66.5226 -150.1902)
		(width 0.254)
		(layer "F.Cu")
		(net "GND")
	)
	(segment
		(start 93.795342 -164.051234)
		(end 95.0468 -164.051234)
		(width 0.508)
		(layer "F.Cu")
		(net "GND")
	)
	(segment
		(start 190.000128 -57.500012)
		(end 190.399924 -57.100216)
		(width 0.254)
		(layer "F.Cu")
		(net "GND")
	)
	(segment
		(start 54.0004 -130.6576)
		(end 53.7718 -130.429)
		(width 0.254)
		(layer "F.Cu")
		(net "GND")
	)
	(segment
		(start 197.1548 -13.0175)
		(end 197.1548 -12.1158)
		(width 0.508)
		(layer "F.Cu")
		(net "GND")
	)
	(segment
		(start 193.999866 -67.099942)
		(end 194.40017 -67.500246)
		(width 0.254)
		(layer "F.Cu")
		(net "GND")
	)
	(segment
		(start 75.403964 -140.627862)
		(end 76.039726 -140.627862)
		(width 0.508)
		(layer "F.Cu")
		(net "GND")
	)
	(segment
		(start 189.999874 -60.700412)
		(end 189.600078 -61.100208)
		(width 0.254)
		(layer "F.Cu")
		(net "GND")
	)
	(segment
		(start 198.80961 -62.29985)
		(end 199.206358 -61.903102)
		(width 0.254)
		(layer "F.Cu")
		(net "GND")
	)
	(segment
		(start 155.956 -85.6869)
		(end 155.956 -84.89442)
		(width 0.508)
		(layer "F.Cu")
		(net "GND")
	)
	(segment
		(start 179.832 -114.681)
		(end 179.832 -113.3094)
		(width 0.508)
		(layer "F.Cu")
		(net "GND")
	)
	(segment
		(start 197.200012 -63.09995)
		(end 197.999858 -63.09995)
		(width 0.254)
		(layer "F.Cu")
		(net "GND")
	)
	(segment
		(start 202.79995 -60.699904)
		(end 202.799696 -60.699904)
		(width 0.254)
		(layer "F.Cu")
		(net "GND")
	)
	(segment
		(start 201.99985 -63.09995)
		(end 201.941938 -63.042038)
		(width 0.254)
		(layer "F.Cu")
		(net "GND")
	)
	(segment
		(start 77.026516 -72.95007)
		(end 77.283818 -72.692768)
		(width 0.508)
		(layer "F.Cu")
		(net "GND")
	)
	(segment
		(start 196.399912 -55.099966)
		(end 196.000116 -54.70017)
		(width 0.254)
		(layer "F.Cu")
		(net "GND")
	)
	(segment
		(start 197.209156 -67.900042)
		(end 197.605904 -67.503294)
		(width 0.254)
		(layer "F.Cu")
		(net "GND")
	)
	(segment
		(start 184.400444 -63.09995)
		(end 184.80024 -62.700154)
		(width 0.254)
		(layer "F.Cu")
		(net "GND")
	)
	(segment
		(start 192.5574 -47.135796)
		(end 191.70015 -46.278546)
		(width 0.508)
		(layer "F.Cu")
		(net "GND")
	)
	(segment
		(start 75.475084 -51.34991)
		(end 77.648562 -51.34991)
		(width 0.508)
		(layer "F.Cu")
		(net "GND")
	)
	(segment
		(start 94.0308 -161.6456)
		(end 94.361 -161.6456)
		(width 0.508)
		(layer "F.Cu")
		(net "GND")
	)
	(segment
		(start 51.699414 -138.600434)
		(end 51.299872 -138.999976)
		(width 0.3556)
		(layer "F.Cu")
		(net "GND")
	)
	(segment
		(start 50.500026 -150.999952)
		(end 50.899822 -151.399748)
		(width 0.3556)
		(layer "F.Cu")
		(net "GND")
	)
	(segment
		(start 184.322212 -44.943268)
		(end 184.097168 -44.943268)
		(width 0.508)
		(layer "F.Cu")
		(net "GND")
	)
	(segment
		(start 85.7885 -149.793706)
		(end 85.826346 -149.75586)
		(width 0.254)
		(layer "F.Cu")
		(net "GND")
	)
	(segment
		(start 202.392788 -65.097406)
		(end 202.361292 -65.06591)
		(width 0.254)
		(layer "F.Cu")
		(net "GND")
	)
	(segment
		(start 190.799974 -59.099958)
		(end 190.800228 -59.099958)
		(width 0.254)
		(layer "F.Cu")
		(net "GND")
	)
	(segment
		(start 184.799986 -56.300116)
		(end 185.200036 -55.900066)
		(width 0.254)
		(layer "F.Cu")
		(net "GND")
	)
	(segment
		(start 193.20002 -59.900058)
		(end 193.999866 -59.900058)
		(width 0.254)
		(layer "F.Cu")
		(net "GND")
	)
	(segment
		(start 192.603628 -71.021956)
		(end 193.003932 -71.021956)
		(width 0.254)
		(layer "F.Cu")
		(net "GND")
	)
	(segment
		(start 199.600058 -63.09995)
		(end 199.600058 -63.096902)
		(width 0.254)
		(layer "F.Cu")
		(net "GND")
	)
	(segment
		(start 67.32778 -154.99842)
		(end 67.32778 -157.80766)
		(width 0.254)
		(layer "F.Cu")
		(net "GND")
	)
	(segment
		(start 75.475084 -95.350076)
		(end 76.74991 -95.350076)
		(width 0.508)
		(layer "F.Cu")
		(net "GND")
	)
	(segment
		(start 58.7502 -163.9697)
		(end 58.7502 -164.7698)
		(width 0.508)
		(layer "F.Cu")
		(net "GND")
	)
	(segment
		(start 68.712334 -158.178246)
		(end 68.6816 -158.20898)
		(width 0.508)
		(layer "F.Cu")
		(net "GND")
	)
	(segment
		(start 204.0382 -77.1398)
		(end 203.60005 -76.70165)
		(width 0.254)
		(layer "F.Cu")
		(net "GND")
	)
	(segment
		(start 180.6321 -47.7012)
		(end 180.6321 -46.8757)
		(width 0.508)
		(layer "F.Cu")
		(net "GND")
	)
	(segment
		(start 51.699668 -138.600434)
		(end 51.699414 -138.600434)
		(width 0.3556)
		(layer "F.Cu")
		(net "GND")
	)
	(segment
		(start 142.0368 -10.2997)
		(end 142.0368 -9.21131)
		(width 0.508)
		(layer "F.Cu")
		(net "GND")
	)
	(segment
		(start 91.567 -29.6418)
		(end 88.563958 -29.6418)
		(width 0.508)
		(layer "F.Cu")
		(net "GND")
	)
	(segment
		(start 47.29988 -137.40003)
		(end 46.89983 -136.99998)
		(width 0.254)
		(layer "F.Cu")
		(net "GND")
	)
	(segment
		(start 56.515 -136.184894)
		(end 56.099964 -136.59993)
		(width 0.254)
		(layer "F.Cu")
		(net "GND")
	)
	(segment
		(start 201.5998 -58.700162)
		(end 201.600054 -58.700162)
		(width 0.254)
		(layer "F.Cu")
		(net "GND")
	)
	(segment
		(start 198.799958 -65.499996)
		(end 198.80961 -65.499996)
		(width 0.254)
		(layer "F.Cu")
		(net "GND")
	)
	(segment
		(start 193.200528 -70.299834)
		(end 193.600324 -69.900038)
		(width 0.254)
		(layer "F.Cu")
		(net "GND")
	)
	(segment
		(start 23.78456 -15.45844)
		(end 25.08758 -15.45844)
		(width 0.508)
		(layer "F.Cu")
		(net "GND")
	)
	(segment
		(start 62.0903 -149.7584)
		(end 62.8396 -149.7584)
		(width 0.254)
		(layer "F.Cu")
		(net "GND")
	)
	(segment
		(start 191.600328 -59.900058)
		(end 192.000124 -59.500262)
		(width 0.254)
		(layer "F.Cu")
		(net "GND")
	)
	(segment
		(start 203.298552 -133.727952)
		(end 203.4032 -133.8326)
		(width 0.508)
		(layer "F.Cu")
		(net "GND")
	)
	(segment
		(start 197.190614 -69.499988)
		(end 196.796406 -69.894196)
		(width 0.254)
		(layer "F.Cu")
		(net "GND")
	)
	(segment
		(start 195.600066 -67.900042)
		(end 195.60032 -67.900042)
		(width 0.254)
		(layer "F.Cu")
		(net "GND")
	)
	(segment
		(start 185.999882 -63.09995)
		(end 186.000136 -63.09995)
		(width 0.254)
		(layer "F.Cu")
		(net "GND")
	)
	(segment
		(start 190.799974 -63.90005)
		(end 190.799974 -63.90894)
		(width 0.254)
		(layer "F.Cu")
		(net "GND")
	)
	(segment
		(start 43.299888 -145.39976)
		(end 43.299888 -145.400014)
		(width 0.3556)
		(layer "F.Cu")
		(net "GND")
	)
	(segment
		(start 77.030834 -66.550032)
		(end 77.274674 -66.306192)
		(width 0.508)
		(layer "F.Cu")
		(net "GND")
	)
	(segment
		(start 94.254574 -51.122834)
		(end 94.43085 -50.946558)
		(width 0.254)
		(layer "F.Cu")
		(net "GND")
	)
	(segment
		(start 155.956 -84.89442)
		(end 155.82392 -84.76234)
		(width 0.508)
		(layer "F.Cu")
		(net "GND")
	)
	(segment
		(start 227.9142 -60.9092)
		(end 227.546154 -61.277246)
		(width 0.254)
		(layer "F.Cu")
		(net "GND")
	)
	(segment
		(start 188.399928 -64.699896)
		(end 188.233812 -64.866012)
		(width 0.254)
		(layer "F.Cu")
		(net "GND")
	)
	(segment
		(start 185.200036 -63.900304)
		(end 185.60034 -64.300608)
		(width 0.254)
		(layer "F.Cu")
		(net "GND")
	)
	(segment
		(start 76.749148 -88.950038)
		(end 77.283818 -88.415368)
		(width 0.508)
		(layer "F.Cu")
		(net "GND")
	)
	(segment
		(start 186.799982 -62.29985)
		(end 186.800236 -62.29985)
		(width 0.254)
		(layer "F.Cu")
		(net "GND")
	)
	(segment
		(start 188.2902 -47.9425)
		(end 188.2902 -47.1678)
		(width 0.508)
		(layer "F.Cu")
		(net "GND")
	)
	(segment
		(start 75.475084 -72.95007)
		(end 77.026516 -72.95007)
		(width 0.508)
		(layer "F.Cu")
		(net "GND")
	)
	(segment
		(start 68.075302 -179.015898)
		(end 68.04152 -179.04968)
		(width 0.508)
		(layer "F.Cu")
		(net "GND")
	)
	(segment
		(start 200.399904 -73.49998)
		(end 200.39965 -73.49998)
		(width 0.254)
		(layer "F.Cu")
		(net "GND")
	)
	(segment
		(start 202.799696 -60.699904)
		(end 201.99985 -59.900058)
		(width 0.254)
		(layer "F.Cu")
		(net "GND")
	)
	(segment
		(start 74.887328 -175.754538)
		(end 74.880216 -175.76165)
		(width 0.508)
		(layer "F.Cu")
		(net "GND")
	)
	(segment
		(start 181.800246 -62.3824)
		(end 181.882796 -62.29985)
		(width 0.254)
		(layer "F.Cu")
		(net "GND")
	)
	(segment
		(start 202.79995 -67.099942)
		(end 202.795378 -67.099942)
		(width 0.254)
		(layer "F.Cu")
		(net "GND")
	)
	(segment
		(start 63.04661 -154.97429)
		(end 63.1063 -154.9146)
		(width 0.508)
		(layer "F.Cu")
		(net "GND")
	)
	(segment
		(start 190.799974 -65.499996)
		(end 190.800228 -65.499996)
		(width 0.254)
		(layer "F.Cu")
		(net "GND")
	)
	(segment
		(start 198.80961 -65.499996)
		(end 199.203818 -65.894204)
		(width 0.254)
		(layer "F.Cu")
		(net "GND")
	)
	(segment
		(start 61.9125 -149.5806)
		(end 62.0903 -149.7584)
		(width 0.254)
		(layer "F.Cu")
		(net "GND")
	)
	(segment
		(start 203.765658 -52.939696)
		(end 203.705714 -52.99964)
		(width 0.254)
		(layer "F.Cu")
		(net "GND")
	)
	(segment
		(start 46.89983 -149.800056)
		(end 47.299626 -150.199852)
		(width 0.3556)
		(layer "F.Cu")
		(net "GND")
	)
	(segment
		(start 185.200036 -66.299842)
		(end 185.200036 -67.099942)
		(width 0.254)
		(layer "F.Cu")
		(net "GND")
	)
	(segment
		(start 48.09998 -142.999968)
		(end 48.899826 -142.999968)
		(width 0.3556)
		(layer "F.Cu")
		(net "GND")
	)
	(segment
		(start 79.925164 -76.950062)
		(end 81.397094 -76.950062)
		(width 0.508)
		(layer "F.Cu")
		(net "GND")
	)
	(segment
		(start 39.699438 -141.799818)
		(end 40.099488 -142.199868)
		(width 0.3556)
		(layer "F.Cu")
		(net "GND")
	)
	(segment
		(start 47.69993 -146.59991)
		(end 48.09998 -146.99996)
		(width 0.3556)
		(layer "F.Cu")
		(net "GND")
	)
	(segment
		(start 187.57011 -88.81999)
		(end 187.57011 -89.64549)
		(width 0.508)
		(layer "F.Cu")
		(net "GND")
	)
	(segment
		(start 74.934572 -168.477946)
		(end 75.3872 -168.930574)
		(width 0.508)
		(layer "F.Cu")
		(net "GND")
	)
	(segment
		(start 190.799974 -71.900034)
		(end 190.799974 -71.902828)
		(width 0.254)
		(layer "F.Cu")
		(net "GND")
	)
	(segment
		(start 187.600082 -59.099958)
		(end 187.200286 -58.700162)
		(width 0.254)
		(layer "F.Cu")
		(net "GND")
	)
	(segment
		(start 189.317376 -71.900034)
		(end 189.399926 -71.817484)
		(width 0.254)
		(layer "F.Cu")
		(net "GND")
	)
	(segment
		(start 189.200028 -59.099958)
		(end 189.200282 -59.099958)
		(width 0.254)
		(layer "F.Cu")
		(net "GND")
	)
	(segment
		(start 79.925164 -90.549984)
		(end 81.182718 -90.549984)
		(width 0.508)
		(layer "F.Cu")
		(net "GND")
	)
	(segment
		(start 34.791396 -135.953754)
		(end 34.79546 -135.94969)
		(width 0.254)
		(layer "F.Cu")
		(net "GND")
	)
	(segment
		(start 193.20002 -66.299842)
		(end 193.190622 -66.299842)
		(width 0.254)
		(layer "F.Cu")
		(net "GND")
	)
	(segment
		(start 168.1861 -112.5728)
		(end 167.1066 -112.5728)
		(width 0.508)
		(layer "F.Cu")
		(net "GND")
	)
	(segment
		(start 183.999886 -73.899776)
		(end 183.60009 -73.49998)
		(width 0.3048)
		(layer "F.Cu")
		(net "GND")
	)
	(segment
		(start 188.399928 -71.899526)
		(end 188.000386 -71.499984)
		(width 0.254)
		(layer "F.Cu")
		(net "GND")
	)
	(segment
		(start 200.399904 -72.69988)
		(end 200.399904 -72.700134)
		(width 0.254)
		(layer "F.Cu")
		(net "GND")
	)
	(segment
		(start 198.799958 -66.298064)
		(end 199.203818 -65.894204)
		(width 0.254)
		(layer "F.Cu")
		(net "GND")
	)
	(segment
		(start 186.799982 -59.900058)
		(end 186.80049 -59.900058)
		(width 0.254)
		(layer "F.Cu")
		(net "GND")
	)
	(segment
		(start 81.142586 -68.150232)
		(end 81.605374 -67.687444)
		(width 0.508)
		(layer "F.Cu")
		(net "GND")
	)
	(segment
		(start 88.5444 -163.449)
		(end 88.5444 -162.3187)
		(width 0.254)
		(layer "F.Cu")
		(net "GND")
	)
	(segment
		(start 193.195702 -75.900026)
		(end 193.20002 -75.900026)
		(width 0.3048)
		(layer "F.Cu")
		(net "GND")
	)
	(segment
		(start 185.999882 -57.500012)
		(end 185.200036 -57.500012)
		(width 0.254)
		(layer "F.Cu")
		(net "GND")
	)
	(segment
		(start 93.141546 -51.122834)
		(end 94.254574 -51.122834)
		(width 0.254)
		(layer "F.Cu")
		(net "GND")
	)
	(segment
		(start 193.999866 -59.099958)
		(end 194.399916 -58.699908)
		(width 0.254)
		(layer "F.Cu")
		(net "GND")
	)
	(segment
		(start 192.800224 -62.700154)
		(end 193.20002 -63.09995)
		(width 0.254)
		(layer "F.Cu")
		(net "GND")
	)
	(segment
		(start 188.399928 -71.099934)
		(end 188.399928 -71.100442)
		(width 0.254)
		(layer "F.Cu")
		(net "GND")
	)
	(segment
		(start 197.999858 -68.70954)
		(end 198.390256 -69.099938)
		(width 0.254)
		(layer "F.Cu")
		(net "GND")
	)
	(segment
		(start 77.018388 -88.149938)
		(end 77.283818 -88.415368)
		(width 0.508)
		(layer "F.Cu")
		(net "GND")
	)
	(segment
		(start 121.2342 -17.5768)
		(end 121.2342 -16.4465)
		(width 0.508)
		(layer "F.Cu")
		(net "GND")
	)
	(segment
		(start 193.20002 -70.299834)
		(end 193.200528 -70.299834)
		(width 0.254)
		(layer "F.Cu")
		(net "GND")
	)
	(segment
		(start 155.9306 -141.0716)
		(end 154.9908 -141.0716)
		(width 0.254)
		(layer "F.Cu")
		(net "GND")
	)
	(segment
		(start 78.8289 -136.726422)
		(end 78.289912 -137.26541)
		(width 0.254)
		(layer "F.Cu")
		(net "GND")
	)
	(segment
		(start 191.600074 -72.69988)
		(end 191.600074 -71.900034)
		(width 0.254)
		(layer "F.Cu")
		(net "GND")
	)
	(segment
		(start 187.600082 -67.900042)
		(end 187.600336 -67.900042)
		(width 0.254)
		(layer "F.Cu")
		(net "GND")
	)
	(segment
		(start 189.999874 -70.299834)
		(end 190.000382 -70.299834)
		(width 0.254)
		(layer "F.Cu")
		(net "GND")
	)
	(segment
		(start 185.999882 -63.90005)
		(end 186.000136 -63.90005)
		(width 0.254)
		(layer "F.Cu")
		(net "GND")
	)
	(segment
		(start 125.2855 -8.636)
		(end 125.6792 -8.636)
		(width 0.254)
		(layer "F.Cu")
		(net "GND")
	)
	(segment
		(start 197.20052 -58.299858)
		(end 197.600316 -57.900062)
		(width 0.254)
		(layer "F.Cu")
		(net "GND")
	)
	(segment
		(start 11.1379 -167.8178)
		(end 10.238486 -167.8178)
		(width 0.508)
		(layer "F.Cu")
		(net "GND")
	)
	(segment
		(start 56.099964 -153.400252)
		(end 56.099964 -153.399998)
		(width 0.254)
		(layer "F.Cu")
		(net "GND")
	)
	(segment
		(start 197.200012 -67.099942)
		(end 197.202552 -67.099942)
		(width 0.254)
		(layer "F.Cu")
		(net "GND")
	)
	(segment
		(start 200.409556 -66.299842)
		(end 200.799954 -65.909444)
		(width 0.254)
		(layer "F.Cu")
		(net "GND")
	)
	(segment
		(start 79.155544 -170.260772)
		(end 79.1464 -170.269916)
		(width 0.508)
		(layer "F.Cu")
		(net "GND")
	)
	(segment
		(start 165.12413 -99.439476)
		(end 166.28618 -99.439476)
		(width 0.508)
		(layer "F.Cu")
		(net "GND")
	)
	(segment
		(start 202.79995 -71.900034)
		(end 203.199746 -72.29983)
		(width 0.3048)
		(layer "F.Cu")
		(net "GND")
	)
	(segment
		(start 185.200036 -71.900034)
		(end 185.20029 -71.900034)
		(width 0.254)
		(layer "F.Cu")
		(net "GND")
	)
	(segment
		(start 124.46889 -11.5443)
		(end 124.4727 -11.54811)
		(width 0.254)
		(layer "F.Cu")
		(net "GND")
	)
	(segment
		(start 77.63891 -52.15001)
		(end 77.827378 -52.338478)
		(width 0.508)
		(layer "F.Cu")
		(net "GND")
	)
	(segment
		(start 178.42484 -122.1994)
		(end 178.42484 -121.11736)
		(width 0.508)
		(layer "F.Cu")
		(net "GND")
	)
	(segment
		(start 51.6636 -131.3053)
		(end 51.689 -131.2799)
		(width 0.508)
		(layer "F.Cu")
		(net "GND")
	)
	(segment
		(start 198.799958 -60.699904)
		(end 198.400162 -60.300108)
		(width 0.254)
		(layer "F.Cu")
		(net "GND")
	)
	(segment
		(start 196.000116 -67.500246)
		(end 196.399912 -67.900042)
		(width 0.254)
		(layer "F.Cu")
		(net "GND")
	)
	(segment
		(start 195.600066 -58.299858)
		(end 194.799966 -59.099958)
		(width 0.254)
		(layer "F.Cu")
		(net "GND")
	)
	(segment
		(start 195.600066 -61.500004)
		(end 195.600066 -61.500512)
		(width 0.254)
		(layer "F.Cu")
		(net "GND")
	)
	(segment
		(start 51.71567 -153.7843)
		(end 51.679602 -153.7843)
		(width 0.3556)
		(layer "F.Cu")
		(net "GND")
	)
	(segment
		(start 193.20002 -73.499472)
		(end 193.599816 -73.099676)
		(width 0.254)
		(layer "F.Cu")
		(net "GND")
	)
	(segment
		(start 190.000382 -70.299834)
		(end 190.400178 -69.900038)
		(width 0.254)
		(layer "F.Cu")
		(net "GND")
	)
	(segment
		(start 198.00062 -58.299858)
		(end 198.400162 -57.900316)
		(width 0.254)
		(layer "F.Cu")
		(net "GND")
	)
	(segment
		(start 186.799982 -73.49998)
		(end 187.199778 -73.899776)
		(width 0.3048)
		(layer "F.Cu")
		(net "GND")
	)
	(segment
		(start 185.200036 -67.099942)
		(end 185.200036 -67.100196)
		(width 0.254)
		(layer "F.Cu")
		(net "GND")
	)
	(segment
		(start 184.399936 -69.499988)
		(end 184.799986 -69.099938)
		(width 0.254)
		(layer "F.Cu")
		(net "GND")
	)
	(segment
		(start 81.425288 -54.550056)
		(end 81.732628 -54.857396)
		(width 0.254)
		(layer "F.Cu")
		(net "GND")
	)
	(segment
		(start 87.63 -129.42316)
		(end 88.22944 -130.0226)
		(width 0.254)
		(layer "F.Cu")
		(net "GND")
	)
	(segment
		(start 203.197714 -63.502286)
		(end 203.197714 -63.492888)
		(width 0.254)
		(layer "F.Cu")
		(net "GND")
	)
	(segment
		(start 187.200032 -65.099946)
		(end 186.799982 -64.699896)
		(width 0.254)
		(layer "F.Cu")
		(net "GND")
	)
	(segment
		(start 190.799974 -69.499988)
		(end 190.800228 -69.499988)
		(width 0.254)
		(layer "F.Cu")
		(net "GND")
	)
	(segment
		(start 95.0468 -162.3314)
		(end 95.0468 -164.051234)
		(width 0.508)
		(layer "F.Cu")
		(net "GND")
	)
	(segment
		(start 203.199746 -70.69963)
		(end 202.79995 -71.099426)
		(width 0.3048)
		(layer "F.Cu")
		(net "GND")
	)
	(segment
		(start 77.84338 -188.86678)
		(end 77.84338 -188.5188)
		(width 0.508)
		(layer "F.Cu")
		(net "GND")
	)
	(segment
		(start 191.600074 -64.699896)
		(end 191.59093 -64.699896)
		(width 0.254)
		(layer "F.Cu")
		(net "GND")
	)
	(segment
		(start 190.799974 -71.902828)
		(end 190.396622 -72.30618)
		(width 0.254)
		(layer "F.Cu")
		(net "GND")
	)
	(segment
		(start 195.20027 -61.900308)
		(end 194.800474 -61.500512)
		(width 0.254)
		(layer "F.Cu")
		(net "GND")
	)
	(segment
		(start 81.182464 -71.350124)
		(end 81.643728 -70.88886)
		(width 0.508)
		(layer "F.Cu")
		(net "GND")
	)
	(segment
		(start 189.200282 -59.900058)
		(end 189.600078 -59.500262)
		(width 0.254)
		(layer "F.Cu")
		(net "GND")
	)
	(segment
		(start 23.234396 -138.961622)
		(end 23.996142 -138.961622)
		(width 0.3048)
		(layer "F.Cu")
		(net "GND")
	)
	(segment
		(start 197.999858 -75.900026)
		(end 198.399908 -75.499976)
		(width 0.3048)
		(layer "F.Cu")
		(net "GND")
	)
	(segment
		(start 198.80326 -63.90005)
		(end 199.206358 -64.303148)
		(width 0.254)
		(layer "F.Cu")
		(net "GND")
	)
	(segment
		(start 192.39992 -71.099934)
		(end 192.52565 -71.099934)
		(width 0.254)
		(layer "F.Cu")
		(net "GND")
	)
	(segment
		(start 187.600082 -60.699904)
		(end 187.993528 -61.09335)
		(width 0.254)
		(layer "F.Cu")
		(net "GND")
	)
	(segment
		(start 90.17 -165.64864)
		(end 90.17 -163.904676)
		(width 0.254)
		(layer "F.Cu")
		(net "GND")
	)
	(segment
		(start 94.46895 -146.651218)
		(end 93.972126 -147.148042)
		(width 0.254)
		(layer "F.Cu")
		(net "GND")
	)
	(segment
		(start 39.299896 -153.400252)
		(end 39.299896 -153.399998)
		(width 0.3556)
		(layer "F.Cu")
		(net "GND")
	)
	(segment
		(start 94.35084 -123.14682)
		(end 94.3991 -123.09856)
		(width 0.254)
		(layer "F.Cu")
		(net "GND")
	)
	(segment
		(start 43.700192 -149.800056)
		(end 43.700192 -149.799802)
		(width 0.3556)
		(layer "F.Cu")
		(net "GND")
	)
	(segment
		(start 202.79995 -66.299842)
		(end 202.79995 -66.304414)
		(width 0.254)
		(layer "F.Cu")
		(net "GND")
	)
	(segment
		(start 186.000136 -63.09995)
		(end 186.399932 -63.499746)
		(width 0.254)
		(layer "F.Cu")
		(net "GND")
	)
	(segment
		(start 198.799958 -75.099926)
		(end 198.399908 -75.499976)
		(width 0.3048)
		(layer "F.Cu")
		(net "GND")
	)
	(segment
		(start 202.79995 -72.699626)
		(end 202.79995 -72.69988)
		(width 0.3048)
		(layer "F.Cu")
		(net "GND")
	)
	(segment
		(start 189.200282 -59.099958)
		(end 189.600078 -58.700162)
		(width 0.254)
		(layer "F.Cu")
		(net "GND")
	)
	(segment
		(start 191.200024 -56.300116)
		(end 191.600074 -55.900066)
		(width 0.254)
		(layer "F.Cu")
		(net "GND")
	)
	(segment
		(start 180.35524 -83.41106)
		(end 180.06314 -83.70316)
		(width 0.254)
		(layer "F.Cu")
		(net "GND")
	)
	(segment
		(start 188.399928 -63.09995)
		(end 188.000132 -63.499746)
		(width 0.254)
		(layer "F.Cu")
		(net "GND")
	)
	(segment
		(start 75.475084 -91.350084)
		(end 76.738734 -91.350084)
		(width 0.508)
		(layer "F.Cu")
		(net "GND")
	)
	(segment
		(start 197.999858 -72.69988)
		(end 197.999858 -72.701658)
		(width 0.254)
		(layer "F.Cu")
		(net "GND")
	)
	(segment
		(start 48.195484 -167.6146)
		(end 48.006 -167.6146)
		(width 0.508)
		(layer "F.Cu")
		(net "GND")
	)
	(segment
		(start 75.475084 -78.550008)
		(end 76.740258 -78.550008)
		(width 0.508)
		(layer "F.Cu")
		(net "GND")
	)
	(segment
		(start 196.597524 -75.206352)
		(end 197.018656 -75.206352)
		(width 0.3048)
		(layer "F.Cu")
		(net "GND")
	)
	(segment
		(start 203.60005 -71.099934)
		(end 203.199746 -70.69963)
		(width 0.3048)
		(layer "F.Cu")
		(net "GND")
	)
	(segment
		(start 66.71183 -180.650388)
		(end 66.709036 -180.653182)
		(width 0.508)
		(layer "F.Cu")
		(net "GND")
	)
	(segment
		(start 30.3276 -129.921)
		(end 30.3276 -130.4417)
		(width 0.508)
		(layer "F.Cu")
		(net "GND")
	)
	(segment
		(start 184.6961 -47.7012)
		(end 184.6961 -46.8757)
		(width 0.508)
		(layer "F.Cu")
		(net "GND")
	)
	(segment
		(start 176.9237 -62.1792)
		(end 176.9237 -61.3537)
		(width 0.508)
		(layer "F.Cu")
		(net "GND")
	)
	(segment
		(start 72.644 -137.795508)
		(end 72.639428 -137.795508)
		(width 0.508)
		(layer "F.Cu")
		(net "GND")
	)
	(segment
		(start 198.000366 -60.699904)
		(end 198.400162 -60.300108)
		(width 0.254)
		(layer "F.Cu")
		(net "GND")
	)
	(segment
		(start 202.79995 -75.099926)
		(end 203.60005 -75.900026)
		(width 0.254)
		(layer "F.Cu")
		(net "GND")
	)
	(segment
		(start 185.200036 -59.100212)
		(end 185.60034 -59.500516)
		(width 0.254)
		(layer "F.Cu")
		(net "GND")
	)
	(segment
		(start 186.800236 -61.500004)
		(end 187.200032 -61.8998)
		(width 0.254)
		(layer "F.Cu")
		(net "GND")
	)
	(segment
		(start 95.25 -29.464)
		(end 95.25 -28.194)
		(width 0.508)
		(layer "F.Cu")
		(net "GND")
	)
	(segment
		(start 224.249234 -61.917834)
		(end 224.889822 -61.277246)
		(width 0.254)
		(layer "F.Cu")
		(net "GND")
	)
	(segment
		(start 69.1007 -180.79974)
		(end 69.1007 -181.6354)
		(width 0.508)
		(layer "F.Cu")
		(net "GND")
	)
	(segment
		(start 76.74991 -95.350076)
		(end 77.283818 -94.816168)
		(width 0.508)
		(layer "F.Cu")
		(net "GND")
	)
	(segment
		(start 224.249234 -60.899548)
		(end 224.249234 -61.917834)
		(width 0.254)
		(layer "F.Cu")
		(net "GND")
	)
	(segment
		(start 76.739496 -84.950046)
		(end 77.283818 -85.494368)
		(width 0.508)
		(layer "F.Cu")
		(net "GND")
	)
	(segment
		(start 185.200036 -65.499996)
		(end 185.201052 -65.499996)
		(width 0.254)
		(layer "F.Cu")
		(net "GND")
	)
	(segment
		(start 95.049848 -137.391648)
		(end 95.240348 -137.391648)
		(width 0.254)
		(layer "F.Cu")
		(net "GND")
	)
	(segment
		(start 94.869 -137.23747)
		(end 94.89567 -137.23747)
		(width 0.254)
		(layer "F.Cu")
		(net "GND")
	)
	(segment
		(start 62.5856 -152.781)
		(end 62.4586 -152.654)
		(width 0.254)
		(layer "F.Cu")
		(net "GND")
	)
	(segment
		(start 189.999874 -60.699904)
		(end 189.999874 -60.700412)
		(width 0.254)
		(layer "F.Cu")
		(net "GND")
	)
	(segment
		(start 194.799966 -55.900066)
		(end 194.399916 -56.300116)
		(width 0.254)
		(layer "F.Cu")
		(net "GND")
	)
	(segment
		(start 195.600066 -55.900066)
		(end 196.399912 -55.900066)
		(width 0.254)
		(layer "F.Cu")
		(net "GND")
	)
	(segment
		(start 125.6284 -7.62)
		(end 126.1618 -8.1534)
		(width 0.254)
		(layer "F.Cu")
		(net "GND")
	)
	(segment
		(start 193.200528 -71.099934)
		(end 193.600324 -70.700138)
		(width 0.254)
		(layer "F.Cu")
		(net "GND")
	)
	(segment
		(start 47.39513 -151.704802)
		(end 47.29988 -151.800052)
		(width 0.3556)
		(layer "F.Cu")
		(net "GND")
	)
	(segment
		(start 201.373994 -28.812744)
		(end 200.52665 -27.9654)
		(width 0.508)
		(layer "F.Cu")
		(net "GND")
	)
	(segment
		(start 88.9 -134.3533)
		(end 88.087962 -134.3533)
		(width 0.254)
		(layer "F.Cu")
		(net "GND")
	)
	(segment
		(start 193.999866 -54.299866)
		(end 193.60007 -53.90007)
		(width 0.254)
		(layer "F.Cu")
		(net "GND")
	)
	(segment
		(start 201.200004 -65.509394)
		(end 200.799954 -65.909444)
		(width 0.254)
		(layer "F.Cu")
		(net "GND")
	)
	(segment
		(start 31.4706 -165.4683)
		(end 31.4706 -166.497)
		(width 0.254)
		(layer "F.Cu")
		(net "GND")
	)
	(segment
		(start 197.200266 -59.900058)
		(end 197.600316 -60.300108)
		(width 0.254)
		(layer "F.Cu")
		(net "GND")
	)
	(segment
		(start 196.399912 -59.900058)
		(end 196.399912 -59.900566)
		(width 0.254)
		(layer "F.Cu")
		(net "GND")
	)
	(segment
		(start 46.900084 -144.199864)
		(end 47.29988 -144.59966)
		(width 0.3556)
		(layer "F.Cu")
		(net "GND")
	)
	(segment
		(start 180.6321 -45.0977)
		(end 180.6321 -44.2722)
		(width 0.508)
		(layer "F.Cu")
		(net "GND")
	)
	(segment
		(start 194.00012 -56.699912)
		(end 194.399916 -56.300116)
		(width 0.254)
		(layer "F.Cu")
		(net "GND")
	)
	(segment
		(start 76.1746 -168.143174)
		(end 75.3872 -168.930574)
		(width 0.508)
		(layer "F.Cu")
		(net "GND")
	)
	(segment
		(start 190.799974 -67.099942)
		(end 191.200278 -67.500246)
		(width 0.254)
		(layer "F.Cu")
		(net "GND")
	)
	(segment
		(start 197.999858 -72.701658)
		(end 198.3994 -73.1012)
		(width 0.254)
		(layer "F.Cu")
		(net "GND")
	)
	(segment
		(start 81.304892 -70.550024)
		(end 81.643728 -70.88886)
		(width 0.508)
		(layer "F.Cu")
		(net "GND")
	)
	(segment
		(start 185.200036 -67.100196)
		(end 185.60034 -67.5005)
		(width 0.254)
		(layer "F.Cu")
		(net "GND")
	)
	(segment
		(start 197.999858 -70.300342)
		(end 197.600062 -70.700138)
		(width 0.254)
		(layer "F.Cu")
		(net "GND")
	)
	(segment
		(start 75.475084 -84.950046)
		(end 76.739496 -84.950046)
		(width 0.508)
		(layer "F.Cu")
		(net "GND")
	)
	(segment
		(start 184.399936 -64.699896)
		(end 184.40019 -64.699896)
		(width 0.254)
		(layer "F.Cu")
		(net "GND")
	)
	(segment
		(start 186.800236 -63.09995)
		(end 187.200032 -63.499746)
		(width 0.254)
		(layer "F.Cu")
		(net "GND")
	)
	(segment
		(start 189.200028 -57.500012)
		(end 189.200282 -57.500012)
		(width 0.254)
		(layer "F.Cu")
		(net "GND")
	)
	(segment
		(start 79.925164 -68.149978)
		(end 79.925164 -68.150232)
		(width 0.254)
		(layer "F.Cu")
		(net "GND")
	)
	(segment
		(start 173.1645 -117.5385)
		(end 173.3296 -117.7036)
		(width 0.508)
		(layer "F.Cu")
		(net "GND")
	)
	(segment
		(start 197.999858 -60.699904)
		(end 198.000366 -60.699904)
		(width 0.254)
		(layer "F.Cu")
		(net "GND")
	)
	(segment
		(start 198.799958 -63.90005)
		(end 198.80326 -63.90005)
		(width 0.254)
		(layer "F.Cu")
		(net "GND")
	)
	(segment
		(start 193.999866 -70.299834)
		(end 193.999866 -70.29958)
		(width 0.254)
		(layer "F.Cu")
		(net "GND")
	)
	(segment
		(start 81.240122 -55.349902)
		(end 81.732628 -54.857396)
		(width 0.254)
		(layer "F.Cu")
		(net "GND")
	)
	(segment
		(start 180.1368 -141.069822)
		(end 180.456586 -140.750036)
		(width 0.508)
		(layer "F.Cu")
		(net "GND")
	)
	(segment
		(start 189.600078 -62.700154)
		(end 189.600078 -62.6999)
		(width 0.254)
		(layer "F.Cu")
		(net "GND")
	)
	(segment
		(start 16.834612 -144.56156)
		(end 16.834358 -144.56156)
		(width 0.3048)
		(layer "F.Cu")
		(net "GND")
	)
	(segment
		(start 23.234396 -146.961352)
		(end 23.634192 -146.561556)
		(width 0.254)
		(layer "F.Cu")
		(net "GND")
	)
	(segment
		(start 77.027278 -79.350108)
		(end 77.283818 -79.093568)
		(width 0.508)
		(layer "F.Cu")
		(net "GND")
	)
	(segment
		(start 196.399912 -60.699904)
		(end 196.399912 -60.69965)
		(width 0.254)
		(layer "F.Cu")
		(net "GND")
	)
	(segment
		(start 184.399936 -59.900058)
		(end 184.799986 -59.500008)
		(width 0.254)
		(layer "F.Cu")
		(net "GND")
	)
	(segment
		(start 198.80961 -69.499988)
		(end 199.20966 -69.099938)
		(width 0.254)
		(layer "F.Cu")
		(net "GND")
	)
	(segment
		(start 74.91984 -155.274518)
		(end 74.91984 -157.86862)
		(width 0.254)
		(layer "F.Cu")
		(net "GND")
	)
	(segment
		(start 187.600082 -63.09995)
		(end 187.600336 -63.09995)
		(width 0.254)
		(layer "F.Cu")
		(net "GND")
	)
	(segment
		(start 200.399904 -67.099942)
		(end 200.402952 -67.099942)
		(width 0.254)
		(layer "F.Cu")
		(net "GND")
	)
	(segment
		(start 49.699926 -142.999968)
		(end 49.699926 -143.800068)
		(width 0.3556)
		(layer "F.Cu")
		(net "GND")
	)
	(segment
		(start 227.546154 -61.277246)
		(end 226.682046 -61.277246)
		(width 0.254)
		(layer "F.Cu")
		(net "GND")
	)
	(segment
		(start 48.09998 -143.800068)
		(end 48.100234 -143.800068)
		(width 0.3556)
		(layer "F.Cu")
		(net "GND")
	)
	(segment
		(start 202.79995 -73.49998)
		(end 203.199746 -73.899776)
		(width 0.3048)
		(layer "F.Cu")
		(net "GND")
	)
	(segment
		(start 75.311 -148.7805)
		(end 74.4728 -148.7805)
		(width 0.508)
		(layer "F.Cu")
		(net "GND")
	)
	(segment
		(start 77.036168 -54.550056)
		(end 77.274928 -54.311296)
		(width 0.254)
		(layer "F.Cu")
		(net "GND")
	)
	(segment
		(start 201.200004 -57.500012)
		(end 201.200004 -57.499758)
		(width 0.254)
		(layer "F.Cu")
		(net "GND")
	)
	(segment
		(start 67.6656 -154.63266)
		(end 67.6656 -154.6606)
		(width 0.254)
		(layer "F.Cu")
		(net "GND")
	)
	(segment
		(start 48.099726 -146.19986)
		(end 48.09998 -146.19986)
		(width 0.3556)
		(layer "F.Cu")
		(net "GND")
	)
	(segment
		(start 50.935128 -166.916862)
		(end 50.935128 -167.292528)
		(width 0.508)
		(layer "F.Cu")
		(net "GND")
	)
	(segment
		(start 76.744576 -58.550048)
		(end 77.516228 -57.778396)
		(width 0.508)
		(layer "F.Cu")
		(net "GND")
	)
	(segment
		(start 47.115476 -142.815564)
		(end 47.29988 -142.999968)
		(width 0.3556)
		(layer "F.Cu")
		(net "GND")
	)
	(segment
		(start 98.9965 -144.399)
		(end 100.053394 -144.399)
		(width 0.508)
		(layer "F.Cu")
		(net "GND")
	)
	(segment
		(start 203.611734 -54.299866)
		(end 204.3684 -53.5432)
		(width 0.254)
		(layer "F.Cu")
		(net "GND")
	)
	(segment
		(start 189.999874 -63.09995)
		(end 189.600078 -62.700154)
		(width 0.254)
		(layer "F.Cu")
		(net "GND")
	)
	(segment
		(start 79.801974 -148.844)
		(end 79.808578 -148.844)
		(width 0.508)
		(layer "F.Cu")
		(net "GND")
	)
	(segment
		(start 186.799982 -58.299858)
		(end 186.80049 -58.299858)
		(width 0.254)
		(layer "F.Cu")
		(net "GND")
	)
	(segment
		(start 198.000366 -59.099958)
		(end 198.400162 -58.700162)
		(width 0.254)
		(layer "F.Cu")
		(net "GND")
	)
	(segment
		(start 202.79995 -70.299834)
		(end 203.199746 -70.69963)
		(width 0.3048)
		(layer "F.Cu")
		(net "GND")
	)
	(segment
		(start 192.800732 -76.294996)
		(end 193.195702 -75.900026)
		(width 0.3048)
		(layer "F.Cu")
		(net "GND")
	)
	(segment
		(start 42.900092 -144.999964)
		(end 43.299888 -145.39976)
		(width 0.3556)
		(layer "F.Cu")
		(net "GND")
	)
	(segment
		(start 49.699926 -145.400014)
		(end 48.899826 -145.400014)
		(width 0.3556)
		(layer "F.Cu")
		(net "GND")
	)
	(segment
		(start 189.200028 -69.499988)
		(end 189.600078 -69.900038)
		(width 0.254)
		(layer "F.Cu")
		(net "GND")
	)
	(segment
		(start 49.13503 -147.235164)
		(end 48.899826 -146.99996)
		(width 0.3556)
		(layer "F.Cu")
		(net "GND")
	)
	(segment
		(start 192.39992 -56.699912)
		(end 192.799716 -56.300116)
		(width 0.254)
		(layer "F.Cu")
		(net "GND")
	)
	(segment
		(start 205.583536 -122.1486)
		(end 205.583536 -123.185936)
		(width 0.508)
		(layer "F.Cu")
		(net "GND")
	)
	(segment
		(start 205.466442 -62.478666)
		(end 204.845158 -63.09995)
		(width 0.3048)
		(layer "F.Cu")
		(net "GND")
	)
	(segment
		(start 50.673 -131.3053)
		(end 51.6636 -131.3053)
		(width 0.508)
		(layer "F.Cu")
		(net "GND")
	)
	(segment
		(start 75.475084 -88.950038)
		(end 76.749148 -88.950038)
		(width 0.508)
		(layer "F.Cu")
		(net "GND")
	)
	(segment
		(start 47.29988 -150.999952)
		(end 47.39513 -151.095202)
		(width 0.3556)
		(layer "F.Cu")
		(net "GND")
	)
	(segment
		(start 183.60009 -62.29985)
		(end 183.60009 -62.300358)
		(width 0.254)
		(layer "F.Cu")
		(net "GND")
	)
	(segment
		(start 182.785004 -150.883366)
		(end 182.785004 -150.070566)
		(width 0.508)
		(layer "F.Cu")
		(net "GND")
	)
	(segment
		(start 201.200004 -65.499996)
		(end 201.200004 -65.509394)
		(width 0.254)
		(layer "F.Cu")
		(net "GND")
	)
	(segment
		(start 96.813624 -13.745464)
		(end 96.739202 -13.671042)
		(width 0.508)
		(layer "F.Cu")
		(net "GND")
	)
	(segment
		(start 89.027 -164.4904)
		(end 89.027 -164.1856)
		(width 0.254)
		(layer "F.Cu")
		(net "GND")
	)
	(segment
		(start 11.05154 -13.71092)
		(end 11.05154 -14.68374)
		(width 0.254)
		(layer "F.Cu")
		(net "GND")
	)
	(segment
		(start 198.799958 -59.099958)
		(end 198.400162 -58.700162)
		(width 0.254)
		(layer "F.Cu")
		(net "GND")
	)
	(segment
		(start 88.5825 -138.0363)
		(end 88.5825 -138.4554)
		(width 0.254)
		(layer "F.Cu")
		(net "GND")
	)
	(segment
		(start 42.500042 -141.400022)
		(end 42.099992 -141.800072)
		(width 0.3556)
		(layer "F.Cu")
		(net "GND")
	)
	(segment
		(start 183.60009 -60.699904)
		(end 183.60009 -60.700158)
		(width 0.254)
		(layer "F.Cu")
		(net "GND")
	)
	(segment
		(start 87.619332 -28.023312)
		(end 86.736936 -28.023312)
		(width 0.3048)
		(layer "F.Cu")
		(net "GND")
	)
	(segment
		(start 22.43455 -146.161506)
		(end 22.0345 -145.761456)
		(width 0.3048)
		(layer "F.Cu")
		(net "GND")
	)
	(segment
		(start 34.293048 -130.696208)
		(end 34.293048 -129.5908)
		(width 0.508)
		(layer "F.Cu")
		(net "GND")
	)
	(segment
		(start 77.029056 -92.14993)
		(end 77.283818 -91.895168)
		(width 0.508)
		(layer "F.Cu")
		(net "GND")
	)
	(segment
		(start 208.90738 -14.58595)
		(end 210.03895 -14.58595)
		(width 0.508)
		(layer "F.Cu")
		(net "GND")
	)
	(segment
		(start 47.29988 -148.60016)
		(end 47.699676 -148.999956)
		(width 0.3556)
		(layer "F.Cu")
		(net "GND")
	)
	(segment
		(start 185.200036 -61.500004)
		(end 185.60034 -61.900308)
		(width 0.254)
		(layer "F.Cu")
		(net "GND")
	)
	(segment
		(start 187.600082 -66.299842)
		(end 187.600082 -67.099942)
		(width 0.254)
		(layer "F.Cu")
		(net "GND")
	)
	(segment
		(start 202.79995 -69.499988)
		(end 202.79995 -69.496178)
		(width 0.3048)
		(layer "F.Cu")
		(net "GND")
	)
	(segment
		(start 193.999866 -65.499996)
		(end 194.399916 -65.900046)
		(width 0.254)
		(layer "F.Cu")
		(net "GND")
	)
	(segment
		(start 95.254572 -12.502642)
		(end 96.776032 -12.502642)
		(width 0.508)
		(layer "F.Cu")
		(net "GND")
	)
	(segment
		(start 196.491098 -75.099926)
		(end 196.597524 -75.206352)
		(width 0.3048)
		(layer "F.Cu")
		(net "GND")
	)
	(segment
		(start 16.458184 -164.5539)
		(end 16.458184 -165.327584)
		(width 0.508)
		(layer "F.Cu")
		(net "GND")
	)
	(segment
		(start 16.834612 -145.36166)
		(end 17.234662 -145.76171)
		(width 0.3048)
		(layer "F.Cu")
		(net "GND")
	)
	(segment
		(start 192.800224 -64.3001)
		(end 193.20002 -64.699896)
		(width 0.254)
		(layer "F.Cu")
		(net "GND")
	)
	(segment
		(start 50.499772 -150.199852)
		(end 50.500026 -150.199852)
		(width 0.3556)
		(layer "F.Cu")
		(net "GND")
	)
	(segment
		(start 184.40019 -66.299842)
		(end 184.799986 -65.900046)
		(width 0.254)
		(layer "F.Cu")
		(net "GND")
	)
	(segment
		(start 186.800236 -71.900034)
		(end 187.200286 -71.499984)
		(width 0.254)
		(layer "F.Cu")
		(net "GND")
	)
	(segment
		(start 11.04392 -13.7033)
		(end 11.05154 -13.71092)
		(width 0.254)
		(layer "F.Cu")
		(net "GND")
	)
	(segment
		(start 188.399928 -70.299834)
		(end 188.000132 -69.900038)
		(width 0.254)
		(layer "F.Cu")
		(net "GND")
	)
	(segment
		(start 192.39992 -60.699904)
		(end 192.800224 -61.100208)
		(width 0.254)
		(layer "F.Cu")
		(net "GND")
	)
	(segment
		(start 193.20002 -60.699904)
		(end 193.20002 -60.700412)
		(width 0.254)
		(layer "F.Cu")
		(net "GND")
	)
	(segment
		(start 32.867346 -124.535946)
		(end 32.05099 -124.535946)
		(width 0.508)
		(layer "F.Cu")
		(net "GND")
	)
	(segment
		(start 77.100684 -63.35014)
		(end 77.490828 -62.959996)
		(width 0.254)
		(layer "F.Cu")
		(net "GND")
	)
	(segment
		(start 185.999882 -60.699904)
		(end 186.400186 -61.100208)
		(width 0.254)
		(layer "F.Cu")
		(net "GND")
	)
	(segment
		(start 192.39992 -70.29704)
		(end 192.793874 -69.903086)
		(width 0.254)
		(layer "F.Cu")
		(net "GND")
	)
	(segment
		(start 89.027 -164.1856)
		(end 89.65692 -163.55568)
		(width 0.254)
		(layer "F.Cu")
		(net "GND")
	)
	(segment
		(start 49.464722 -147.235164)
		(end 49.13503 -147.235164)
		(width 0.3556)
		(layer "F.Cu")
		(net "GND")
	)
	(segment
		(start 51.699668 -149.799802)
		(end 51.299872 -149.400006)
		(width 0.3556)
		(layer "F.Cu")
		(net "GND")
	)
	(segment
		(start 186.000136 -67.900042)
		(end 186.399932 -68.299838)
		(width 0.254)
		(layer "F.Cu")
		(net "GND")
	)
	(segment
		(start 76.747624 -76.149962)
		(end 77.283818 -75.613768)
		(width 0.508)
		(layer "F.Cu")
		(net "GND")
	)
	(segment
		(start 79.925164 -54.550056)
		(end 81.425288 -54.550056)
		(width 0.254)
		(layer "F.Cu")
		(net "GND")
	)
	(segment
		(start 90.59672 -148.333968)
		(end 90.173048 -147.910296)
		(width 0.508)
		(layer "F.Cu")
		(net "GND")
	)
	(segment
		(start 186.000136 -71.099934)
		(end 186.400186 -70.699884)
		(width 0.254)
		(layer "F.Cu")
		(net "GND")
	)
	(segment
		(start 55.0926 -130.102864)
		(end 55.604664 -130.102864)
		(width 0.254)
		(layer "F.Cu")
		(net "GND")
	)
	(segment
		(start 193.20002 -61.500004)
		(end 192.800224 -61.100208)
		(width 0.254)
		(layer "F.Cu")
		(net "GND")
	)
	(segment
		(start 199.600058 -61.509402)
		(end 199.206358 -61.903102)
		(width 0.254)
		(layer "F.Cu")
		(net "GND")
	)
	(segment
		(start 47.699676 -153.000202)
		(end 47.29988 -153.399998)
		(width 0.254)
		(layer "F.Cu")
		(net "GND")
	)
	(segment
		(start 185.999882 -67.099942)
		(end 186.000136 -67.099942)
		(width 0.254)
		(layer "F.Cu")
		(net "GND")
	)
	(segment
		(start 23.234142 -142.961614)
		(end 22.834346 -143.36141)
		(width 0.3048)
		(layer "F.Cu")
		(net "GND")
	)
	(segment
		(start 49.699926 -143.800068)
		(end 49.699672 -143.800068)
		(width 0.3556)
		(layer "F.Cu")
		(net "GND")
	)
	(segment
		(start 199.606408 -71.099934)
		(end 200.004426 -70.701916)
		(width 0.254)
		(layer "F.Cu")
		(net "GND")
	)
	(segment
		(start 189.600078 -62.6999)
		(end 189.200028 -62.29985)
		(width 0.254)
		(layer "F.Cu")
		(net "GND")
	)
	(segment
		(start 81.259934 -64.950086)
		(end 81.584038 -64.625982)
		(width 0.508)
		(layer "F.Cu")
		(net "GND")
	)
	(segment
		(start 87.67445 -29.83484)
		(end 86.45779 -29.83484)
		(width 0.508)
		(layer "F.Cu")
		(net "GND")
	)
	(segment
		(start 122.184668 -17.265142)
		(end 121.84761 -17.6022)
		(width 0.508)
		(layer "F.Cu")
		(net "GND")
	)
	(segment
		(start 26.2636 -139.761468)
		(end 26.993088 -139.03198)
		(width 0.3048)
		(layer "F.Cu")
		(net "GND")
	)
	(segment
		(start 49.299368 -141.00048)
		(end 48.899826 -141.400022)
		(width 0.254)
		(layer "F.Cu")
		(net "GND")
	)
	(segment
		(start 156.224478 -87.936578)
		(end 156.224478 -88.853264)
		(width 0.254)
		(layer "F.Cu")
		(net "GND")
	)
	(segment
		(start 187.600336 -71.099934)
		(end 187.600082 -71.099934)
		(width 0.254)
		(layer "F.Cu")
		(net "GND")
	)
	(segment
		(start 185.201052 -65.499996)
		(end 185.60034 -65.100708)
		(width 0.254)
		(layer "F.Cu")
		(net "GND")
	)
	(segment
		(start 54.288436 -124.5362)
		(end 56.012334 -124.5362)
		(width 0.254)
		(layer "F.Cu")
		(net "GND")
	)
	(segment
		(start 80.13446 -172.3136)
		(end 79.98968 -172.45838)
		(width 0.254)
		(layer "F.Cu")
		(net "GND")
	)
	(segment
		(start 81.344008 -74.550016)
		(end 81.758028 -74.135996)
		(width 0.508)
		(layer "F.Cu")
		(net "GND")
	)
	(segment
		(start 203.191872 -69.101208)
		(end 203.191872 -69.09181)
		(width 0.3048)
		(layer "F.Cu")
		(net "GND")
	)
	(segment
		(start 201.200258 -75.900026)
		(end 201.200004 -75.900026)
		(width 0.3048)
		(layer "F.Cu")
		(net "GND")
	)
	(segment
		(start 197.999858 -59.099958)
		(end 198.000366 -59.099958)
		(width 0.254)
		(layer "F.Cu")
		(net "GND")
	)
	(segment
		(start 191.600074 -71.099934)
		(end 191.200024 -70.699884)
		(width 0.254)
		(layer "F.Cu")
		(net "GND")
	)
	(segment
		(start 193.20002 -53.50002)
		(end 193.60007 -53.90007)
		(width 0.254)
		(layer "F.Cu")
		(net "GND")
	)
	(segment
		(start 81.4705 -149.08276)
		(end 80.040734 -149.08276)
		(width 0.381)
		(layer "F.Cu")
		(net "GND")
	)
	(segment
		(start 189.200028 -67.099942)
		(end 189.200028 -67.10934)
		(width 0.254)
		(layer "F.Cu")
		(net "GND")
	)
	(segment
		(start 74.1553 -149.098)
		(end 74.3839 -148.8694)
		(width 0.508)
		(layer "F.Cu")
		(net "GND")
	)
	(segment
		(start 195.600066 -71.900034)
		(end 195.600066 -71.898256)
		(width 0.254)
		(layer "F.Cu")
		(net "GND")
	)
	(segment
		(start 203.60005 -75.900026)
		(end 203.60005 -76.699872)
		(width 0.3048)
		(layer "F.Cu")
		(net "GND")
	)
	(segment
		(start 187.600082 -67.099942)
		(end 187.600336 -67.099942)
		(width 0.254)
		(layer "F.Cu")
		(net "GND")
	)
	(segment
		(start 185.200036 -59.099958)
		(end 185.200036 -59.100212)
		(width 0.254)
		(layer "F.Cu")
		(net "GND")
	)
	(segment
		(start 46.500288 -146.19986)
		(end 46.900084 -145.800064)
		(width 0.3556)
		(layer "F.Cu")
		(net "GND")
	)
	(segment
		(start 22.43455 -145.36166)
		(end 22.834346 -145.761456)
		(width 0.3048)
		(layer "F.Cu")
		(net "GND")
	)
	(segment
		(start 227.1903 -56.1721)
		(end 227.9142 -56.896)
		(width 0.254)
		(layer "F.Cu")
		(net "GND")
	)
	(segment
		(start 33.5534 -125.222)
		(end 32.867346 -124.535946)
		(width 0.508)
		(layer "F.Cu")
		(net "GND")
	)
	(segment
		(start 191.708024 -69.499988)
		(end 191.793876 -69.58584)
		(width 0.254)
		(layer "F.Cu")
		(net "GND")
	)
	(segment
		(start 93.124528 -49.873916)
		(end 93.124528 -51.105816)
		(width 0.254)
		(layer "F.Cu")
		(net "GND")
	)
	(segment
		(start 76.1746 -148.7805)
		(end 76.6699 -148.7805)
		(width 0.508)
		(layer "F.Cu")
		(net "GND")
	)
	(segment
		(start 189.200028 -70.299834)
		(end 189.200282 -70.299834)
		(width 0.254)
		(layer "F.Cu")
		(net "GND")
	)
	(segment
		(start 77.150214 -158.867602)
		(end 77.150214 -159.729678)
		(width 0.254)
		(layer "F.Cu")
		(net "GND")
	)
	(segment
		(start 56.19115 -124.5362)
		(end 56.012334 -124.5362)
		(width 0.254)
		(layer "F.Cu")
		(net "GND")
	)
	(segment
		(start 185.200036 -60.699904)
		(end 185.200036 -60.700158)
		(width 0.254)
		(layer "F.Cu")
		(net "GND")
	)
	(segment
		(start 181.882796 -62.29985)
		(end 181.99989 -62.29985)
		(width 0.254)
		(layer "F.Cu")
		(net "GND")
	)
	(segment
		(start 194.399916 -62.6999)
		(end 193.999866 -62.29985)
		(width 0.254)
		(layer "F.Cu")
		(net "GND")
	)
	(segment
		(start 225.691954 -58.666888)
		(end 225.691954 -57.568846)
		(width 0.254)
		(layer "F.Cu")
		(net "GND")
	)
	(segment
		(start 220.726 -102.4636)
		(end 221.6785 -102.4636)
		(width 0.508)
		(layer "F.Cu")
		(net "GND")
	)
	(segment
		(start 22.834854 -148.962364)
		(end 22.834854 -149.216364)
		(width 0.3048)
		(layer "F.Cu")
		(net "GND")
	)
	(segment
		(start 186.80049 -59.900058)
		(end 187.200286 -59.500262)
		(width 0.254)
		(layer "F.Cu")
		(net "GND")
	)
	(segment
		(start 201.99985 -59.900058)
		(end 201.600054 -60.299854)
		(width 0.254)
		(layer "F.Cu")
		(net "GND")
	)
	(segment
		(start 199.600058 -63.90005)
		(end 199.600058 -63.909448)
		(width 0.254)
		(layer "F.Cu")
		(net "GND")
	)
	(segment
		(start 200.402952 -67.099942)
		(end 200.796652 -67.493642)
		(width 0.254)
		(layer "F.Cu")
		(net "GND")
	)
	(segment
		(start 186.799982 -63.09995)
		(end 186.800236 -63.09995)
		(width 0.254)
		(layer "F.Cu")
		(net "GND")
	)
	(segment
		(start 188.000386 -70.69963)
		(end 187.600336 -71.09968)
		(width 0.254)
		(layer "F.Cu")
		(net "GND")
	)
	(segment
		(start 197.999858 -68.699888)
		(end 197.999858 -68.70954)
		(width 0.254)
		(layer "F.Cu")
		(net "GND")
	)
	(segment
		(start 201.99477 -61.500004)
		(end 201.592688 -61.902086)
		(width 0.254)
		(layer "F.Cu")
		(net "GND")
	)
	(segment
		(start 185.999882 -72.69988)
		(end 186.799982 -73.49998)
		(width 0.254)
		(layer "F.Cu")
		(net "GND")
	)
	(segment
		(start 34.791396 -136.73709)
		(end 34.791396 -135.953754)
		(width 0.254)
		(layer "F.Cu")
		(net "GND")
	)
	(segment
		(start 189.999874 -71.099934)
		(end 190.399924 -70.699884)
		(width 0.254)
		(layer "F.Cu")
		(net "GND")
	)
	(segment
		(start 203.199746 -73.899776)
		(end 203.599542 -73.49998)
		(width 0.3556)
		(layer "F.Cu")
		(net "GND")
	)
	(segment
		(start 81.16443 -96.149922)
		(end 81.585308 -95.729044)
		(width 0.254)
		(layer "F.Cu")
		(net "GND")
	)
	(segment
		(start 29.367226 -179.57673)
		(end 28.64993 -179.57673)
		(width 0.508)
		(layer "F.Cu")
		(net "GND")
	)
	(segment
		(start 96.739202 -13.671042)
		(end 95.254572 -13.671042)
		(width 0.508)
		(layer "F.Cu")
		(net "GND")
	)
	(segment
		(start 74.934572 -168.041828)
		(end 74.934572 -168.477946)
		(width 0.508)
		(layer "F.Cu")
		(net "GND")
	)
	(segment
		(start 99.3521 -155.0162)
		(end 99.3521 -155.810966)
		(width 0.508)
		(layer "F.Cu")
		(net "GND")
	)
	(segment
		(start 181.99989 -62.290452)
		(end 182.394606 -61.895736)
		(width 0.254)
		(layer "F.Cu")
		(net "GND")
	)
	(segment
		(start 191.600074 -60.699904)
		(end 191.600074 -60.700412)
		(width 0.254)
		(layer "F.Cu")
		(net "GND")
	)
	(segment
		(start 68.3514 -144.0942)
		(end 67.6529 -144.0942)
		(width 0.254)
		(layer "F.Cu")
		(net "GND")
	)
	(segment
		(start 198.799958 -67.099942)
		(end 199.600058 -67.900042)
		(width 0.254)
		(layer "F.Cu")
		(net "GND")
	)
	(segment
		(start 185.200036 -63.90005)
		(end 185.200036 -63.900304)
		(width 0.254)
		(layer "F.Cu")
		(net "GND")
	)
	(segment
		(start 200.579736 -74.565764)
		(end 200.399904 -74.385932)
		(width 0.254)
		(layer "F.Cu")
		(net "GND")
	)
	(segment
		(start 40.099996 -148.599906)
		(end 39.699946 -148.999956)
		(width 0.3048)
		(layer "F.Cu")
		(net "GND")
	)
	(segment
		(start 74.8919 -133.2865)
		(end 74.8919 -132.743702)
		(width 0.508)
		(layer "F.Cu")
		(net "GND")
	)
	(segment
		(start 61.6458 -131.74218)
		(end 61.976 -131.74218)
		(width 0.508)
		(layer "F.Cu")
		(net "GND")
	)
	(segment
		(start 194.799966 -70.29958)
		(end 194.400424 -69.900038)
		(width 0.254)
		(layer "F.Cu")
		(net "GND")
	)
	(segment
		(start 194.799966 -70.299834)
		(end 194.799966 -70.29958)
		(width 0.254)
		(layer "F.Cu")
		(net "GND")
	)
	(segment
		(start 91.195144 -162.52952)
		(end 91.195144 -161.5186)
		(width 0.254)
		(layer "F.Cu")
		(net "GND")
	)
	(segment
		(start 187.600336 -62.29985)
		(end 188.000132 -62.699646)
		(width 0.254)
		(layer "F.Cu")
		(net "GND")
	)
	(segment
		(start 55.0164 -167.2336)
		(end 54.9656 -167.2336)
		(width 0.254)
		(layer "F.Cu")
		(net "GND")
	)
	(segment
		(start 190.799974 -75.900026)
		(end 191.600074 -75.099926)
		(width 0.3048)
		(layer "F.Cu")
		(net "GND")
	)
	(segment
		(start 202.795378 -67.099942)
		(end 202.392788 -66.697352)
		(width 0.254)
		(layer "F.Cu")
		(net "GND")
	)
	(segment
		(start 89.809574 -132.506974)
		(end 89.7382 -132.4356)
		(width 0.508)
		(layer "F.Cu")
		(net "GND")
	)
	(segment
		(start 191.642746 -46.278546)
		(end 191.4652 -46.101)
		(width 0.508)
		(layer "F.Cu")
		(net "GND")
	)
	(segment
		(start 193.999866 -55.099966)
		(end 193.60007 -54.70017)
		(width 0.254)
		(layer "F.Cu")
		(net "GND")
	)
	(segment
		(start 94.46895 -146.528028)
		(end 94.46895 -146.651218)
		(width 0.254)
		(layer "F.Cu")
		(net "GND")
	)
	(segment
		(start 191.516 -47.9425)
		(end 191.516 -47.244)
		(width 0.508)
		(layer "F.Cu")
		(net "GND")
	)
	(segment
		(start 188.399928 -73.49998)
		(end 188.799724 -73.899776)
		(width 0.3048)
		(layer "F.Cu")
		(net "GND")
	)
	(segment
		(start 75.475084 -69.749924)
		(end 76.751942 -69.749924)
		(width 0.508)
		(layer "F.Cu")
		(net "GND")
	)
	(segment
		(start 182.790338 -61.500004)
		(end 182.394606 -61.895736)
		(width 0.254)
		(layer "F.Cu")
		(net "GND")
	)
	(segment
		(start 198.799958 -66.299842)
		(end 198.799958 -66.298064)
		(width 0.254)
		(layer "F.Cu")
		(net "GND")
	)
	(segment
		(start 197.200012 -61.500004)
		(end 197.999858 -61.500004)
		(width 0.254)
		(layer "F.Cu")
		(net "GND")
	)
	(segment
		(start 194.799966 -58.299858)
		(end 194.40017 -57.900062)
		(width 0.254)
		(layer "F.Cu")
		(net "GND")
	)
	(segment
		(start 189.80023 -71.817484)
		(end 189.88278 -71.900034)
		(width 0.254)
		(layer "F.Cu")
		(net "GND")
	)
	(segment
		(start 197.999858 -73.49998)
		(end 198.00062 -73.49998)
		(width 0.254)
		(layer "F.Cu")
		(net "GND")
	)
	(segment
		(start 77.017626 -94.549976)
		(end 77.283818 -94.816168)
		(width 0.508)
		(layer "F.Cu")
		(net "GND")
	)
	(segment
		(start 197.199758 -56.699912)
		(end 196.800216 -56.30037)
		(width 0.254)
		(layer "F.Cu")
		(net "GND")
	)
	(segment
		(start 199.600058 -63.909448)
		(end 199.206358 -64.303148)
		(width 0.254)
		(layer "F.Cu")
		(net "GND")
	)
	(segment
		(start 83.473544 -132.72135)
		(end 83.57489 -132.620004)
		(width 0.508)
		(layer "F.Cu")
		(net "GND")
	)
	(segment
		(start 202.392788 -66.697352)
		(end 201.99985 -66.304414)
		(width 0.254)
		(layer "F.Cu")
		(net "GND")
	)
	(segment
		(start 198.80961 -63.09995)
		(end 199.206358 -62.703202)
		(width 0.254)
		(layer "F.Cu")
		(net "GND")
	)
	(segment
		(start 37.680646 -176.69891)
		(end 37.655246 -176.72431)
		(width 0.508)
		(layer "F.Cu")
		(net "GND")
	)
	(segment
		(start 194.799966 -75.099926)
		(end 194.682872 -75.21702)
		(width 0.254)
		(layer "F.Cu")
		(net "GND")
	)
	(segment
		(start 201.200004 -59.099958)
		(end 201.5998 -58.700162)
		(width 0.254)
		(layer "F.Cu")
		(net "GND")
	)
	(segment
		(start 186.800236 -67.099942)
		(end 187.200032 -67.499738)
		(width 0.254)
		(layer "F.Cu")
		(net "GND")
	)
	(segment
		(start 193.20002 -58.299858)
		(end 193.999866 -58.299858)
		(width 0.254)
		(layer "F.Cu")
		(net "GND")
	)
	(segment
		(start 187.990988 -61.8998)
		(end 188.390784 -61.500004)
		(width 0.254)
		(layer "F.Cu")
		(net "GND")
	)
	(segment
		(start 186.000136 -62.29985)
		(end 186.399932 -62.699646)
		(width 0.254)
		(layer "F.Cu")
		(net "GND")
	)
	(segment
		(start 201.1934 -68.699888)
		(end 200.791826 -69.101462)
		(width 0.254)
		(layer "F.Cu")
		(net "GND")
	)
	(segment
		(start 95.0087 -15.8115)
		(end 94.488 -15.8115)
		(width 0.4064)
		(layer "F.Cu")
		(net "GND")
	)
	(segment
		(start 21.492464 -15.41145)
		(end 21.492464 -16.373856)
		(width 0.508)
		(layer "F.Cu")
		(net "GND")
	)
	(segment
		(start 188.399928 -71.900034)
		(end 188.399928 -71.899526)
		(width 0.254)
		(layer "F.Cu")
		(net "GND")
	)
	(segment
		(start 183.60009 -57.500012)
		(end 183.60009 -57.499758)
		(width 0.254)
		(layer "F.Cu")
		(net "GND")
	)
	(segment
		(start 90.4748 -163.599876)
		(end 90.4748 -163.249864)
		(width 0.254)
		(layer "F.Cu")
		(net "GND")
	)
	(segment
		(start 69.7738 -118.2116)
		(end 69.977 -118.4148)
		(width 0.508)
		(layer "F.Cu")
		(net "GND")
	)
	(segment
		(start 206.1845 -82.55)
		(end 205.8162 -82.9183)
		(width 0.254)
		(layer "F.Cu")
		(net "GND")
	)
	(segment
		(start 42.099992 -148.199856)
		(end 42.499788 -147.80006)
		(width 0.3556)
		(layer "F.Cu")
		(net "GND")
	)
	(segment
		(start 204.642974 -59.099958)
		(end 204.399896 -59.099958)
		(width 0.254)
		(layer "F.Cu")
		(net "GND")
	)
	(segment
		(start 193.08191 -71.099934)
		(end 193.20002 -71.099934)
		(width 0.254)
		(layer "F.Cu")
		(net "GND")
	)
	(segment
		(start 75.475084 -58.550048)
		(end 76.744576 -58.550048)
		(width 0.508)
		(layer "F.Cu")
		(net "GND")
	)
	(segment
		(start 200.399904 -67.89039)
		(end 200.796652 -67.493642)
		(width 0.254)
		(layer "F.Cu")
		(net "GND")
	)
	(segment
		(start 193.20002 -74.306684)
		(end 193.591942 -74.698606)
		(width 0.254)
		(layer "F.Cu")
		(net "GND")
	)
	(segment
		(start 195.600066 -60.699904)
		(end 195.600574 -60.699904)
		(width 0.254)
		(layer "F.Cu")
		(net "GND")
	)
	(segment
		(start 17.634458 -146.161506)
		(end 17.634712 -146.161506)
		(width 0.3048)
		(layer "F.Cu")
		(net "GND")
	)
	(segment
		(start 190.800228 -69.499988)
		(end 191.200278 -69.900038)
		(width 0.254)
		(layer "F.Cu")
		(net "GND")
	)
	(segment
		(start 95.3008 -16.1036)
		(end 95.0087 -15.8115)
		(width 0.4064)
		(layer "F.Cu")
		(net "GND")
	)
	(segment
		(start 202.600052 -56.782716)
		(end 202.682856 -56.699912)
		(width 0.254)
		(layer "F.Cu")
		(net "GND")
	)
	(segment
		(start 191.600074 -59.900058)
		(end 191.600328 -59.900058)
		(width 0.254)
		(layer "F.Cu")
		(net "GND")
	)
	(segment
		(start 53.773324 -162.926268)
		(end 53.773324 -163.918646)
		(width 0.508)
		(layer "F.Cu")
		(net "GND")
	)
	(segment
		(start 34.5694 -165.4683)
		(end 34.5694 -166.7002)
		(width 0.508)
		(layer "F.Cu")
		(net "GND")
	)
	(segment
		(start 206.5401 -133.922516)
		(end 206.5401 -135.4963)
		(width 0.508)
		(layer "F.Cu")
		(net "GND")
	)
	(segment
		(start 201.200004 -68.699888)
		(end 201.1934 -68.699888)
		(width 0.254)
		(layer "F.Cu")
		(net "GND")
	)
	(segment
		(start 193.999866 -69.499988)
		(end 193.999866 -69.500496)
		(width 0.254)
		(layer "F.Cu")
		(net "GND")
	)
	(segment
		(start 90.4748 -163.249864)
		(end 91.195144 -162.52952)
		(width 0.254)
		(layer "F.Cu")
		(net "GND")
	)
	(segment
		(start 192.39992 -63.90005)
		(end 192.400174 -63.90005)
		(width 0.254)
		(layer "F.Cu")
		(net "GND")
	)
	(segment
		(start 19.0627 -145.36166)
		(end 19.100038 -145.398998)
		(width 0.254)
		(layer "F.Cu")
		(net "GND")
	)
	(segment
		(start 205.096872 -59.553856)
		(end 204.642974 -59.099958)
		(width 0.254)
		(layer "F.Cu")
		(net "GND")
	)
	(segment
		(start 29.4894 -129.921)
		(end 30.3276 -129.921)
		(width 0.381)
		(layer "F.Cu")
		(net "GND")
	)
	(segment
		(start 67.7672 -170.4467)
		(end 67.7672 -171.437046)
		(width 0.508)
		(layer "F.Cu")
		(net "GND")
	)
	(segment
		(start 197.200012 -56.699912)
		(end 197.199758 -56.699912)
		(width 0.254)
		(layer "F.Cu")
		(net "GND")
	)
	(segment
		(start 197.200012 -67.900042)
		(end 197.209156 -67.900042)
		(width 0.254)
		(layer "F.Cu")
		(net "GND")
	)
	(segment
		(start 23.234396 -145.36166)
		(end 23.234396 -145.362422)
		(width 0.3048)
		(layer "F.Cu")
		(net "GND")
	)
	(segment
		(start 79.925164 -64.950086)
		(end 81.259934 -64.950086)
		(width 0.508)
		(layer "F.Cu")
		(net "GND")
	)
	(segment
		(start 79.808578 -148.844)
		(end 80.43672 -148.215858)
		(width 0.508)
		(layer "F.Cu")
		(net "GND")
	)
	(segment
		(start 81.439766 -132.07746)
		(end 81.364074 -132.07746)
		(width 0.3556)
		(layer "F.Cu")
		(net "GND")
	)
	(segment
		(start 189.999874 -59.099958)
		(end 190.000128 -59.099958)
		(width 0.254)
		(layer "F.Cu")
		(net "GND")
	)
	(segment
		(start 193.20002 -55.099966)
		(end 193.200274 -55.099966)
		(width 0.254)
		(layer "F.Cu")
		(net "GND")
	)
	(segment
		(start 185.999882 -70.299834)
		(end 186.000136 -70.299834)
		(width 0.254)
		(layer "F.Cu")
		(net "GND")
	)
	(segment
		(start 95.10522 -180.66004)
		(end 95.590868 -180.66004)
		(width 0.4318)
		(layer "F.Cu")
		(net "GND")
	)
	(segment
		(start 183.60009 -63.90005)
		(end 183.20004 -64.3001)
		(width 0.254)
		(layer "F.Cu")
		(net "GND")
	)
	(segment
		(start 192.39992 -65.499996)
		(end 192.39992 -65.50914)
		(width 0.254)
		(layer "F.Cu")
		(net "GND")
	)
	(segment
		(start 197.200012 -75.099926)
		(end 197.290944 -75.099926)
		(width 0.3048)
		(layer "F.Cu")
		(net "GND")
	)
	(segment
		(start 203.599542 -73.49998)
		(end 203.60005 -73.49998)
		(width 0.3556)
		(layer "F.Cu")
		(net "GND")
	)
	(segment
		(start 198.399908 -75.499976)
		(end 197.999858 -75.099926)
		(width 0.3048)
		(layer "F.Cu")
		(net "GND")
	)
	(segment
		(start 155.7401 -87.4522)
		(end 156.224478 -87.936578)
		(width 0.254)
		(layer "F.Cu")
		(net "GND")
	)
	(segment
		(start 197.200012 -63.90005)
		(end 197.999858 -63.90005)
		(width 0.254)
		(layer "F.Cu")
		(net "GND")
	)
	(segment
		(start 193.993262 -75.099926)
		(end 193.591942 -74.698606)
		(width 0.254)
		(layer "F.Cu")
		(net "GND")
	)
	(segment
		(start 224.3074 -56.1721)
		(end 225.1202 -56.1721)
		(width 0.254)
		(layer "F.Cu")
		(net "GND")
	)
	(segment
		(start 77.035152 -53.749956)
		(end 75.475084 -53.749956)
		(width 0.254)
		(layer "F.Cu")
		(net "GND")
	)
	(segment
		(start 94.361 -161.6456)
		(end 95.0468 -162.3314)
		(width 0.508)
		(layer "F.Cu")
		(net "GND")
	)
	(segment
		(start 199.600058 -66.299842)
		(end 199.600058 -66.290444)
		(width 0.254)
		(layer "F.Cu")
		(net "GND")
	)
	(segment
		(start 228.731826 -76.019914)
		(end 228.909626 -76.019914)
		(width 0.508)
		(layer "F.Cu")
		(net "GND")
	)
	(segment
		(start 199.600058 -72.69988)
		(end 199.590406 -72.69988)
		(width 0.254)
		(layer "F.Cu")
		(net "GND")
	)
	(segment
		(start 91.805506 -129.506726)
		(end 90.795348 -129.506726)
		(width 0.254)
		(layer "F.Cu")
		(net "GND")
	)
	(segment
		(start 184.40019 -64.699896)
		(end 184.799986 -64.3001)
		(width 0.254)
		(layer "F.Cu")
		(net "GND")
	)
	(segment
		(start 185.999882 -59.099958)
		(end 186.400186 -59.500262)
		(width 0.254)
		(layer "F.Cu")
		(net "GND")
	)
	(segment
		(start 176.9237 -61.3537)
		(end 176.9364 -61.341)
		(width 0.508)
		(layer "F.Cu")
		(net "GND")
	)
	(segment
		(start 195.600066 -68.699888)
		(end 196.399912 -68.699888)
		(width 0.254)
		(layer "F.Cu")
		(net "GND")
	)
	(segment
		(start 74.880216 -175.76165)
		(end 74.880216 -176.581816)
		(width 0.508)
		(layer "F.Cu")
		(net "GND")
	)
	(segment
		(start 61.976 -131.74218)
		(end 62.484 -131.23418)
		(width 0.508)
		(layer "F.Cu")
		(net "GND")
	)
	(segment
		(start 197.999858 -66.299842)
		(end 197.999858 -66.297048)
		(width 0.254)
		(layer "F.Cu")
		(net "GND")
	)
	(segment
		(start 91.208352 -132.506974)
		(end 89.809574 -132.506974)
		(width 0.508)
		(layer "F.Cu")
		(net "GND")
	)
	(segment
		(start 48.703484 -167.1066)
		(end 48.195484 -167.6146)
		(width 0.508)
		(layer "F.Cu")
		(net "GND")
	)
	(segment
		(start 202.79995 -65.499996)
		(end 202.795378 -65.499996)
		(width 0.3048)
		(layer "F.Cu")
		(net "GND")
	)
	(segment
		(start 121.925334 -10.241534)
		(end 121.3485 -10.241534)
		(width 0.254)
		(layer "F.Cu")
		(net "GND")
	)
	(segment
		(start 58.50001 -172.699934)
		(end 59.7154 -172.699934)
		(width 0.508)
		(layer "F.Cu")
		(net "GND")
	)
	(segment
		(start 77.827378 -52.338478)
		(end 78.43901 -52.95011)
		(width 0.508)
		(layer "F.Cu")
		(net "GND")
	)
	(segment
		(start 89.51214 -170.80484)
		(end 91.007184 -170.80484)
		(width 0.3556)
		(layer "F.Cu")
		(net "GND")
	)
	(segment
		(start 202.79995 -74.299572)
		(end 203.199746 -73.899776)
		(width 0.3048)
		(layer "F.Cu")
		(net "GND")
	)
	(segment
		(start 16.833342 -136.561576)
		(end 16.3576 -136.906)
		(width 0.3048)
		(layer "F.Cu")
		(net "GND")
	)
	(segment
		(start 50.099722 -150.599902)
		(end 50.499772 -150.199852)
		(width 0.3556)
		(layer "F.Cu")
		(net "GND")
	)
	(segment
		(start 193.20002 -75.900026)
		(end 192.39992 -75.099926)
		(width 0.3048)
		(layer "F.Cu")
		(net "GND")
	)
	(segment
		(start 186.799982 -71.099934)
		(end 186.799982 -71.09968)
		(width 0.254)
		(layer "F.Cu")
		(net "GND")
	)
	(segment
		(start 195.600066 -71.099934)
		(end 195.590668 -71.099934)
		(width 0.254)
		(layer "F.Cu")
		(net "GND")
	)
	(segment
		(start 189.200028 -67.10934)
		(end 189.593982 -67.503294)
		(width 0.254)
		(layer "F.Cu")
		(net "GND")
	)
	(segment
		(start 36.7792 -166.0017)
		(end 36.7792 -167.1066)
		(width 0.508)
		(layer "F.Cu")
		(net "GND")
	)
	(segment
		(start 50.099722 -150.599648)
		(end 50.099722 -150.599902)
		(width 0.3556)
		(layer "F.Cu")
		(net "GND")
	)
	(segment
		(start 54.0004 -131.3053)
		(end 54.0004 -130.6576)
		(width 0.254)
		(layer "F.Cu")
		(net "GND")
	)
	(segment
		(start 53.299868 -148.199856)
		(end 52.900072 -147.80006)
		(width 0.3556)
		(layer "F.Cu")
		(net "GND")
	)
	(segment
		(start 197.200012 -69.499988)
		(end 197.190614 -69.499988)
		(width 0.254)
		(layer "F.Cu")
		(net "GND")
	)
	(segment
		(start 189.999874 -69.499988)
		(end 190.000128 -69.499988)
		(width 0.254)
		(layer "F.Cu")
		(net "GND")
	)
	(segment
		(start 79.925164 -86.549992)
		(end 81.304892 -86.549992)
		(width 0.508)
		(layer "F.Cu")
		(net "GND")
	)
	(segment
		(start 67.563746 -171.6405)
		(end 67.6656 -171.538646)
		(width 0.508)
		(layer "F.Cu")
		(net "GND")
	)
	(segment
		(start 183.60009 -70.299834)
		(end 183.20004 -69.899784)
		(width 0.254)
		(layer "F.Cu")
		(net "GND")
	)
	(segment
		(start 185.200036 -64.700404)
		(end 185.60034 -65.100708)
		(width 0.254)
		(layer "F.Cu")
		(net "GND")
	)
	(segment
		(start 193.999866 -57.500012)
		(end 194.000374 -57.500012)
		(width 0.254)
		(layer "F.Cu")
		(net "GND")
	)
	(segment
		(start 193.999866 -63.90005)
		(end 194.00012 -63.90005)
		(width 0.254)
		(layer "F.Cu")
		(net "GND")
	)
	(segment
		(start 184.399936 -67.900042)
		(end 184.799986 -67.499992)
		(width 0.254)
		(layer "F.Cu")
		(net "GND")
	)
	(segment
		(start 77.01915 -81.7499)
		(end 77.283818 -82.014568)
		(width 0.508)
		(layer "F.Cu")
		(net "GND")
	)
	(segment
		(start 22.834854 -145.761964)
		(end 22.834346 -145.761456)
		(width 0.3048)
		(layer "F.Cu")
		(net "GND")
	)
	(segment
		(start 196.400674 -58.299858)
		(end 196.800216 -57.900316)
		(width 0.254)
		(layer "F.Cu")
		(net "GND")
	)
	(segment
		(start 197.999858 -63.90005)
		(end 198.799958 -63.90005)
		(width 0.254)
		(layer "F.Cu")
		(net "GND")
	)
	(segment
		(start 187.600082 -56.699912)
		(end 187.599828 -56.699912)
		(width 0.254)
		(layer "F.Cu")
		(net "GND")
	)
	(segment
		(start 186.800236 -63.90005)
		(end 187.200032 -64.299846)
		(width 0.254)
		(layer "F.Cu")
		(net "GND")
	)
	(segment
		(start 197.202806 -65.499996)
		(end 197.605904 -65.903094)
		(width 0.254)
		(layer "F.Cu")
		(net "GND")
	)
	(segment
		(start 193.999866 -56.699912)
		(end 194.00012 -56.699912)
		(width 0.254)
		(layer "F.Cu")
		(net "GND")
	)
	(segment
		(start 62.5094 -136.530842)
		(end 62.606936 -136.433306)
		(width 0.254)
		(layer "F.Cu")
		(net "GND")
	)
	(segment
		(start 191.600074 -60.700412)
		(end 191.200278 -61.100208)
		(width 0.254)
		(layer "F.Cu")
		(net "GND")
	)
	(segment
		(start 198.799958 -61.500004)
		(end 198.80326 -61.500004)
		(width 0.254)
		(layer "F.Cu")
		(net "GND")
	)
	(segment
		(start 199.600058 -59.900058)
		(end 199.600058 -59.099958)
		(width 0.254)
		(layer "F.Cu")
		(net "GND")
	)
	(segment
		(start 156.723842 -95.48241)
		(end 156.556202 -95.65005)
		(width 0.254)
		(layer "F.Cu")
		(net "GND")
	)
	(segment
		(start 160.3375 -85.8393)
		(end 159.9946 -86.1822)
		(width 0.508)
		(layer "F.Cu")
		(net "GND")
	)
	(segment
		(start 75.83678 -188.89218)
		(end 75.83678 -188.4426)
		(width 0.508)
		(layer "F.Cu")
		(net "GND")
	)
	(segment
		(start 201.99985 -75.900026)
		(end 201.600054 -76.299822)
		(width 0.3048)
		(layer "F.Cu")
		(net "GND")
	)
	(segment
		(start 195.2498 -24.3078)
		(end 195.03644 -24.52116)
		(width 0.4064)
		(layer "F.Cu")
		(net "GND")
	)
	(segment
		(start 196.000116 -75.499722)
		(end 196.399912 -75.099926)
		(width 0.3048)
		(layer "F.Cu")
		(net "GND")
	)
	(segment
		(start 77.91831 -51.34991)
		(end 78.71841 -52.15001)
		(width 0.508)
		(layer "F.Cu")
		(net "GND")
	)
	(segment
		(start 54.9656 -167.2336)
		(end 54.619652 -166.887652)
		(width 0.254)
		(layer "F.Cu")
		(net "GND")
	)
	(segment
		(start 197.39991 -64.6176)
		(end 197.317614 -64.699896)
		(width 0.254)
		(layer "F.Cu")
		(net "GND")
	)
	(segment
		(start 197.200012 -59.099958)
		(end 197.20052 -59.099958)
		(width 0.254)
		(layer "F.Cu")
		(net "GND")
	)
	(segment
		(start 79.155544 -169.190416)
		(end 79.155544 -170.260772)
		(width 0.508)
		(layer "F.Cu")
		(net "GND")
	)
	(segment
		(start 40.099996 -145.400014)
		(end 39.699946 -144.999964)
		(width 0.3556)
		(layer "F.Cu")
		(net "GND")
	)
	(segment
		(start 184.399936 -61.500004)
		(end 184.799986 -61.099954)
		(width 0.254)
		(layer "F.Cu")
		(net "GND")
	)
	(segment
		(start 191.200278 -67.500246)
		(end 191.600074 -67.900042)
		(width 0.254)
		(layer "F.Cu")
		(net "GND")
	)
	(segment
		(start 89.6239 -132.3213)
		(end 88.9 -132.3213)
		(width 0.508)
		(layer "F.Cu")
		(net "GND")
	)
	(segment
		(start 197.999858 -59.900058)
		(end 197.999858 -59.900566)
		(width 0.254)
		(layer "F.Cu")
		(net "GND")
	)
	(segment
		(start 48.899826 -143.800068)
		(end 48.90008 -143.800068)
		(width 0.3556)
		(layer "F.Cu")
		(net "GND")
	)
	(segment
		(start 43.700446 -141.00048)
		(end 44.099988 -141.400022)
		(width 0.3556)
		(layer "F.Cu")
		(net "GND")
	)
	(segment
		(start 30.6578 -129.5908)
		(end 30.3276 -129.921)
		(width 0.381)
		(layer "F.Cu")
		(net "GND")
	)
	(segment
		(start 81.182718 -84.149946)
		(end 81.643728 -83.688936)
		(width 0.508)
		(layer "F.Cu")
		(net "GND")
	)
	(segment
		(start 197.999858 -64.699896)
		(end 198.799958 -64.699896)
		(width 0.254)
		(layer "F.Cu")
		(net "GND")
	)
	(segment
		(start 202.79995 -63.90005)
		(end 203.197714 -63.502286)
		(width 0.254)
		(layer "F.Cu")
		(net "GND")
	)
	(segment
		(start 81.182718 -90.549984)
		(end 81.643728 -90.088974)
		(width 0.508)
		(layer "F.Cu")
		(net "GND")
	)
	(segment
		(start 188.800232 -56.300116)
		(end 188.799978 -56.300116)
		(width 0.254)
		(layer "F.Cu")
		(net "GND")
	)
	(segment
		(start 94.021656 -162.51428)
		(end 94.021656 -161.654744)
		(width 0.254)
		(layer "F.Cu")
		(net "GND")
	)
	(segment
		(start 48.09998 -145.400014)
		(end 48.50003 -144.999964)
		(width 0.3556)
		(layer "F.Cu")
		(net "GND")
	)
	(segment
		(start 200.000108 -75.499722)
		(end 199.600312 -75.099926)
		(width 0.3048)
		(layer "F.Cu")
		(net "GND")
	)
	(segment
		(start 158.977076 -87.314024)
		(end 159.9946 -86.2965)
		(width 0.254)
		(layer "F.Cu")
		(net "GND")
	)
	(segment
		(start 199.598026 -64.699896)
		(end 199.203818 -65.094104)
		(width 0.254)
		(layer "F.Cu")
		(net "GND")
	)
	(segment
		(start 47.8536 -163.5633)
		(end 46.99 -163.5633)
		(width 0.508)
		(layer "F.Cu")
		(net "GND")
	)
	(segment
		(start 177.3809 -63.3476)
		(end 177.885344 -63.3476)
		(width 0.254)
		(layer "F.Cu")
		(net "GND")
	)
	(segment
		(start 196.399912 -69.499988)
		(end 196.402198 -69.499988)
		(width 0.254)
		(layer "F.Cu")
		(net "GND")
	)
	(segment
		(start 66.71183 -179.819554)
		(end 66.71183 -180.650388)
		(width 0.508)
		(layer "F.Cu")
		(net "GND")
	)
	(segment
		(start 186.799982 -63.90005)
		(end 186.800236 -63.90005)
		(width 0.254)
		(layer "F.Cu")
		(net "GND")
	)
	(segment
		(start 189.999874 -73.49998)
		(end 190.39967 -73.899776)
		(width 0.3048)
		(layer "F.Cu")
		(net "GND")
	)
	(segment
		(start 77.84338 -188.5188)
		(end 77.81798 -188.5188)
		(width 0.508)
		(layer "F.Cu")
		(net "GND")
	)
	(segment
		(start 183.60009 -71.900034)
		(end 184.00014 -71.499984)
		(width 0.254)
		(layer "F.Cu")
		(net "GND")
	)
	(segment
		(start 194.007486 -135.128)
		(end 194.007486 -136.446514)
		(width 0.508)
		(layer "F.Cu")
		(net "GND")
	)
	(segment
		(start 43.700192 -149.799802)
		(end 44.099988 -149.400006)
		(width 0.3556)
		(layer "F.Cu")
		(net "GND")
	)
	(segment
		(start 56.3626 -159.2961)
		(end 56.3626 -160.2232)
		(width 0.508)
		(layer "F.Cu")
		(net "GND")
	)
	(segment
		(start 183.60009 -59.099958)
		(end 183.20004 -59.500008)
		(width 0.254)
		(layer "F.Cu")
		(net "GND")
	)
	(segment
		(start 81.108042 -64.149986)
		(end 81.584038 -64.625982)
		(width 0.508)
		(layer "F.Cu")
		(net "GND")
	)
	(segment
		(start 92.44965 -55.95366)
		(end 91.998038 -56.405272)
		(width 0.254)
		(layer "F.Cu")
		(net "GND")
	)
	(segment
		(start 197.88251 -64.699896)
		(end 197.800214 -64.6176)
		(width 0.254)
		(layer "F.Cu")
		(net "GND")
	)
	(segment
		(start 95.25 -30.734)
		(end 95.25 -29.464)
		(width 0.508)
		(layer "F.Cu")
		(net "GND")
	)
	(segment
		(start 23.234396 -145.362422)
		(end 22.834854 -145.761964)
		(width 0.3048)
		(layer "F.Cu")
		(net "GND")
	)
	(segment
		(start 193.999866 -55.900066)
		(end 194.399916 -56.300116)
		(width 0.254)
		(layer "F.Cu")
		(net "GND")
	)
	(segment
		(start 193.20002 -59.099958)
		(end 193.999866 -59.099958)
		(width 0.254)
		(layer "F.Cu")
		(net "GND")
	)
	(segment
		(start 94.5388 -167.141652)
		(end 95.0468 -166.633652)
		(width 0.508)
		(layer "F.Cu")
		(net "GND")
	)
	(segment
		(start 50.546762 -161.723578)
		(end 50.17897 -161.723578)
		(width 0.508)
		(layer "F.Cu")
		(net "GND")
	)
	(segment
		(start 193.20002 -74.299826)
		(end 193.20002 -74.306684)
		(width 0.254)
		(layer "F.Cu")
		(net "GND")
	)
	(segment
		(start 186.799982 -59.099958)
		(end 186.80049 -59.099958)
		(width 0.254)
		(layer "F.Cu")
		(net "GND")
	)
	(segment
		(start 165.1254 -137.2362)
		(end 166.0144 -137.2362)
		(width 0.508)
		(layer "F.Cu")
		(net "GND")
	)
	(segment
		(start 50.099722 -137.000234)
		(end 49.699926 -136.600438)
		(width 0.254)
		(layer "F.Cu")
		(net "GND")
	)
	(segment
		(start 94.021656 -161.654744)
		(end 94.0308 -161.6456)
		(width 0.254)
		(layer "F.Cu")
		(net "GND")
	)
	(segment
		(start 88.370918 -29.83484)
		(end 87.67445 -29.83484)
		(width 0.508)
		(layer "F.Cu")
		(net "GND")
	)
	(segment
		(start 77.516228 -57.778396)
		(end 77.567028 -57.778396)
		(width 0.508)
		(layer "F.Cu")
		(net "GND")
	)
	(segment
		(start 66.356992 -177.821844)
		(end 66.276474 -177.741326)
		(width 0.4064)
		(layer "F.Cu")
		(net "GND")
	)
	(segment
		(start 186.800236 -70.299834)
		(end 187.200286 -69.899784)
		(width 0.254)
		(layer "F.Cu")
		(net "GND")
	)
	(segment
		(start 47.8536 -128.6129)
		(end 47.8536 -128.768602)
		(width 0.254)
		(layer "F.Cu")
		(net "GND")
	)
	(segment
		(start 92.4052 -126.5682)
		(end 91.6432 -125.8062)
		(width 0.254)
		(layer "F.Cu")
		(net "GND")
	)
	(segment
		(start 194.799712 -56.699912)
		(end 194.399916 -56.300116)
		(width 0.254)
		(layer "F.Cu")
		(net "GND")
	)
	(segment
		(start 77.596492 -157.601158)
		(end 77.58938 -157.60827)
		(width 0.508)
		(layer "F.Cu")
		(net "GND")
	)
	(segment
		(start 86.45779 -29.83484)
		(end 86.435438 -29.857192)
		(width 0.508)
		(layer "F.Cu")
		(net "GND")
	)
	(segment
		(start 16.458184 -165.327584)
		(end 16.480536 -165.349936)
		(width 0.508)
		(layer "F.Cu")
		(net "GND")
	)
	(segment
		(start 47.300134 -143.800068)
		(end 47.29988 -143.800068)
		(width 0.3556)
		(layer "F.Cu")
		(net "GND")
	)
	(segment
		(start 159.9946 -86.2965)
		(end 159.9946 -86.1822)
		(width 0.254)
		(layer "F.Cu")
		(net "GND")
	)
	(segment
		(start 82.341466 -140.74013)
		(end 83.441286 -140.74013)
		(width 0.508)
		(layer "F.Cu")
		(net "GND")
	)
	(segment
		(start 200.399904 -74.385932)
		(end 200.399904 -74.299826)
		(width 0.254)
		(layer "F.Cu")
		(net "GND")
	)
	(segment
		(start 194.11696 -75.21702)
		(end 193.999866 -75.099926)
		(width 0.254)
		(layer "F.Cu")
		(net "GND")
	)
	(segment
		(start 203.191872 -69.09181)
		(end 202.79995 -68.699888)
		(width 0.3048)
		(layer "F.Cu")
		(net "GND")
	)
	(segment
		(start 97.6376 -152.273)
		(end 97.3582 -152.5524)
		(width 0.508)
		(layer "F.Cu")
		(net "GND")
	)
	(segment
		(start 44.099988 -149.400006)
		(end 44.500038 -149.800056)
		(width 0.3556)
		(layer "F.Cu")
		(net "GND")
	)
	(segment
		(start 192.400174 -63.90005)
		(end 192.800224 -64.3001)
		(width 0.254)
		(layer "F.Cu")
		(net "GND")
	)
	(segment
		(start 195.4403 -28.702)
		(end 196.2658 -28.702)
		(width 0.508)
		(layer "F.Cu")
		(net "GND")
	)
	(segment
		(start 197.4977 -16.764)
		(end 197.4977 -15.8369)
		(width 0.508)
		(layer "F.Cu")
		(net "GND")
	)
	(segment
		(start 215.9762 -103.3018)
		(end 215.9762 -102.5652)
		(width 0.508)
		(layer "F.Cu")
		(net "GND")
	)
	(segment
		(start 187.600082 -57.500012)
		(end 187.600082 -56.699912)
		(width 0.254)
		(layer "F.Cu")
		(net "GND")
	)
	(segment
		(start 193.20002 -72.708262)
		(end 192.804542 -73.10374)
		(width 0.254)
		(layer "F.Cu")
		(net "GND")
	)
	(segment
		(start 200.40473 -75.099926)
		(end 200.579736 -74.92492)
		(width 0.254)
		(layer "F.Cu")
		(net "GND")
	)
	(segment
		(start 42.499788 -147.80006)
		(end 42.500042 -147.80006)
		(width 0.3556)
		(layer "F.Cu")
		(net "GND")
	)
	(segment
		(start 47.69993 -152.999948)
		(end 47.69993 -153.000202)
		(width 0.254)
		(layer "F.Cu")
		(net "GND")
	)
	(segment
		(start 193.190622 -66.299842)
		(end 192.793874 -65.903094)
		(width 0.254)
		(layer "F.Cu")
		(net "GND")
	)
	(segment
		(start 186.800236 -67.900042)
		(end 187.200032 -68.299838)
		(width 0.254)
		(layer "F.Cu")
		(net "GND")
	)
	(segment
		(start 199.600058 -64.699896)
		(end 199.598026 -64.699896)
		(width 0.254)
		(layer "F.Cu")
		(net "GND")
	)
	(segment
		(start 67.709034 -154.589226)
		(end 67.6656 -154.63266)
		(width 0.254)
		(layer "F.Cu")
		(net "GND")
	)
	(segment
		(start 197.20052 -59.099958)
		(end 197.600316 -58.700162)
		(width 0.254)
		(layer "F.Cu")
		(net "GND")
	)
	(segment
		(start 202.79995 -69.496178)
		(end 203.193396 -69.102732)
		(width 0.3048)
		(layer "F.Cu")
		(net "GND")
	)
	(segment
		(start 98.113342 -152.273)
		(end 97.6376 -152.273)
		(width 0.508)
		(layer "F.Cu")
		(net "GND")
	)
	(segment
		(start 81.1784 -170.2943)
		(end 81.162144 -170.278044)
		(width 0.508)
		(layer "F.Cu")
		(net "GND")
	)
	(segment
		(start 147.883626 -98.199448)
		(end 147.972272 -98.288094)
		(width 0.254)
		(layer "F.Cu")
		(net "GND")
	)
	(segment
		(start 48.899826 -144.600168)
		(end 48.50003 -144.999964)
		(width 0.3556)
		(layer "F.Cu")
		(net "GND")
	)
	(segment
		(start 190.799974 -56.699912)
		(end 190.79972 -56.699912)
		(width 0.254)
		(layer "F.Cu")
		(net "GND")
	)
	(segment
		(start 143.9545 -17.4625)
		(end 144.272 -17.78)
		(width 0.508)
		(layer "F.Cu")
		(net "GND")
	)
	(segment
		(start 96.776032 -12.502642)
		(end 96.817942 -12.460732)
		(width 0.508)
		(layer "F.Cu")
		(net "GND")
	)
	(segment
		(start 48.899826 -146.999706)
		(end 48.899826 -146.99996)
		(width 0.3556)
		(layer "F.Cu")
		(net "GND")
	)
	(segment
		(start 71.53783 -139.546076)
		(end 72.5932 -139.546076)
		(width 0.3556)
		(layer "F.Cu")
		(net "GND")
	)
	(segment
		(start 197.20052 -70.299834)
		(end 197.600062 -69.900292)
		(width 0.254)
		(layer "F.Cu")
		(net "GND")
	)
	(segment
		(start 193.20002 -60.700412)
		(end 192.800224 -61.100208)
		(width 0.254)
		(layer "F.Cu")
		(net "GND")
	)
	(segment
		(start 189.999874 -66.299842)
		(end 189.600078 -65.900046)
		(width 0.254)
		(layer "F.Cu")
		(net "GND")
	)
	(segment
		(start 75.475084 -63.35014)
		(end 77.100684 -63.35014)
		(width 0.254)
		(layer "F.Cu")
		(net "GND")
	)
	(segment
		(start 77.02804 -85.750146)
		(end 77.283818 -85.494368)
		(width 0.508)
		(layer "F.Cu")
		(net "GND")
	)
	(segment
		(start 203.60005 -64.699896)
		(end 203.690982 -64.699896)
		(width 0.3048)
		(layer "F.Cu")
		(net "GND")
	)
	(segment
		(start 185.200036 -57.500012)
		(end 185.200036 -57.50814)
		(width 0.254)
		(layer "F.Cu")
		(net "GND")
	)
	(segment
		(start 193.20002 -71.099934)
		(end 193.200528 -71.099934)
		(width 0.254)
		(layer "F.Cu")
		(net "GND")
	)
	(segment
		(start 62.4586 -152.654)
		(end 61.8109 -152.654)
		(width 0.254)
		(layer "F.Cu")
		(net "GND")
	)
	(segment
		(start 75.475084 -94.549976)
		(end 77.017626 -94.549976)
		(width 0.508)
		(layer "F.Cu")
		(net "GND")
	)
	(segment
		(start 195.600066 -61.500512)
		(end 195.20027 -61.900308)
		(width 0.254)
		(layer "F.Cu")
		(net "GND")
	)
	(segment
		(start 195.03644 -24.52116)
		(end 195.03644 -25.3365)
		(width 0.4064)
		(layer "F.Cu")
		(net "GND")
	)
	(segment
		(start 79.925164 -70.550024)
		(end 81.304892 -70.550024)
		(width 0.508)
		(layer "F.Cu")
		(net "GND")
	)
	(segment
		(start 76.748386 -82.55)
		(end 77.283818 -82.014568)
		(width 0.508)
		(layer "F.Cu")
		(net "GND")
	)
	(segment
		(start 46.500034 -145.400014)
		(end 46.900084 -145.800064)
		(width 0.3556)
		(layer "F.Cu")
		(net "GND")
	)
	(segment
		(start 199.600058 -58.299858)
		(end 199.200262 -57.900062)
		(width 0.254)
		(layer "F.Cu")
		(net "GND")
	)
	(segment
		(start 66.867278 -159.068262)
		(end 67.779138 -159.068262)
		(width 0.508)
		(layer "F.Cu")
		(net "GND")
	)
	(segment
		(start 77.81798 -188.5188)
		(end 77.81798 -187.648596)
		(width 0.508)
		(layer "F.Cu")
		(net "GND")
	)
	(segment
		(start 194.000374 -57.500012)
		(end 194.40017 -57.100216)
		(width 0.254)
		(layer "F.Cu")
		(net "GND")
	)
	(segment
		(start 182.79999 -61.500004)
		(end 182.790338 -61.500004)
		(width 0.254)
		(layer "F.Cu")
		(net "GND")
	)
	(segment
		(start 159.55264 -143.647922)
		(end 159.55264 -144.55013)
		(width 0.508)
		(layer "F.Cu")
		(net "GND")
	)
	(segment
		(start 196.399912 -53.50002)
		(end 196.000116 -53.100224)
		(width 0.254)
		(layer "F.Cu")
		(net "GND")
	)
	(segment
		(start 38.899846 -153.800302)
		(end 39.299896 -153.400252)
		(width 0.3556)
		(layer "F.Cu")
		(net "GND")
	)
	(segment
		(start 185.200036 -70.299834)
		(end 184.799986 -70.699884)
		(width 0.254)
		(layer "F.Cu")
		(net "GND")
	)
	(segment
		(start 38.899846 -136.200134)
		(end 38.9001 -136.200134)
		(width 0.3556)
		(layer "F.Cu")
		(net "GND")
	)
	(segment
		(start 194.799966 -66.299842)
		(end 194.40017 -65.900046)
		(width 0.254)
		(layer "F.Cu")
		(net "GND")
	)
	(segment
		(start 81.268062 -67.350132)
		(end 81.605374 -67.687444)
		(width 0.508)
		(layer "F.Cu")
		(net "GND")
	)
	(segment
		(start 191.600328 -57.500012)
		(end 192.000124 -57.100216)
		(width 0.254)
		(layer "F.Cu")
		(net "GND")
	)
	(segment
		(start 25.6794 -130.0099)
		(end 26.7589 -130.0099)
		(width 0.508)
		(layer "F.Cu")
		(net "GND")
	)
	(segment
		(start 68.498974 -144.1196)
		(end 68.3768 -144.1196)
		(width 0.254)
		(layer "F.Cu")
		(net "GND")
	)
	(segment
		(start 189.200028 -59.900058)
		(end 189.200282 -59.900058)
		(width 0.254)
		(layer "F.Cu")
		(net "GND")
	)
	(segment
		(start 192.79997 -56.300116)
		(end 193.20002 -55.900066)
		(width 0.254)
		(layer "F.Cu")
		(net "GND")
	)
	(segment
		(start 191.600074 -71.900034)
		(end 191.600074 -71.099934)
		(width 0.254)
		(layer "F.Cu")
		(net "GND")
	)
	(segment
		(start 75.475084 -54.550056)
		(end 77.036168 -54.550056)
		(width 0.254)
		(layer "F.Cu")
		(net "GND")
	)
	(segment
		(start 75.81138 -188.4426)
		(end 75.81138 -187.648596)
		(width 0.508)
		(layer "F.Cu")
		(net "GND")
	)
	(segment
		(start 186.80049 -59.099958)
		(end 187.200286 -58.700162)
		(width 0.254)
		(layer "F.Cu")
		(net "GND")
	)
	(segment
		(start 199.600058 -61.500004)
		(end 199.600058 -61.509402)
		(width 0.254)
		(layer "F.Cu")
		(net "GND")
	)
	(segment
		(start 194.799966 -69.499988)
		(end 194.799966 -69.499734)
		(width 0.254)
		(layer "F.Cu")
		(net "GND")
	)
	(segment
		(start 194.800474 -61.500512)
		(end 194.800474 -61.500004)
		(width 0.254)
		(layer "F.Cu")
		(net "GND")
	)
	(segment
		(start 28.9052 -130.5052)
		(end 29.4894 -129.921)
		(width 0.381)
		(layer "F.Cu")
		(net "GND")
	)
	(segment
		(start 181.317392 -62.29985)
		(end 181.399942 -62.3824)
		(width 0.254)
		(layer "F.Cu")
		(net "GND")
	)
	(segment
		(start 189.99073 -67.900042)
		(end 189.593982 -67.503294)
		(width 0.254)
		(layer "F.Cu")
		(net "GND")
	)
	(segment
		(start 189.200028 -63.90005)
		(end 189.590934 -64.290956)
		(width 0.254)
		(layer "F.Cu")
		(net "GND")
	)
	(segment
		(start 195.60032 -67.900042)
		(end 196.000116 -67.500246)
		(width 0.254)
		(layer "F.Cu")
		(net "GND")
	)
	(segment
		(start 45.44568 -121.424192)
		(end 44.741592 -121.424192)
		(width 0.508)
		(layer "F.Cu")
		(net "GND")
	)
	(segment
		(start 183.60009 -67.099942)
		(end 183.20004 -67.499992)
		(width 0.254)
		(layer "F.Cu")
		(net "GND")
	)
	(segment
		(start 74.8919 -132.743702)
		(end 74.623422 -132.475224)
		(width 0.508)
		(layer "F.Cu")
		(net "GND")
	)
	(segment
		(start 189.200028 -68.699888)
		(end 189.600078 -69.099938)
		(width 0.254)
		(layer "F.Cu")
		(net "GND")
	)
	(segment
		(start 48.50003 -146.59991)
		(end 48.899826 -146.999706)
		(width 0.3556)
		(layer "F.Cu")
		(net "GND")
	)
	(segment
		(start 147.972272 -98.288094)
		(end 148.843492 -98.288094)
		(width 0.254)
		(layer "F.Cu")
		(net "GND")
	)
	(segment
		(start 22.43455 -148.561552)
		(end 22.43455 -148.56206)
		(width 0.3048)
		(layer "F.Cu")
		(net "GND")
	)
	(segment
		(start 192.39992 -68.699888)
		(end 192.39992 -68.709286)
		(width 0.254)
		(layer "F.Cu")
		(net "GND")
	)
	(segment
		(start 95.240348 -137.391648)
		(end 95.8215 -137.9728)
		(width 0.254)
		(layer "F.Cu")
		(net "GND")
	)
	(segment
		(start 38.9001 -136.200134)
		(end 39.299896 -136.59993)
		(width 0.3556)
		(layer "F.Cu")
		(net "GND")
	)
	(segment
		(start 194.800474 -61.500004)
		(end 194.799966 -61.500004)
		(width 0.254)
		(layer "F.Cu")
		(net "GND")
	)
	(segment
		(start 216.1794 -103.505)
		(end 215.9762 -103.3018)
		(width 0.508)
		(layer "F.Cu")
		(net "GND")
	)
	(segment
		(start 188.399928 -66.299842)
		(end 189.200028 -67.099942)
		(width 0.254)
		(layer "F.Cu")
		(net "GND")
	)
	(segment
		(start 46.900338 -141.00048)
		(end 47.29988 -141.400022)
		(width 0.3556)
		(layer "F.Cu")
		(net "GND")
	)
	(segment
		(start 189.999874 -67.900042)
		(end 189.99073 -67.900042)
		(width 0.254)
		(layer "F.Cu")
		(net "GND")
	)
	(segment
		(start 185.999882 -71.900034)
		(end 186.000136 -71.900034)
		(width 0.254)
		(layer "F.Cu")
		(net "GND")
	)
	(segment
		(start 87.63 -129.3622)
		(end 87.63 -129.42316)
		(width 0.254)
		(layer "F.Cu")
		(net "GND")
	)
	(segment
		(start 75.475084 -66.550032)
		(end 77.030834 -66.550032)
		(width 0.508)
		(layer "F.Cu")
		(net "GND")
	)
	(segment
		(start 195.600066 -73.49998)
		(end 195.199762 -73.099676)
		(width 0.254)
		(layer "F.Cu")
		(net "GND")
	)
	(segment
		(start 81.304892 -92.95003)
		(end 81.643728 -93.288866)
		(width 0.508)
		(layer "F.Cu")
		(net "GND")
	)
	(segment
		(start 48.899826 -146.19986)
		(end 49.699926 -146.19986)
		(width 0.3556)
		(layer "F.Cu")
		(net "GND")
	)
	(segment
		(start 188.399928 -57.500012)
		(end 189.200028 -57.500012)
		(width 0.254)
		(layer "F.Cu")
		(net "GND")
	)
	(segment
		(start 54.500018 -149.400006)
		(end 54.099968 -148.999956)
		(width 0.3556)
		(layer "F.Cu")
		(net "GND")
	)
	(segment
		(start 197.999858 -71.099934)
		(end 197.600062 -70.700138)
		(width 0.254)
		(layer "F.Cu")
		(net "GND")
	)
	(segment
		(start 18.2372 -175.6918)
		(end 18.2372 -177.5079)
		(width 0.508)
		(layer "F.Cu")
		(net "GND")
	)
	(segment
		(start 42.900092 -149.799802)
		(end 43.299888 -149.400006)
		(width 0.3556)
		(layer "F.Cu")
		(net "GND")
	)
	(segment
		(start 197.999858 -59.900566)
		(end 197.600316 -60.300108)
		(width 0.254)
		(layer "F.Cu")
		(net "GND")
	)
	(segment
		(start 203.60005 -76.70165)
		(end 203.60005 -76.699872)
		(width 0.254)
		(layer "F.Cu")
		(net "GND")
	)
	(segment
		(start 189.999874 -57.500012)
		(end 190.000128 -57.500012)
		(width 0.254)
		(layer "F.Cu")
		(net "GND")
	)
	(segment
		(start 198.808086 -135.255)
		(end 198.808086 -136.573514)
		(width 0.508)
		(layer "F.Cu")
		(net "GND")
	)
	(segment
		(start 185.999882 -58.299858)
		(end 186.799982 -58.299858)
		(width 0.254)
		(layer "F.Cu")
		(net "GND")
	)
	(segment
		(start 195.600066 -59.099958)
		(end 194.799966 -59.900058)
		(width 0.254)
		(layer "F.Cu")
		(net "GND")
	)
	(segment
		(start 95.210376 -20.34413)
		(end 95.210376 -19.4818)
		(width 0.3048)
		(layer "F.Cu")
		(net "GND")
	)
	(segment
		(start 190.797942 -75.101958)
		(end 190.799974 -75.099926)
		(width 0.3048)
		(layer "F.Cu")
		(net "GND")
	)
	(segment
		(start 77.596492 -54.311296)
		(end 77.035152 -53.749956)
		(width 0.254)
		(layer "F.Cu")
		(net "GND")
	)
	(segment
		(start 90.17 -166.497762)
		(end 90.81389 -167.141652)
		(width 0.508)
		(layer "F.Cu")
		(net "GND")
	)
	(segment
		(start 93.223588 -61.133736)
		(end 92.895928 -61.133736)
		(width 0.508)
		(layer "F.Cu")
		(net "GND")
	)
	(segment
		(start 188.399928 -58.299858)
		(end 189.200028 -58.299858)
		(width 0.254)
		(layer "F.Cu")
		(net "GND")
	)
	(segment
		(start 46.684438 -142.815564)
		(end 47.115476 -142.815564)
		(width 0.3556)
		(layer "F.Cu")
		(net "GND")
	)
	(segment
		(start 62.8396 -161.925)
		(end 62.8396 -162.4203)
		(width 0.254)
		(layer "F.Cu")
		(net "GND")
	)
	(segment
		(start 194.799966 -71.09968)
		(end 194.400424 -70.700138)
		(width 0.254)
		(layer "F.Cu")
		(net "GND")
	)
	(segment
		(start 185.200036 -60.700158)
		(end 185.60034 -61.100462)
		(width 0.254)
		(layer "F.Cu")
		(net "GND")
	)
	(segment
		(start 227.830126 -76.581)
		(end 228.17074 -76.581)
		(width 0.508)
		(layer "F.Cu")
		(net "GND")
	)
	(segment
		(start 88.527382 -178.46548)
		(end 88.97112 -178.46548)
		(width 0.508)
		(layer "F.Cu")
		(net "GND")
	)
	(segment
		(start 201.99985 -56.699912)
		(end 201.600054 -56.300116)
		(width 0.254)
		(layer "F.Cu")
		(net "GND")
	)
	(segment
		(start 81.319116 -77.749908)
		(end 81.758028 -77.310996)
		(width 0.508)
		(layer "F.Cu")
		(net "GND")
	)
	(segment
		(start 75.475084 -75.350116)
		(end 77.020166 -75.350116)
		(width 0.508)
		(layer "F.Cu")
		(net "GND")
	)
	(segment
		(start 195.600066 -71.898256)
		(end 195.196206 -71.494396)
		(width 0.254)
		(layer "F.Cu")
		(net "GND")
	)
	(segment
		(start 185.200036 -63.100204)
		(end 185.60034 -63.500508)
		(width 0.254)
		(layer "F.Cu")
		(net "GND")
	)
	(segment
		(start 79.925164 -93.75013)
		(end 81.182464 -93.75013)
		(width 0.508)
		(layer "F.Cu")
		(net "GND")
	)
	(segment
		(start 190.799974 -75.900026)
		(end 190.402464 -75.502516)
		(width 0.3048)
		(layer "F.Cu")
		(net "GND")
	)
	(segment
		(start 203.60005 -76.699872)
		(end 202.79995 -76.699872)
		(width 0.3048)
		(layer "F.Cu")
		(net "GND")
	)
	(segment
		(start 197.200012 -65.499996)
		(end 197.202806 -65.499996)
		(width 0.254)
		(layer "F.Cu")
		(net "GND")
	)
	(segment
		(start 48.899826 -145.400014)
		(end 48.499776 -145.800064)
		(width 0.3556)
		(layer "F.Cu")
		(net "GND")
	)
	(segment
		(start 183.60009 -55.908194)
		(end 183.20893 -56.299354)
		(width 0.254)
		(layer "F.Cu")
		(net "GND")
	)
	(segment
		(start 196.399912 -59.900566)
		(end 196.00037 -60.300108)
		(width 0.254)
		(layer "F.Cu")
		(net "GND")
	)
	(segment
		(start 193.999866 -71.09968)
		(end 193.600324 -70.700138)
		(width 0.254)
		(layer "F.Cu")
		(net "GND")
	)
	(segment
		(start 197.200012 -59.900058)
		(end 197.200266 -59.900058)
		(width 0.254)
		(layer "F.Cu")
		(net "GND")
	)
	(segment
		(start 121.84761 -17.6022)
		(end 121.2596 -17.6022)
		(width 0.508)
		(layer "F.Cu")
		(net "GND")
	)
	(segment
		(start 91.251532 -152.73528)
		(end 91.251532 -151.59228)
		(width 0.254)
		(layer "F.Cu")
		(net "GND")
	)
	(segment
		(start 190.800228 -59.900058)
		(end 191.200024 -59.500262)
		(width 0.254)
		(layer "F.Cu")
		(net "GND")
	)
	(segment
		(start 91.674696 -39.573454)
		(end 93.411548 -39.573454)
		(width 0.508)
		(layer "F.Cu")
		(net "GND")
	)
	(segment
		(start 75.475084 -81.7499)
		(end 77.01915 -81.7499)
		(width 0.508)
		(layer "F.Cu")
		(net "GND")
	)
	(segment
		(start 92.180918 -139.0396)
		(end 91.49715 -139.0396)
		(width 0.254)
		(layer "F.Cu")
		(net "GND")
	)
	(segment
		(start 52.499514 -141.00048)
		(end 52.099972 -141.400022)
		(width 0.3556)
		(layer "F.Cu")
		(net "GND")
	)
	(segment
		(start 198.80961 -64.699896)
		(end 199.203818 -65.094104)
		(width 0.254)
		(layer "F.Cu")
		(net "GND")
	)
	(segment
		(start 188.399928 -69.499988)
		(end 188.399928 -69.49948)
		(width 0.254)
		(layer "F.Cu")
		(net "GND")
	)
	(segment
		(start 201.99985 -56.699912)
		(end 202.116944 -56.699912)
		(width 0.254)
		(layer "F.Cu")
		(net "GND")
	)
	(segment
		(start 187.600082 -58.299858)
		(end 187.200286 -57.900062)
		(width 0.254)
		(layer "F.Cu")
		(net "GND")
	)
	(segment
		(start 190.799974 -71.099934)
		(end 190.399924 -70.699884)
		(width 0.254)
		(layer "F.Cu")
		(net "GND")
	)
	(segment
		(start 200.000108 -56.300116)
		(end 199.600058 -55.900066)
		(width 0.254)
		(layer "F.Cu")
		(net "GND")
	)
	(segment
		(start 191.600074 -69.499988)
		(end 191.708024 -69.499988)
		(width 0.254)
		(layer "F.Cu")
		(net "GND")
	)
	(segment
		(start 89.3064 -137.3124)
		(end 88.5825 -138.0363)
		(width 0.254)
		(layer "F.Cu")
		(net "GND")
	)
	(segment
		(start 73.0504 -149.098)
		(end 74.1553 -149.098)
		(width 0.508)
		(layer "F.Cu")
		(net "GND")
	)
	(segment
		(start 192.19418 -69.58584)
		(end 192.280032 -69.499988)
		(width 0.254)
		(layer "F.Cu")
		(net "GND")
	)
	(segment
		(start 185.999882 -61.500004)
		(end 186.000136 -61.500004)
		(width 0.254)
		(layer "F.Cu")
		(net "GND")
	)
	(segment
		(start 64.7827 -149.9108)
		(end 66.2432 -149.9108)
		(width 0.254)
		(layer "F.Cu")
		(net "GND")
	)
	(segment
		(start 198.80961 -68.699888)
		(end 199.20966 -69.099938)
		(width 0.254)
		(layer "F.Cu")
		(net "GND")
	)
	(segment
		(start 140.34516 -15.27302)
		(end 140.34516 -16.39062)
		(width 0.3556)
		(layer "F.Cu")
		(net "GND")
	)
	(segment
		(start 186.799982 -57.500012)
		(end 186.800236 -57.500012)
		(width 0.254)
		(layer "F.Cu")
		(net "GND")
	)
	(segment
		(start 42.900092 -149.800056)
		(end 42.900092 -149.799802)
		(width 0.3556)
		(layer "F.Cu")
		(net "GND")
	)
	(segment
		(start 46.499272 -117.791992)
		(end 47.43069 -117.791992)
		(width 0.508)
		(layer "F.Cu")
		(net "GND")
	)
	(segment
		(start 195.600574 -60.699904)
		(end 196.00037 -60.300108)
		(width 0.254)
		(layer "F.Cu")
		(net "GND")
	)
	(segment
		(start 47.29988 -152.599898)
		(end 47.69993 -152.999948)
		(width 0.254)
		(layer "F.Cu")
		(net "GND")
	)
	(segment
		(start 187.600082 -62.29985)
		(end 187.600336 -62.29985)
		(width 0.254)
		(layer "F.Cu")
		(net "GND")
	)
	(segment
		(start 183.60009 -60.700158)
		(end 183.200294 -61.099954)
		(width 0.254)
		(layer "F.Cu")
		(net "GND")
	)
	(segment
		(start 203.789534 -64.601344)
		(end 204.210666 -64.601344)
		(width 0.3048)
		(layer "F.Cu")
		(net "GND")
	)
	(segment
		(start 42.500042 -144.599914)
		(end 42.900092 -144.999964)
		(width 0.3556)
		(layer "F.Cu")
		(net "GND")
	)
	(segment
		(start 75.475084 -65.749932)
		(end 76.718414 -65.749932)
		(width 0.508)
		(layer "F.Cu")
		(net "GND")
	)
	(segment
		(start 65.9765 -164.75075)
		(end 67.00139 -164.75075)
		(width 0.508)
		(layer "F.Cu")
		(net "GND")
	)
	(segment
		(start 198.799958 -58.299858)
		(end 198.799704 -58.299858)
		(width 0.254)
		(layer "F.Cu")
		(net "GND")
	)
	(segment
		(start 172.5168 -117.5385)
		(end 173.1645 -117.5385)
		(width 0.508)
		(layer "F.Cu")
		(net "GND")
	)
	(segment
		(start 185.200036 -59.900058)
		(end 185.60034 -60.300362)
		(width 0.254)
		(layer "F.Cu")
		(net "GND")
	)
	(segment
		(start 198.00062 -73.49998)
		(end 198.3994 -73.1012)
		(width 0.254)
		(layer "F.Cu")
		(net "GND")
	)
	(segment
		(start 76.738734 -91.350084)
		(end 77.283818 -91.895168)
		(width 0.508)
		(layer "F.Cu")
		(net "GND")
	)
	(segment
		(start 22.43455 -148.56206)
		(end 22.834854 -148.962364)
		(width 0.3048)
		(layer "F.Cu")
		(net "GND")
	)
	(segment
		(start 98.73488 -177.08372)
		(end 99.6696 -177.08372)
		(width 0.508)
		(layer "F.Cu")
		(net "GND")
	)
	(segment
		(start 218.694 -103.3399)
		(end 218.694 -104.267)
		(width 0.508)
		(layer "F.Cu")
		(net "GND")
	)
	(segment
		(start 66.489326 -168.201086)
		(end 67.21729 -168.201086)
		(width 0.508)
		(layer "F.Cu")
		(net "GND")
	)
	(segment
		(start 198.714106 -63.185802)
		(end 198.799958 -63.09995)
		(width 0.254)
		(layer "F.Cu")
		(net "GND")
	)
	(segment
		(start 48.899826 -142.999968)
		(end 48.899826 -143.800068)
		(width 0.3556)
		(layer "F.Cu")
		(net "GND")
	)
	(segment
		(start 46.99 -163.5633)
		(end 46.981618 -163.571682)
		(width 0.508)
		(layer "F.Cu")
		(net "GND")
	)
	(segment
		(start 93.124528 -51.105816)
		(end 93.141546 -51.122834)
		(width 0.254)
		(layer "F.Cu")
		(net "GND")
	)
	(segment
		(start 189.200028 -71.099934)
		(end 189.200028 -70.299834)
		(width 0.254)
		(layer "F.Cu")
		(net "GND")
	)
	(segment
		(start 64.0715 -170.27525)
		(end 62.94755 -170.27525)
		(width 0.508)
		(layer "F.Cu")
		(net "GND")
	)
	(segment
		(start 199.590406 -72.69988)
		(end 199.192134 -72.301608)
		(width 0.254)
		(layer "F.Cu")
		(net "GND")
	)
	(segment
		(start 91.452446 -165.564058)
		(end 90.254582 -165.564058)
		(width 0.254)
		(layer "F.Cu")
		(net "GND")
	)
	(segment
		(start 198.400162 -56.300116)
		(end 198.399908 -56.300116)
		(width 0.254)
		(layer "F.Cu")
		(net "GND")
	)
	(segment
		(start 198.799958 -71.900034)
		(end 198.799958 -71.909432)
		(width 0.254)
		(layer "F.Cu")
		(net "GND")
	)
	(segment
		(start 192.39992 -70.299834)
		(end 192.39992 -70.29704)
		(width 0.254)
		(layer "F.Cu")
		(net "GND")
	)
	(segment
		(start 80.6704 -154.1399)
		(end 80.6704 -153.2382)
		(width 0.508)
		(layer "F.Cu")
		(net "GND")
	)
	(segment
		(start 81.397094 -76.950062)
		(end 81.758028 -77.310996)
		(width 0.508)
		(layer "F.Cu")
		(net "GND")
	)
	(segment
		(start 194.682872 -75.21702)
		(end 194.11696 -75.21702)
		(width 0.254)
		(layer "F.Cu")
		(net "GND")
	)
	(segment
		(start 197.20052 -60.699904)
		(end 197.600316 -60.300108)
		(width 0.254)
		(layer "F.Cu")
		(net "GND")
	)
	(segment
		(start 190.799974 -58.299858)
		(end 190.800482 -58.299858)
		(width 0.254)
		(layer "F.Cu")
		(net "GND")
	)
	(segment
		(start 49.699926 -144.599914)
		(end 49.299876 -144.199864)
		(width 0.3556)
		(layer "F.Cu")
		(net "GND")
	)
	(segment
		(start 186.399932 -65.099946)
		(end 185.999882 -64.699896)
		(width 0.254)
		(layer "F.Cu")
		(net "GND")
	)
	(segment
		(start 71.7804 -174.1551)
		(end 71.5899 -174.3456)
		(width 0.3556)
		(layer "F.Cu")
		(net "GND")
	)
	(segment
		(start 202.392788 -65.034922)
		(end 202.727814 -64.699896)
		(width 0.3048)
		(layer "F.Cu")
		(net "GND")
	)
	(segment
		(start 180.7718 -88.5825)
		(end 180.7718 -89.429082)
		(width 0.508)
		(layer "F.Cu")
		(net "GND")
	)
	(segment
		(start 16.834612 -138.961622)
		(end 15.619222 -138.961622)
		(width 0.254)
		(layer "F.Cu")
		(net "GND")
	)
	(segment
		(start 185.999882 -65.499996)
		(end 186.399932 -65.099946)
		(width 0.254)
		(layer "F.Cu")
		(net "GND")
	)
	(segment
		(start 44.741592 -121.424192)
		(end 44.4754 -121.158)
		(width 0.508)
		(layer "F.Cu")
		(net "GND")
	)
	(segment
		(start 94.89567 -137.23747)
		(end 95.049848 -137.391648)
		(width 0.254)
		(layer "F.Cu")
		(net "GND")
	)
	(segment
		(start 185.999882 -67.900042)
		(end 186.000136 -67.900042)
		(width 0.254)
		(layer "F.Cu")
		(net "GND")
	)
	(segment
		(start 76.74102 -72.14997)
		(end 77.283818 -72.692768)
		(width 0.508)
		(layer "F.Cu")
		(net "GND")
	)
	(segment
		(start 191.70015 -46.278546)
		(end 191.642746 -46.278546)
		(width 0.508)
		(layer "F.Cu")
		(net "GND")
	)
	(segment
		(start 95.210376 -21.51253)
		(end 95.210376 -22.3266)
		(width 0.3048)
		(layer "F.Cu")
		(net "GND")
	)
	(segment
		(start 51.679602 -153.7843)
		(end 51.299872 -153.40457)
		(width 0.3556)
		(layer "F.Cu")
		(net "GND")
	)
	(segment
		(start 49.299622 -141.00048)
		(end 49.299368 -141.00048)
		(width 0.254)
		(layer "F.Cu")
		(net "GND")
	)
	(segment
		(start 48.899826 -143.800068)
		(end 48.50003 -144.199864)
		(width 0.3556)
		(layer "F.Cu")
		(net "GND")
	)
	(segment
		(start 67.32778 -157.80766)
		(end 67.7291 -158.20898)
		(width 0.254)
		(layer "F.Cu")
		(net "GND")
	)
	(segment
		(start 79.925164 -67.350132)
		(end 81.268062 -67.350132)
		(width 0.508)
		(layer "F.Cu")
		(net "GND")
	)
	(segment
		(start 100.053394 -144.399)
		(end 100.053648 -144.398746)
		(width 0.508)
		(layer "F.Cu")
		(net "GND")
	)
	(segment
		(start 192.800224 -67.500246)
		(end 193.20002 -67.900042)
		(width 0.254)
		(layer "F.Cu")
		(net "GND")
	)
	(segment
		(start 198.80326 -61.500004)
		(end 199.206358 -61.903102)
		(width 0.254)
		(layer "F.Cu")
		(net "GND")
	)
	(segment
		(start 185.200036 -57.50814)
		(end 184.808876 -57.8993)
		(width 0.254)
		(layer "F.Cu")
		(net "GND")
	)
	(segment
		(start 190.000128 -69.499988)
		(end 190.400178 -69.900038)
		(width 0.254)
		(layer "F.Cu")
		(net "GND")
	)
	(segment
		(start 185.200036 -62.300104)
		(end 185.60034 -62.700408)
		(width 0.254)
		(layer "F.Cu")
		(net "GND")
	)
	(segment
		(start 227.9142 -56.896)
		(end 227.9142 -60.9092)
		(width 0.254)
		(layer "F.Cu")
		(net "GND")
	)
	(segment
		(start 198.799958 -67.900042)
		(end 198.717408 -67.982592)
		(width 0.254)
		(layer "F.Cu")
		(net "GND")
	)
	(segment
		(start 190.000128 -59.900058)
		(end 190.399924 -59.500262)
		(width 0.254)
		(layer "F.Cu")
		(net "GND")
	)
	(segment
		(start 206.870808 -98.992436)
		(end 205.980284 -98.992436)
		(width 0.508)
		(layer "F.Cu")
		(net "GND")
	)
	(segment
		(start 44.099988 -148.599906)
		(end 44.099988 -149.400006)
		(width 0.3556)
		(layer "F.Cu")
		(net "GND")
	)
	(segment
		(start 194.399916 -65.900046)
		(end 194.40017 -65.900046)
		(width 0.254)
		(layer "F.Cu")
		(net "GND")
	)
	(segment
		(start 191.600074 -57.500012)
		(end 191.600328 -57.500012)
		(width 0.254)
		(layer "F.Cu")
		(net "GND")
	)
	(segment
		(start 95.25 -28.194)
		(end 95.25 -27.2542)
		(width 0.508)
		(layer "F.Cu")
		(net "GND")
	)
	(segment
		(start 195.199 -122.8852)
		(end 195.199 -121.92)
		(width 0.508)
		(layer "F.Cu")
		(net "GND")
	)
	(segment
		(start 47.300134 -146.19986)
		(end 47.69993 -145.800064)
		(width 0.3556)
		(layer "F.Cu")
		(net "GND")
	)
	(segment
		(start 191.600328 -59.099958)
		(end 192.000124 -58.700162)
		(width 0.254)
		(layer "F.Cu")
		(net "GND")
	)
	(segment
		(start 177.885344 -63.3476)
		(end 178.181 -63.643256)
		(width 0.254)
		(layer "F.Cu")
		(net "GND")
	)
	(segment
		(start 190.800228 -57.500012)
		(end 191.200024 -57.100216)
		(width 0.254)
		(layer "F.Cu")
		(net "GND")
	)
	(segment
		(start 47.29988 -144.59966)
		(end 47.29988 -144.599914)
		(width 0.3556)
		(layer "F.Cu")
		(net "GND")
	)
	(segment
		(start 186.799982 -70.299834)
		(end 186.800236 -70.299834)
		(width 0.254)
		(layer "F.Cu")
		(net "GND")
	)
	(segment
		(start 191.193674 -69.10324)
		(end 191.193674 -69.093588)
		(width 0.254)
		(layer "F.Cu")
		(net "GND")
	)
	(segment
		(start 81.858358 -140.257022)
		(end 82.341466 -140.74013)
		(width 0.508)
		(layer "F.Cu")
		(net "GND")
	)
	(segment
		(start 76.6699 -148.7805)
		(end 76.9874 -149.098)
		(width 0.508)
		(layer "F.Cu")
		(net "GND")
	)
	(segment
		(start 47.69993 -145.800064)
		(end 48.099726 -146.19986)
		(width 0.3556)
		(layer "F.Cu")
		(net "GND")
	)
	(segment
		(start 94.76994 -180.32476)
		(end 95.10522 -180.66004)
		(width 0.4318)
		(layer "F.Cu")
		(net "GND")
	)
	(segment
		(start 183.4642 -153.3398)
		(end 183.4642 -154.4828)
		(width 0.508)
		(layer "F.Cu")
		(net "GND")
	)
	(segment
		(start 70.744842 -187.04687)
		(end 70.744842 -187.95746)
		(width 0.508)
		(layer "F.Cu")
		(net "GND")
	)
	(segment
		(start 180.1368 -141.8082)
		(end 180.1368 -141.069822)
		(width 0.508)
		(layer "F.Cu")
		(net "GND")
	)
	(segment
		(start 185.200036 -63.09995)
		(end 185.200036 -63.100204)
		(width 0.254)
		(layer "F.Cu")
		(net "GND")
	)
	(segment
		(start 193.003932 -71.021956)
		(end 193.08191 -71.099934)
		(width 0.254)
		(layer "F.Cu")
		(net "GND")
	)
	(segment
		(start 35.2806 -133.603746)
		(end 29.692346 -133.603746)
		(width 0.381)
		(layer "F.Cu")
		(net "GND")
	)
	(segment
		(start 53.643784 -123.891548)
		(end 54.288436 -124.5362)
		(width 0.254)
		(layer "F.Cu")
		(net "GND")
	)
	(segment
		(start 200.000108 -75.499722)
		(end 200.399904 -75.099926)
		(width 0.3048)
		(layer "F.Cu")
		(net "GND")
	)
	(segment
		(start 202.79995 -67.900042)
		(end 202.79995 -67.099942)
		(width 0.254)
		(layer "F.Cu")
		(net "GND")
	)
	(segment
		(start 184.40019 -56.699912)
		(end 184.799986 -56.300116)
		(width 0.254)
		(layer "F.Cu")
		(net "GND")
	)
	(segment
		(start 79.925164 -89.750138)
		(end 81.177892 -89.750138)
		(width 0.508)
		(layer "F.Cu")
		(net "GND")
	)
	(segment
		(start 189.999874 -58.299858)
		(end 190.000382 -58.299858)
		(width 0.254)
		(layer "F.Cu")
		(net "GND")
	)
	(segment
		(start 47.69993 -153.000202)
		(end 47.699676 -153.000202)
		(width 0.254)
		(layer "F.Cu")
		(net "GND")
	)
	(segment
		(start 58.7502 -164.7698)
		(end 58.6486 -164.8714)
		(width 0.508)
		(layer "F.Cu")
		(net "GND")
	)
	(segment
		(start 84.069682 -147.265898)
		(end 83.08594 -148.24964)
		(width 0.254)
		(layer "F.Cu")
		(net "GND")
	)
	(segment
		(start 47.29988 -148.599906)
		(end 47.29988 -148.60016)
		(width 0.3556)
		(layer "F.Cu")
		(net "GND")
	)
	(segment
		(start 122.4026 -10.7188)
		(end 121.925334 -10.241534)
		(width 0.254)
		(layer "F.Cu")
		(net "GND")
	)
	(segment
		(start 190.000382 -58.299858)
		(end 190.399924 -57.900316)
		(width 0.254)
		(layer "F.Cu")
		(net "GND")
	)
	(segment
		(start 89.092024 -166.95928)
		(end 89.941908 -167.809164)
		(width 0.508)
		(layer "F.Cu")
		(net "GND")
	)
	(segment
		(start 81.364074 -132.07746)
		(end 80.73898 -132.702554)
		(width 0.3556)
		(layer "F.Cu")
		(net "GND")
	)
	(segment
		(start 194.799966 -71.099934)
		(end 194.799966 -71.09968)
		(width 0.254)
		(layer "F.Cu")
		(net "GND")
	)
	(segment
		(start 47.39513 -151.095202)
		(end 47.39513 -151.704802)
		(width 0.3556)
		(layer "F.Cu")
		(net "GND")
	)
	(segment
		(start 193.200274 -54.299866)
		(end 193.60007 -53.90007)
		(width 0.254)
		(layer "F.Cu")
		(net "GND")
	)
	(segment
		(start 197.999858 -70.299834)
		(end 197.999858 -70.300342)
		(width 0.254)
		(layer "F.Cu")
		(net "GND")
	)
	(segment
		(start 193.20002 -69.499988)
		(end 193.20002 -69.497194)
		(width 0.254)
		(layer "F.Cu")
		(net "GND")
	)
	(segment
		(start 195.600066 -56.699912)
		(end 196.399912 -56.699912)
		(width 0.254)
		(layer "F.Cu")
		(net "GND")
	)
	(segment
		(start 192.39992 -67.099942)
		(end 192.800224 -67.500246)
		(width 0.254)
		(layer "F.Cu")
		(net "GND")
	)
	(segment
		(start 85.168994 -166.74592)
		(end 85.65896 -167.235886)
		(width 0.254)
		(layer "F.Cu")
		(net "GND")
	)
	(segment
		(start 187.600336 -67.900042)
		(end 188.000132 -68.299838)
		(width 0.254)
		(layer "F.Cu")
		(net "GND")
	)
	(segment
		(start 188.390784 -61.500004)
		(end 188.399928 -61.500004)
		(width 0.254)
		(layer "F.Cu")
		(net "GND")
	)
	(segment
		(start 196.399912 -66.299842)
		(end 196.000116 -65.900046)
		(width 0.254)
		(layer "F.Cu")
		(net "GND")
	)
	(segment
		(start 197.39864 -75.207622)
		(end 197.819772 -75.207622)
		(width 0.3048)
		(layer "F.Cu")
		(net "GND")
	)
	(segment
		(start 202.79995 -66.304414)
		(end 203.192888 -66.697352)
		(width 0.254)
		(layer "F.Cu")
		(net "GND")
	)
	(segment
		(start 179.832 -113.3094)
		(end 179.9082 -113.2332)
		(width 0.508)
		(layer "F.Cu")
		(net "GND")
	)
	(segment
		(start 52.8066 -162.9283)
		(end 52.8066 -163.9824)
		(width 0.508)
		(layer "F.Cu")
		(net "GND")
	)
	(segment
		(start 186.000136 -61.500004)
		(end 186.399932 -61.8998)
		(width 0.254)
		(layer "F.Cu")
		(net "GND")
	)
	(segment
		(start 74.44105 -177.020982)
		(end 74.44105 -177.883058)
		(width 0.254)
		(layer "F.Cu")
		(net "GND")
	)
	(segment
		(start 50.060098 -172.699934)
		(end 48.708818 -172.699934)
		(width 0.508)
		(layer "F.Cu")
		(net "GND")
	)
	(segment
		(start 196.399912 -59.099958)
		(end 197.200012 -59.099958)
		(width 0.254)
		(layer "F.Cu")
		(net "GND")
	)
	(segment
		(start 90.17 -165.64864)
		(end 90.17 -166.497762)
		(width 0.508)
		(layer "F.Cu")
		(net "GND")
	)
	(segment
		(start 201.53376 -62.633606)
		(end 201.200004 -62.29985)
		(width 0.254)
		(layer "F.Cu")
		(net "GND")
	)
	(segment
		(start 191.193674 -69.093588)
		(end 190.799974 -68.699888)
		(width 0.254)
		(layer "F.Cu")
		(net "GND")
	)
	(segment
		(start 76.1746 -167.8686)
		(end 76.1746 -168.143174)
		(width 0.508)
		(layer "F.Cu")
		(net "GND")
	)
	(segment
		(start 88.647016 -46.50232)
		(end 88.647016 -47.066708)
		(width 0.508)
		(layer "F.Cu")
		(net "GND")
	)
	(segment
		(start 94.488 -18.3261)
		(end 95.3262 -18.3261)
		(width 0.4064)
		(layer "F.Cu")
		(net "GND")
	)
	(segment
		(start 125.6792 -8.636)
		(end 126.1618 -8.1534)
		(width 0.254)
		(layer "F.Cu")
		(net "GND")
	)
	(segment
		(start 189.200028 -71.900034)
		(end 189.317376 -71.900034)
		(width 0.254)
		(layer "F.Cu")
		(net "GND")
	)
	(segment
		(start 124.4727 -11.6586)
		(end 124.4727 -12.4714)
		(width 0.254)
		(layer "F.Cu")
		(net "GND")
	)
	(segment
		(start 187.599828 -74.299826)
		(end 187.199778 -73.899776)
		(width 0.3048)
		(layer "F.Cu")
		(net "GND")
	)
	(segment
		(start 91.05392 -38.952678)
		(end 91.674696 -39.573454)
		(width 0.508)
		(layer "F.Cu")
		(net "GND")
	)
	(segment
		(start 88.22944 -130.0226)
		(end 88.3285 -130.0226)
		(width 0.254)
		(layer "F.Cu")
		(net "GND")
	)
	(segment
		(start 49.699926 -150.199852)
		(end 50.099722 -150.599648)
		(width 0.3556)
		(layer "F.Cu")
		(net "GND")
	)
	(segment
		(start 79.925164 -64.149986)
		(end 81.108042 -64.149986)
		(width 0.508)
		(layer "F.Cu")
		(net "GND")
	)
	(segment
		(start 16.480536 -165.349936)
		(end 16.04137 -165.789102)
		(width 0.254)
		(layer "F.Cu")
		(net "GND")
	)
	(segment
		(start 70.744842 -187.95746)
		(end 70.752462 -187.96508)
		(width 0.508)
		(layer "F.Cu")
		(net "GND")
	)
	(segment
		(start 46.500034 -146.99996)
		(end 46.900084 -146.59991)
		(width 0.3556)
		(layer "F.Cu")
		(net "GND")
	)
	(segment
		(start 61.468 -176.1236)
		(end 61.627004 -175.964596)
		(width 0.254)
		(layer "F.Cu")
		(net "GND")
	)
	(segment
		(start 51.906678 -166.861744)
		(end 51.906678 -167.473122)
		(width 0.508)
		(layer "F.Cu")
		(net "GND")
	)
	(segment
		(start 188.233812 -64.866012)
		(end 188.233812 -64.866266)
		(width 0.254)
		(layer "F.Cu")
		(net "GND")
	)
	(segment
		(start 48.899826 -146.19986)
		(end 48.899826 -146.200114)
		(width 0.3556)
		(layer "F.Cu")
		(net "GND")
	)
	(segment
		(start 184.097168 -44.943268)
		(end 183.4261 -44.2722)
		(width 0.508)
		(layer "F.Cu")
		(net "GND")
	)
	(segment
		(start 69.215762 -179.015898)
		(end 68.075302 -179.015898)
		(width 0.508)
		(layer "F.Cu")
		(net "GND")
	)
	(segment
		(start 63.04661 -155.736798)
		(end 63.04661 -154.97429)
		(width 0.508)
		(layer "F.Cu")
		(net "GND")
	)
	(segment
		(start 40.099996 -146.99996)
		(end 39.699946 -147.40001)
		(width 0.3556)
		(layer "F.Cu")
		(net "GND")
	)
	(segment
		(start 194.799966 -68.699888)
		(end 194.799966 -68.70065)
		(width 0.254)
		(layer "F.Cu")
		(net "GND")
	)
	(segment
		(start 183.60009 -68.699888)
		(end 183.20004 -69.099938)
		(width 0.254)
		(layer "F.Cu")
		(net "GND")
	)
	(segment
		(start 192.800732 -76.305156)
		(end 192.800732 -76.294996)
		(width 0.3048)
		(layer "F.Cu")
		(net "GND")
	)
	(segment
		(start 87.5538 -129.286)
		(end 87.63 -129.3622)
		(width 0.254)
		(layer "F.Cu")
		(net "GND")
	)
	(segment
		(start 189.999874 -59.900058)
		(end 190.000128 -59.900058)
		(width 0.254)
		(layer "F.Cu")
		(net "GND")
	)
	(segment
		(start 187.600082 -71.900034)
		(end 187.600336 -71.900034)
		(width 0.254)
		(layer "F.Cu")
		(net "GND")
	)
	(segment
		(start 198.799958 -59.900312)
		(end 198.400162 -60.300108)
		(width 0.254)
		(layer "F.Cu")
		(net "GND")
	)
	(segment
		(start 193.200274 -55.099966)
		(end 193.60007 -54.70017)
		(width 0.254)
		(layer "F.Cu")
		(net "GND")
	)
	(segment
		(start 203.199746 -72.29983)
		(end 202.79995 -72.699626)
		(width 0.3048)
		(layer "F.Cu")
		(net "GND")
	)
	(segment
		(start 196.399912 -70.29069)
		(end 196.796406 -69.894196)
		(width 0.254)
		(layer "F.Cu")
		(net "GND")
	)
	(segment
		(start 200.399904 -75.099926)
		(end 200.40473 -75.099926)
		(width 0.254)
		(layer "F.Cu")
		(net "GND")
	)
	(segment
		(start 50.94224 -161.3154)
		(end 50.546762 -161.723578)
		(width 0.508)
		(layer "F.Cu")
		(net "GND")
	)
	(segment
		(start 196.409056 -68.699888)
		(end 196.805804 -68.30314)
		(width 0.254)
		(layer "F.Cu")
		(net "GND")
	)
	(segment
		(start 189.88278 -71.900034)
		(end 189.999874 -71.900034)
		(width 0.254)
		(layer "F.Cu")
		(net "GND")
	)
	(segment
		(start 46.500034 -144.599914)
		(end 46.900084 -144.999964)
		(width 0.3556)
		(layer "F.Cu")
		(net "GND")
	)
	(segment
		(start 200.399904 -67.900042)
		(end 200.399904 -67.89039)
		(width 0.254)
		(layer "F.Cu")
		(net "GND")
	)
	(segment
		(start 92.204032 -139.016486)
		(end 92.180918 -139.0396)
		(width 0.254)
		(layer "F.Cu")
		(net "GND")
	)
	(segment
		(start 196.399912 -70.299834)
		(end 196.399912 -70.29069)
		(width 0.254)
		(layer "F.Cu")
		(net "GND")
	)
	(segment
		(start 186.799982 -60.699904)
		(end 187.200286 -60.2996)
		(width 0.254)
		(layer "F.Cu")
		(net "GND")
	)
	(segment
		(start 152.399492 -98.288094)
		(end 152.399492 -99.38258)
		(width 0.508)
		(layer "F.Cu")
		(net "GND")
	)
	(segment
		(start 197.999858 -61.500004)
		(end 197.999858 -60.699904)
		(width 0.254)
		(layer "F.Cu")
		(net "GND")
	)
	(segment
		(start 47.8536 -128.768602)
		(end 48.620172 -129.535174)
		(width 0.254)
		(layer "F.Cu")
		(net "GND")
	)
	(segment
		(start 69.1769 -161.9123)
		(end 69.7992 -161.29)
		(width 0.508)
		(layer "F.Cu")
		(net "GND")
	)
	(segment
		(start 92.895928 -61.133736)
		(end 92.131388 -60.369196)
		(width 0.508)
		(layer "F.Cu")
		(net "GND")
	)
	(segment
		(start 188.399928 -55.900066)
		(end 188.799978 -56.300116)
		(width 0.254)
		(layer "F.Cu")
		(net "GND")
	)
	(segment
		(start 188.399928 -59.099958)
		(end 189.200028 -59.099958)
		(width 0.254)
		(layer "F.Cu")
		(net "GND")
	)
	(segment
		(start 203.590652 -63.09995)
		(end 203.60005 -63.09995)
		(width 0.254)
		(layer "F.Cu")
		(net "GND")
	)
	(segment
		(start 195.600066 -75.899772)
		(end 196.000116 -75.499722)
		(width 0.3048)
		(layer "F.Cu")
		(net "GND")
	)
	(segment
		(start 201.600054 -76.299822)
		(end 201.200258 -75.900026)
		(width 0.3048)
		(layer "F.Cu")
		(net "GND")
	)
	(segment
		(start 184.399936 -56.699912)
		(end 184.40019 -56.699912)
		(width 0.254)
		(layer "F.Cu")
		(net "GND")
	)
	(segment
		(start 199.600312 -75.099926)
		(end 199.600058 -75.099926)
		(width 0.3048)
		(layer "F.Cu")
		(net "GND")
	)
	(segment
		(start 67.7672 -171.437046)
		(end 67.6656 -171.538646)
		(width 0.508)
		(layer "F.Cu")
		(net "GND")
	)
	(segment
		(start 66.802 -171.6405)
		(end 67.563746 -171.6405)
		(width 0.508)
		(layer "F.Cu")
		(net "GND")
	)
	(segment
		(start 187.600082 -59.900058)
		(end 187.200286 -59.500262)
		(width 0.254)
		(layer "F.Cu")
		(net "GND")
	)
	(segment
		(start 200.399904 -54.299866)
		(end 199.999854 -54.699916)
		(width 0.254)
		(layer "F.Cu")
		(net "GND")
	)
	(segment
		(start 195.600066 -57.500012)
		(end 194.799966 -57.500012)
		(width 0.254)
		(layer "F.Cu")
		(net "GND")
	)
	(segment
		(start 183.4261 -47.7012)
		(end 183.4261 -46.8757)
		(width 0.508)
		(layer "F.Cu")
		(net "GND")
	)
	(segment
		(start 186.800236 -68.699888)
		(end 187.200032 -69.099684)
		(width 0.254)
		(layer "F.Cu")
		(net "GND")
	)
	(segment
		(start 187.600082 -70.299834)
		(end 187.600082 -70.29958)
		(width 0.254)
		(layer "F.Cu")
		(net "GND")
	)
	(segment
		(start 191.600074 -61.500004)
		(end 191.200278 -61.100208)
		(width 0.254)
		(layer "F.Cu")
		(net "GND")
	)
	(segment
		(start 200.39965 -73.49998)
		(end 199.9996 -73.09993)
		(width 0.254)
		(layer "F.Cu")
		(net "GND")
	)
	(segment
		(start 81.586832 -131.930394)
		(end 81.439766 -132.07746)
		(width 0.3556)
		(layer "F.Cu")
		(net "GND")
	)
	(segment
		(start 194.000374 -58.299858)
		(end 194.40017 -57.900062)
		(width 0.254)
		(layer "F.Cu")
		(net "GND")
	)
	(segment
		(start 194.799966 -56.699912)
		(end 194.799712 -56.699912)
		(width 0.254)
		(layer "F.Cu")
		(net "GND")
	)
	(segment
		(start 192.39992 -59.900058)
		(end 192.000124 -59.500262)
		(width 0.254)
		(layer "F.Cu")
		(net "GND")
	)
	(segment
		(start 189.999874 -71.900034)
		(end 189.999874 -71.909432)
		(width 0.254)
		(layer "F.Cu")
		(net "GND")
	)
	(segment
		(start 193.999866 -71.900034)
		(end 193.991484 -71.900034)
		(width 0.254)
		(layer "F.Cu")
		(net "GND")
	)
	(segment
		(start 69.33946 -158.86684)
		(end 68.6816 -158.20898)
		(width 0.254)
		(layer "F.Cu")
		(net "GND")
	)
	(segment
		(start 192.303146 -133.735064)
		(end 192.303146 -134.640828)
		(width 0.508)
		(layer "F.Cu")
		(net "GND")
	)
	(segment
		(start 190.799974 -57.500012)
		(end 190.800228 -57.500012)
		(width 0.254)
		(layer "F.Cu")
		(net "GND")
	)
	(segment
		(start 67.21729 -168.201086)
		(end 67.31 -168.293796)
		(width 0.508)
		(layer "F.Cu")
		(net "GND")
	)
	(segment
		(start 79.925164 -73.749916)
		(end 81.371948 -73.749916)
		(width 0.508)
		(layer "F.Cu")
		(net "GND")
	)
	(segment
		(start 185.200036 -58.29046)
		(end 184.808876 -57.8993)
		(width 0.254)
		(layer "F.Cu")
		(net "GND")
	)
	(segment
		(start 194.799966 -59.900058)
		(end 194.40017 -59.500262)
		(width 0.254)
		(layer "F.Cu")
		(net "GND")
	)
	(segment
		(start 185.200036 -72.69988)
		(end 185.200036 -73.49998)
		(width 0.254)
		(layer "F.Cu")
		(net "GND")
	)
	(segment
		(start 187.600082 -70.29958)
		(end 187.200286 -69.899784)
		(width 0.254)
		(layer "F.Cu")
		(net "GND")
	)
	(segment
		(start 185.999882 -59.900058)
		(end 186.400186 -60.300362)
		(width 0.254)
		(layer "F.Cu")
		(net "GND")
	)
	(segment
		(start 186.800236 -62.29985)
		(end 187.200032 -62.699646)
		(width 0.254)
		(layer "F.Cu")
		(net "GND")
	)
	(segment
		(start 202.795378 -65.499996)
		(end 202.392788 -65.097406)
		(width 0.3048)
		(layer "F.Cu")
		(net "GND")
	)
	(segment
		(start 23.234396 -141.361668)
		(end 23.233888 -141.361668)
		(width 0.254)
		(layer "F.Cu")
		(net "GND")
	)
	(segment
		(start 201.600054 -58.699654)
		(end 201.600054 -58.700162)
		(width 0.254)
		(layer "F.Cu")
		(net "GND")
	)
	(segment
		(start 47.29988 -149.399752)
		(end 47.29988 -149.400006)
		(width 0.3556)
		(layer "F.Cu")
		(net "GND")
	)
	(segment
		(start 191.600074 -58.299858)
		(end 191.600582 -58.299858)
		(width 0.254)
		(layer "F.Cu")
		(net "GND")
	)
	(segment
		(start 185.999882 -62.29985)
		(end 186.000136 -62.29985)
		(width 0.254)
		(layer "F.Cu")
		(net "GND")
	)
	(segment
		(start 196.399912 -63.09995)
		(end 196.399912 -63.90005)
		(width 0.254)
		(layer "F.Cu")
		(net "GND")
	)
	(segment
		(start 198.399908 -56.300116)
		(end 197.999858 -55.900066)
		(width 0.254)
		(layer "F.Cu")
		(net "GND")
	)
	(segment
		(start 190.800482 -58.299858)
		(end 191.200024 -57.900316)
		(width 0.254)
		(layer "F.Cu")
		(net "GND")
	)
	(segment
		(start 83.57489 -132.620004)
		(end 83.57489 -131.90855)
		(width 0.508)
		(layer "F.Cu")
		(net "GND")
	)
	(segment
		(start 187.600336 -67.099942)
		(end 188.000132 -67.499738)
		(width 0.254)
		(layer "F.Cu")
		(net "GND")
	)
	(segment
		(start 90.795348 -129.506726)
		(end 90.734896 -129.567178)
		(width 0.254)
		(layer "F.Cu")
		(net "GND")
	)
	(segment
		(start 49.699672 -143.800068)
		(end 49.299876 -144.199864)
		(width 0.3556)
		(layer "F.Cu")
		(net "GND")
	)
	(segment
		(start 47.699676 -150.600156)
		(end 47.29988 -150.999952)
		(width 0.3556)
		(layer "F.Cu")
		(net "GND")
	)
	(segment
		(start 197.800214 -64.6176)
		(end 197.39991 -64.6176)
		(width 0.254)
		(layer "F.Cu")
		(net "GND")
	)
	(segment
		(start 188.399928 -71.100442)
		(end 188.000386 -71.499984)
		(width 0.254)
		(layer "F.Cu")
		(net "GND")
	)
	(segment
		(start 93.972126 -147.148042)
		(end 93.972126 -147.461732)
		(width 0.254)
		(layer "F.Cu")
		(net "GND")
	)
	(segment
		(start 197.125082 -75.099926)
		(end 197.200012 -75.099926)
		(width 0.3048)
		(layer "F.Cu")
		(net "GND")
	)
	(segment
		(start 191.516 -47.244)
		(end 191.3636 -47.0916)
		(width 0.508)
		(layer "F.Cu")
		(net "GND")
	)
	(segment
		(start 170.8785 -123.34875)
		(end 172.02785 -123.34875)
		(width 0.508)
		(layer "F.Cu")
		(net "GND")
	)
	(segment
		(start 197.200012 -60.699904)
		(end 197.20052 -60.699904)
		(width 0.254)
		(layer "F.Cu")
		(net "GND")
	)
	(segment
		(start 50.899822 -149.800056)
		(end 50.899822 -149.799802)
		(width 0.3556)
		(layer "F.Cu")
		(net "GND")
	)
	(segment
		(start 21.492464 -16.373856)
		(end 21.49094 -16.37538)
		(width 0.508)
		(layer "F.Cu")
		(net "GND")
	)
	(segment
		(start 197.200012 -71.890382)
		(end 197.59041 -71.499984)
		(width 0.254)
		(layer "F.Cu")
		(net "GND")
	)
	(segment
		(start 196.000116 -75.499722)
		(end 195.60032 -75.099926)
		(width 0.3048)
		(layer "F.Cu")
		(net "GND")
	)
	(segment
		(start 16.834358 -144.56156)
		(end 16.434054 -144.961864)
		(width 0.3048)
		(layer "F.Cu")
		(net "GND")
	)
	(segment
		(start 198.799958 -71.909432)
		(end 199.192134 -72.301608)
		(width 0.254)
		(layer "F.Cu")
		(net "GND")
	)
	(segment
		(start 205.17612 -53.70068)
		(end 205.17612 -54.63032)
		(width 0.254)
		(layer "F.Cu")
		(net "GND")
	)
	(segment
		(start 186.799982 -66.299842)
		(end 186.799982 -67.099942)
		(width 0.254)
		(layer "F.Cu")
		(net "GND")
	)
	(segment
		(start 183.60009 -55.900066)
		(end 183.60009 -55.908194)
		(width 0.254)
		(layer "F.Cu")
		(net "GND")
	)
	(segment
		(start 40.099996 -143.800068)
		(end 40.500046 -144.200118)
		(width 0.254)
		(layer "F.Cu")
		(net "GND")
	)
	(segment
		(start 202.361292 -65.061338)
		(end 201.99985 -64.699896)
		(width 0.254)
		(layer "F.Cu")
		(net "GND")
	)
	(segment
		(start 70.744842 -161.96437)
		(end 70.750684 -161.958528)
		(width 0.508)
		(layer "F.Cu")
		(net "GND")
	)
	(segment
		(start 197.1548 -12.1158)
		(end 197.1802 -12.0904)
		(width 0.508)
		(layer "F.Cu")
		(net "GND")
	)
	(segment
		(start 52.900072 -147.80006)
		(end 52.899818 -147.80006)
		(width 0.3556)
		(layer "F.Cu")
		(net "GND")
	)
	(segment
		(start 71.5899 -174.3456)
		(end 70.9676 -174.3456)
		(width 0.3556)
		(layer "F.Cu")
		(net "GND")
	)
	(segment
		(start 27.5844 -146.565366)
		(end 27.526234 -146.623532)
		(width 0.508)
		(layer "F.Cu")
		(net "GND")
	)
	(segment
		(start 79.925164 -87.350092)
		(end 81.182464 -87.350092)
		(width 0.508)
		(layer "F.Cu")
		(net "GND")
	)
	(segment
		(start 203.590398 -66.299842)
		(end 203.60005 -66.299842)
		(width 0.254)
		(layer "F.Cu")
		(net "GND")
	)
	(segment
		(start 75.83678 -188.4426)
		(end 75.81138 -188.4426)
		(width 0.508)
		(layer "F.Cu")
		(net "GND")
	)
	(segment
		(start 77.58938 -157.60827)
		(end 77.58938 -158.428436)
		(width 0.508)
		(layer "F.Cu")
		(net "GND")
	)
	(segment
		(start 195.600066 -67.100196)
		(end 196.000116 -67.500246)
		(width 0.254)
		(layer "F.Cu")
		(net "GND")
	)
	(segment
		(start 199.600058 -65.499996)
		(end 199.598026 -65.499996)
		(width 0.254)
		(layer "F.Cu")
		(net "GND")
	)
	(segment
		(start 202.361292 -65.06591)
		(end 202.361292 -65.061338)
		(width 0.254)
		(layer "F.Cu")
		(net "GND")
	)
	(segment
		(start 202.199748 -56.782716)
		(end 202.600052 -56.782716)
		(width 0.254)
		(layer "F.Cu")
		(net "GND")
	)
	(segment
		(start 48.708818 -172.699934)
		(end 48.708564 -172.69968)
		(width 0.508)
		(layer "F.Cu")
		(net "GND")
	)
	(segment
		(start 192.39992 -57.500012)
		(end 192.000124 -57.100216)
		(width 0.254)
		(layer "F.Cu")
		(net "GND")
	)
	(segment
		(start 180.06314 -83.70316)
		(end 180.06314 -83.9724)
		(width 0.254)
		(layer "F.Cu")
		(net "GND")
	)
	(segment
		(start 49.299876 -136.99998)
		(end 48.899826 -136.59993)
		(width 0.254)
		(layer "F.Cu")
		(net "GND")
	)
	(segment
		(start 186.799982 -65.499996)
		(end 187.200032 -65.099946)
		(width 0.254)
		(layer "F.Cu")
		(net "GND")
	)
	(segment
		(start 194.799966 -72.69988)
		(end 195.199762 -73.099676)
		(width 0.3048)
		(layer "F.Cu")
		(net "GND")
	)
	(segment
		(start 51.699668 -149.800056)
		(end 51.699668 -149.799802)
		(width 0.3556)
		(layer "F.Cu")
		(net "GND")
	)
	(segment
		(start 197.999858 -64.699896)
		(end 197.88251 -64.699896)
		(width 0.254)
		(layer "F.Cu")
		(net "GND")
	)
	(segment
		(start 196.399912 -63.90005)
		(end 196.399912 -63.900304)
		(width 0.254)
		(layer "F.Cu")
		(net "GND")
	)
	(segment
		(start 201.200004 -62.29985)
		(end 201.200004 -62.29477)
		(width 0.254)
		(layer "F.Cu")
		(net "GND")
	)
	(segment
		(start 194.40017 -67.500246)
		(end 194.799966 -67.900042)
		(width 0.254)
		(layer "F.Cu")
		(net "GND")
	)
	(segment
		(start 185.200036 -67.900042)
		(end 185.60034 -68.300346)
		(width 0.254)
		(layer "F.Cu")
		(net "GND")
	)
	(segment
		(start 79.925164 -84.149946)
		(end 81.182718 -84.149946)
		(width 0.508)
		(layer "F.Cu")
		(net "GND")
	)
	(segment
		(start 179.787804 -154.362404)
		(end 179.9844 -154.559)
		(width 0.508)
		(layer "F.Cu")
		(net "GND")
	)
	(segment
		(start 200.399904 -67.099942)
		(end 200.399904 -66.299842)
		(width 0.254)
		(layer "F.Cu")
		(net "GND")
	)
	(segment
		(start 198.717408 -67.982592)
		(end 198.717408 -68.617338)
		(width 0.254)
		(layer "F.Cu")
		(net "GND")
	)
	(segment
		(start 194.799966 -69.499734)
		(end 194.400424 -69.100192)
		(width 0.254)
		(layer "F.Cu")
		(net "GND")
	)
	(segment
		(start 193.5226 -20.7518)
		(end 193.7258 -20.955)
		(width 0.4064)
		(layer "F.Cu")
		(net "GND")
	)
	(segment
		(start 196.399912 -72.69988)
		(end 196.799708 -73.099676)
		(width 0.3048)
		(layer "F.Cu")
		(net "GND")
	)
	(segment
		(start 43.700192 -141.00048)
		(end 43.700446 -141.00048)
		(width 0.3556)
		(layer "F.Cu")
		(net "GND")
	)
	(segment
		(start 199.600058 -60.699904)
		(end 199.600058 -59.900058)
		(width 0.254)
		(layer "F.Cu")
		(net "GND")
	)
	(segment
		(start 124.46889 -10.682478)
		(end 124.46889 -11.5443)
		(width 0.254)
		(layer "F.Cu")
		(net "GND")
	)
	(segment
		(start 203.197714 -63.492888)
		(end 203.590652 -63.09995)
		(width 0.254)
		(layer "F.Cu")
		(net "GND")
	)
	(segment
		(start 201.190352 -66.299842)
		(end 200.799954 -65.909444)
		(width 0.254)
		(layer "F.Cu")
		(net "GND")
	)
	(segment
		(start 186.80049 -58.299858)
		(end 187.200286 -57.900062)
		(width 0.254)
		(layer "F.Cu")
		(net "GND")
	)
	(segment
		(start 76.751942 -69.749924)
		(end 77.274674 -69.227192)
		(width 0.508)
		(layer "F.Cu")
		(net "GND")
	)
	(segment
		(start 190.799974 -62.29985)
		(end 191.200278 -62.700154)
		(width 0.254)
		(layer "F.Cu")
		(net "GND")
	)
	(segment
		(start 203.193396 -69.102732)
		(end 203.191872 -69.101208)
		(width 0.3048)
		(layer "F.Cu")
		(net "GND")
	)
	(segment
		(start 190.799974 -60.699904)
		(end 191.200278 -61.100208)
		(width 0.254)
		(layer "F.Cu")
		(net "GND")
	)
	(segment
		(start 202.116944 -56.699912)
		(end 202.199748 -56.782716)
		(width 0.254)
		(layer "F.Cu")
		(net "GND")
	)
	(segment
		(start 190.800228 -59.099958)
		(end 191.200024 -58.700162)
		(width 0.254)
		(layer "F.Cu")
		(net "GND")
	)
	(segment
		(start 205.17612 -54.63032)
		(end 204.706474 -55.099966)
		(width 0.254)
		(layer "F.Cu")
		(net "GND")
	)
	(segment
		(start 75.475084 -68.950078)
		(end 76.99756 -68.950078)
		(width 0.254)
		(layer "F.Cu")
		(net "GND")
	)
	(segment
		(start 185.999882 -56.699912)
		(end 185.999882 -57.500012)
		(width 0.254)
		(layer "F.Cu")
		(net "GND")
	)
	(segment
		(start 194.564 -20.955)
		(end 194.80276 -20.71624)
		(width 0.4064)
		(layer "F.Cu")
		(net "GND")
	)
	(segment
		(start 47.29988 -140.600684)
		(end 46.900084 -141.00048)
		(width 0.3048)
		(layer "F.Cu")
		(net "GND")
	)
	(segment
		(start 81.177892 -83.3501)
		(end 81.643728 -83.688936)
		(width 0.508)
		(layer "F.Cu")
		(net "GND")
	)
	(segment
		(start 200.399904 -56.699912)
		(end 200.000108 -56.300116)
		(width 0.254)
		(layer "F.Cu")
		(net "GND")
	)
	(segment
		(start 55.6768 -163.5887)
		(end 55.6768 -164.3888)
		(width 0.254)
		(layer "F.Cu")
		(net "GND")
	)
	(segment
		(start 184.399936 -72.700134)
		(end 183.60009 -73.49998)
		(width 0.254)
		(layer "F.Cu")
		(net "GND")
	)
	(segment
		(start 185.200036 -64.699896)
		(end 185.200036 -64.700404)
		(width 0.254)
		(layer "F.Cu")
		(net "GND")
	)
	(segment
		(start 18.2372 -177.5079)
		(end 18.2499 -177.5206)
		(width 0.508)
		(layer "F.Cu")
		(net "GND")
	)
	(segment
		(start 56.49976 -153.800048)
		(end 56.099964 -153.400252)
		(width 0.254)
		(layer "F.Cu")
		(net "GND")
	)
	(segment
		(start 198.717408 -68.617338)
		(end 198.799958 -68.699888)
		(width 0.254)
		(layer "F.Cu")
		(net "GND")
	)
	(segment
		(start 200.400158 -67.900042)
		(end 201.200004 -68.699888)
		(width 0.254)
		(layer "F.Cu")
		(net "GND")
	)
	(segment
		(start 184.399936 -72.69988)
		(end 184.399936 -72.700134)
		(width 0.254)
		(layer "F.Cu")
		(net "GND")
	)
	(segment
		(start 197.999858 -63.09995)
		(end 198.08571 -63.185802)
		(width 0.254)
		(layer "F.Cu")
		(net "GND")
	)
	(segment
		(start 192.39992 -58.299858)
		(end 192.399666 -58.299858)
		(width 0.254)
		(layer "F.Cu")
		(net "GND")
	)
	(segment
		(start 192.5574 -47.8409)
		(end 192.5574 -47.135796)
		(width 0.508)
		(layer "F.Cu")
		(net "GND")
	)
	(segment
		(start 195.590668 -71.099934)
		(end 195.196206 -71.494396)
		(width 0.254)
		(layer "F.Cu")
		(net "GND")
	)
	(segment
		(start 192.399666 -58.299858)
		(end 192.000124 -57.900316)
		(width 0.254)
		(layer "F.Cu")
		(net "GND")
	)
	(segment
		(start 158.977076 -88.3412)
		(end 158.977076 -87.314024)
		(width 0.254)
		(layer "F.Cu")
		(net "GND")
	)
	(segment
		(start 195.600066 -65.499996)
		(end 196.000116 -65.900046)
		(width 0.254)
		(layer "F.Cu")
		(net "GND")
	)
	(segment
		(start 195.600066 -62.29985)
		(end 195.599812 -62.29985)
		(width 0.254)
		(layer "F.Cu")
		(net "GND")
	)
	(segment
		(start 200.81875 -21.8567)
		(end 201.8411 -21.8567)
		(width 0.508)
		(layer "F.Cu")
		(net "GND")
	)
	(segment
		(start 94.3991 -122.376692)
		(end 94.4626 -122.313192)
		(width 0.254)
		(layer "F.Cu")
		(net "GND")
	)
	(segment
		(start 189.599824 -64.299846)
		(end 189.590934 -64.299846)
		(width 0.254)
		(layer "F.Cu")
		(net "GND")
	)
	(segment
		(start 184.399936 -71.100188)
		(end 184.00014 -71.499984)
		(width 0.254)
		(layer "F.Cu")
		(net "GND")
	)
	(segment
		(start 46.89983 -136.99998)
		(end 47.29988 -136.59993)
		(width 0.254)
		(layer "F.Cu")
		(net "GND")
	)
	(segment
		(start 193.999866 -71.099934)
		(end 193.999866 -71.09968)
		(width 0.254)
		(layer "F.Cu")
		(net "GND")
	)
	(segment
		(start 89.65692 -163.55568)
		(end 89.65692 -163.096956)
		(width 0.254)
		(layer "F.Cu")
		(net "GND")
	)
	(segment
		(start 67.31 -168.293796)
		(end 67.31 -168.5925)
		(width 0.508)
		(layer "F.Cu")
		(net "GND")
	)
	(segment
		(start 187.600336 -68.699888)
		(end 188.000132 -69.099684)
		(width 0.254)
		(layer "F.Cu")
		(net "GND")
	)
	(segment
		(start 181.99989 -62.29985)
		(end 181.99989 -62.290452)
		(width 0.254)
		(layer "F.Cu")
		(net "GND")
	)
	(segment
		(start 197.200012 -61.500004)
		(end 196.399912 -61.500004)
		(width 0.254)
		(layer "F.Cu")
		(net "GND")
	)
	(segment
		(start 70.750684 -161.958528)
		(end 70.750684 -160.8963)
		(width 0.508)
		(layer "F.Cu")
		(net "GND")
	)
	(segment
		(start 198.799704 -58.299858)
		(end 198.400162 -57.900316)
		(width 0.254)
		(layer "F.Cu")
		(net "GND")
	)
	(segment
		(start 61.73724 -136.433306)
		(end 61.834776 -136.530842)
		(width 0.254)
		(layer "F.Cu")
		(net "GND")
	)
	(segment
		(start 124.4727 -11.54811)
		(end 124.4727 -11.6586)
		(width 0.254)
		(layer "F.Cu")
		(net "GND")
	)
	(segment
		(start 88.563958 -29.6418)
		(end 88.370918 -29.83484)
		(width 0.508)
		(layer "F.Cu")
		(net "GND")
	)
	(segment
		(start 204.845158 -63.09995)
		(end 204.399896 -63.09995)
		(width 0.3048)
		(layer "F.Cu")
		(net "GND")
	)
	(segment
		(start 79.925164 -96.149922)
		(end 81.16443 -96.149922)
		(width 0.254)
		(layer "F.Cu")
		(net "GND")
	)
	(segment
		(start 200.399904 -75.900026)
		(end 200.399904 -75.899518)
		(width 0.3048)
		(layer "F.Cu")
		(net "GND")
	)
	(segment
		(start 193.999866 -58.299858)
		(end 194.000374 -58.299858)
		(width 0.254)
		(layer "F.Cu")
		(net "GND")
	)
	(segment
		(start 79.925164 -71.350124)
		(end 81.182464 -71.350124)
		(width 0.508)
		(layer "F.Cu")
		(net "GND")
	)
	(segment
		(start 198.799958 -71.090536)
		(end 199.197722 -70.692772)
		(width 0.254)
		(layer "F.Cu")
		(net "GND")
	)
	(segment
		(start 91.49715 -139.0396)
		(end 91.459304 -139.077446)
		(width 0.254)
		(layer "F.Cu")
		(net "GND")
	)
	(segment
		(start 42.500042 -142.999968)
		(end 42.900092 -142.599918)
		(width 0.3556)
		(layer "F.Cu")
		(net "GND")
	)
	(segment
		(start 68.5546 -144.175226)
		(end 68.498974 -144.1196)
		(width 0.254)
		(layer "F.Cu")
		(net "GND")
	)
	(segment
		(start 201.200004 -62.29477)
		(end 201.592688 -61.902086)
		(width 0.254)
		(layer "F.Cu")
		(net "GND")
	)
	(segment
		(start 27.5844 -145.796)
		(end 27.5844 -146.565366)
		(width 0.508)
		(layer "F.Cu")
		(net "GND")
	)
	(segment
		(start 79.925164 -77.749908)
		(end 81.319116 -77.749908)
		(width 0.508)
		(layer "F.Cu")
		(net "GND")
	)
	(segment
		(start 17.634458 -147.761452)
		(end 17.234408 -148.161502)
		(width 0.254)
		(layer "F.Cu")
		(net "GND")
	)
	(segment
		(start 187.993528 -61.09335)
		(end 187.993528 -61.102748)
		(width 0.254)
		(layer "F.Cu")
		(net "GND")
	)
	(segment
		(start 195.600066 -67.099942)
		(end 195.600066 -67.100196)
		(width 0.254)
		(layer "F.Cu")
		(net "GND")
	)
	(segment
		(start 42.500042 -146.19986)
		(end 43.299888 -145.400014)
		(width 0.3556)
		(layer "F.Cu")
		(net "GND")
	)
	(segment
		(start 81.371948 -73.749916)
		(end 81.758028 -74.135996)
		(width 0.508)
		(layer "F.Cu")
		(net "GND")
	)
	(segment
		(start 192.280032 -69.499988)
		(end 192.39992 -69.499988)
		(width 0.254)
		(layer "F.Cu")
		(net "GND")
	)
	(segment
		(start 81.182464 -80.950054)
		(end 81.643728 -80.48879)
		(width 0.508)
		(layer "F.Cu")
		(net "GND")
	)
	(segment
		(start 201.19975 -73.49998)
		(end 200.7997 -73.09993)
		(width 0.254)
		(layer "F.Cu")
		(net "GND")
	)
	(segment
		(start 200.399904 -69.493384)
		(end 200.791826 -69.101462)
		(width 0.254)
		(layer "F.Cu")
		(net "GND")
	)
	(segment
		(start 185.7756 -91.3003)
		(end 185.7756 -92.1258)
		(width 0.508)
		(layer "F.Cu")
		(net "GND")
	)
	(segment
		(start 187.600082 -69.499988)
		(end 188.000132 -69.900038)
		(width 0.254)
		(layer "F.Cu")
		(net "GND")
	)
	(segment
		(start 185.599832 -73.899776)
		(end 185.200036 -73.49998)
		(width 0.3048)
		(layer "F.Cu")
		(net "GND")
	)
	(segment
		(start 52.899818 -150.199852)
		(end 52.499768 -150.599902)
		(width 0.254)
		(layer "F.Cu")
		(net "GND")
	)
	(segment
		(start 48.899826 -144.599914)
		(end 48.899826 -144.600168)
		(width 0.3556)
		(layer "F.Cu")
		(net "GND")
	)
	(segment
		(start 90.81389 -167.141652)
		(end 94.5388 -167.141652)
		(width 0.508)
		(layer "F.Cu")
		(net "GND")
	)
	(segment
		(start 187.600082 -74.299826)
		(end 187.599828 -74.299826)
		(width 0.3048)
		(layer "F.Cu")
		(net "GND")
	)
	(segment
		(start 42.9006 -161.8107)
		(end 42.926 -161.8361)
		(width 0.254)
		(layer "F.Cu")
		(net "GND")
	)
	(segment
		(start 75.475084 -72.14997)
		(end 76.74102 -72.14997)
		(width 0.508)
		(layer "F.Cu")
		(net "GND")
	)
	(segment
		(start 156.556202 -96.384872)
		(end 156.572712 -96.401382)
		(width 0.254)
		(layer "F.Cu")
		(net "GND")
	)
	(segment
		(start 85.7885 -150.368)
		(end 85.7885 -149.793706)
		(width 0.254)
		(layer "F.Cu")
		(net "GND")
	)
	(segment
		(start 195.600066 -69.499988)
		(end 194.799966 -69.499988)
		(width 0.254)
		(layer "F.Cu")
		(net "GND")
	)
	(segment
		(start 189.999874 -71.909432)
		(end 190.396622 -72.30618)
		(width 0.254)
		(layer "F.Cu")
		(net "GND")
	)
	(segment
		(start 187.600082 -63.90005)
		(end 187.600336 -63.90005)
		(width 0.254)
		(layer "F.Cu")
		(net "GND")
	)
	(segment
		(start 34.293048 -129.5908)
		(end 30.6578 -129.5908)
		(width 0.381)
		(layer "F.Cu")
		(net "GND")
	)
	(segment
		(start 82.663538 -136.171686)
		(end 83.479386 -136.171686)
		(width 0.508)
		(layer "F.Cu")
		(net "GND")
	)
	(segment
		(start 67.7291 -158.20898)
		(end 68.6816 -158.20898)
		(width 0.254)
		(layer "F.Cu")
		(net "GND")
	)
	(segment
		(start 201.698352 -130.089148)
		(end 202.520042 -130.089148)
		(width 0.508)
		(layer "F.Cu")
		(net "GND")
	)
	(segment
		(start 200.399904 -69.499988)
		(end 200.399904 -69.493384)
		(width 0.254)
		(layer "F.Cu")
		(net "GND")
	)
	(segment
		(start 94.3991 -123.09856)
		(end 94.3991 -122.376692)
		(width 0.254)
		(layer "F.Cu")
		(net "GND")
	)
	(segment
		(start 88.087962 -134.3533)
		(end 87.756238 -134.021576)
		(width 0.254)
		(layer "F.Cu")
		(net "GND")
	)
	(segment
		(start 200.88225 -16.9545)
		(end 202.141328 -16.9545)
		(width 0.508)
		(layer "F.Cu")
		(net "GND")
	)
	(segment
		(start 201.897488 -63.036958)
		(end 201.53376 -62.67323)
		(width 0.254)
		(layer "F.Cu")
		(net "GND")
	)
	(segment
		(start 194.799966 -63.09995)
		(end 194.399916 -62.6999)
		(width 0.254)
		(layer "F.Cu")
		(net "GND")
	)
	(segment
		(start 52.9971 -127.4699)
		(end 52.705 -127.762)
		(width 0.508)
		(layer "F.Cu")
		(net "GND")
	)
	(segment
		(start 178.517296 -119.61622)
		(end 178.517296 -121.024904)
		(width 0.3556)
		(layer "F.Cu")
		(net "GND")
	)
	(segment
		(start 204.210666 -64.601344)
		(end 204.309218 -64.699896)
		(width 0.3048)
		(layer "F.Cu")
		(net "GND")
	)
	(segment
		(start 47.29988 -146.99996)
		(end 47.69993 -146.59991)
		(width 0.3556)
		(layer "F.Cu")
		(net "GND")
	)
	(segment
		(start 75.475084 -52.15001)
		(end 77.63891 -52.15001)
		(width 0.508)
		(layer "F.Cu")
		(net "GND")
	)
	(segment
		(start 180.7718 -89.429082)
		(end 180.953918 -89.6112)
		(width 0.508)
		(layer "F.Cu")
		(net "GND")
	)
	(segment
		(start 200.399904 -72.700134)
		(end 200.7997 -73.09993)
		(width 0.254)
		(layer "F.Cu")
		(net "GND")
	)
	(segment
		(start 191.793876 -69.58584)
		(end 192.19418 -69.58584)
		(width 0.254)
		(layer "F.Cu")
		(net "GND")
	)
	(segment
		(start 182.79872 -62.29985)
		(end 182.394606 -61.895736)
		(width 0.254)
		(layer "F.Cu")
		(net "GND")
	)
	(segment
		(start 75.475084 -85.750146)
		(end 77.02804 -85.750146)
		(width 0.508)
		(layer "F.Cu")
		(net "GND")
	)
	(segment
		(start 85.826346 -149.75586)
		(end 85.826346 -149.319996)
		(width 0.254)
		(layer "F.Cu")
		(net "GND")
	)
	(segment
		(start 75.475084 -82.55)
		(end 76.748386 -82.55)
		(width 0.508)
		(layer "F.Cu")
		(net "GND")
	)
	(segment
		(start 88.00211 -178.60899)
		(end 88.383872 -178.60899)
		(width 0.508)
		(layer "F.Cu")
		(net "GND")
	)
	(segment
		(start 188.399928 -59.900058)
		(end 189.200028 -59.900058)
		(width 0.254)
		(layer "F.Cu")
		(net "GND")
	)
	(segment
		(start 30.3276 -130.4417)
		(end 29.8958 -130.8735)
		(width 0.508)
		(layer "F.Cu")
		(net "GND")
	)
	(segment
		(start 76.99756 -68.950078)
		(end 77.274674 -69.227192)
		(width 0.254)
		(layer "F.Cu")
		(net "GND")
	)
	(segment
		(start 92.9132 -126.5682)
		(end 92.4052 -126.5682)
		(width 0.254)
		(layer "F.Cu")
		(net "GND")
	)
	(segment
		(start 193.999866 -68.699888)
		(end 194.00012 -68.699888)
		(width 0.254)
		(layer "F.Cu")
		(net "GND")
	)
	(segment
		(start 90.59672 -148.745956)
		(end 90.59672 -148.333968)
		(width 0.508)
		(layer "F.Cu")
		(net "GND")
	)
	(segment
		(start 48.100234 -143.800068)
		(end 48.50003 -144.199864)
		(width 0.3556)
		(layer "F.Cu")
		(net "GND")
	)
	(segment
		(start 198.804784 -70.299834)
		(end 199.197722 -70.692772)
		(width 0.254)
		(layer "F.Cu")
		(net "GND")
	)
	(segment
		(start 74.490834 -141.540992)
		(end 75.403964 -140.627862)
		(width 0.508)
		(layer "F.Cu")
		(net "GND")
	)
	(segment
		(start 193.20002 -72.69988)
		(end 193.20002 -72.708262)
		(width 0.254)
		(layer "F.Cu")
		(net "GND")
	)
	(segment
		(start 160.9852 -85.8393)
		(end 160.3375 -85.8393)
		(width 0.508)
		(layer "F.Cu")
		(net "GND")
	)
	(segment
		(start 197.999858 -67.900042)
		(end 197.999858 -67.897248)
		(width 0.254)
		(layer "F.Cu")
		(net "GND")
	)
	(segment
		(start 188.233812 -64.866266)
		(end 188.000132 -65.099946)
		(width 0.254)
		(layer "F.Cu")
		(net "GND")
	)
	(segment
		(start 193.20002 -68.699888)
		(end 193.20002 -68.709286)
		(width 0.254)
		(layer "F.Cu")
		(net "GND")
	)
	(segment
		(start 201.200004 -66.299842)
		(end 201.190352 -66.299842)
		(width 0.254)
		(layer "F.Cu")
		(net "GND")
	)
	(segment
		(start 81.177892 -89.750138)
		(end 81.643728 -90.088974)
		(width 0.508)
		(layer "F.Cu")
		(net "GND")
	)
	(segment
		(start 79.925164 -55.349902)
		(end 81.240122 -55.349902)
		(width 0.254)
		(layer "F.Cu")
		(net "GND")
	)
	(segment
		(start 95.070168 -148.1709)
		(end 95.070168 -147.3962)
		(width 0.254)
		(layer "F.Cu")
		(net "GND")
	)
	(segment
		(start 155.5242 -87.4522)
		(end 155.7401 -87.4522)
		(width 0.254)
		(layer "F.Cu")
		(net "GND")
	)
	(segment
		(start 190.799466 -73.49998)
		(end 190.39967 -73.899776)
		(width 0.3048)
		(layer "F.Cu")
		(net "GND")
	)
	(segment
		(start 202.79995 -71.099426)
		(end 202.79995 -71.099934)
		(width 0.3048)
		(layer "F.Cu")
		(net "GND")
	)
	(segment
		(start 91.05392 -32.39008)
		(end 91.05392 -38.952678)
		(width 0.508)
		(layer "F.Cu")
		(net "GND")
	)
	(segment
		(start 99.6696 -177.08372)
		(end 99.75088 -177.165)
		(width 0.508)
		(layer "F.Cu")
		(net "GND")
	)
	(segment
		(start 78.43901 -52.95011)
		(end 79.925164 -52.95011)
		(width 0.508)
		(layer "F.Cu")
		(net "GND")
	)
	(segment
		(start 69.96938 -154.55392)
		(end 74.199242 -154.55392)
		(width 0.254)
		(layer "F.Cu")
		(net "GND")
	)
	(segment
		(start 51.7271 -161.6964)
		(end 51.33594 -161.6964)
		(width 0.508)
		(layer "F.Cu")
		(net "GND")
	)
	(segment
		(start 196.399912 -55.900066)
		(end 196.800216 -56.30037)
		(width 0.254)
		(layer "F.Cu")
		(net "GND")
	)
	(segment
		(start 61.627004 -175.964596)
		(end 62.476634 -175.964596)
		(width 0.254)
		(layer "F.Cu")
		(net "GND")
	)
	(segment
		(start 91.459304 -139.077446)
		(end 90.357706 -139.077446)
		(width 0.254)
		(layer "F.Cu")
		(net "GND")
	)
	(segment
		(start 201.665078 -28.812744)
		(end 201.373994 -28.812744)
		(width 0.508)
		(layer "F.Cu")
		(net "GND")
	)
	(segment
		(start 71.60514 -163.6395)
		(end 71.60514 -162.79114)
		(width 0.508)
		(layer "F.Cu")
		(net "GND")
	)
	(segment
		(start 50.899822 -151.400002)
		(end 50.500026 -151.799798)
		(width 0.3556)
		(layer "F.Cu")
		(net "GND")
	)
	(segment
		(start 185.999882 -68.699888)
		(end 185.60034 -68.300346)
		(width 0.254)
		(layer "F.Cu")
		(net "GND")
	)
	(segment
		(start 183.60009 -57.499758)
		(end 184.399936 -56.699912)
		(width 0.254)
		(layer "F.Cu")
		(net "GND")
	)
	(segment
		(start 197.200012 -71.109586)
		(end 197.59041 -71.499984)
		(width 0.254)
		(layer "F.Cu")
		(net "GND")
	)
	(segment
		(start 194.799966 -59.099958)
		(end 194.399916 -58.699908)
		(width 0.254)
		(layer "F.Cu")
		(net "GND")
	)
	(segment
		(start 183.60009 -62.300358)
		(end 183.200294 -62.700154)
		(width 0.254)
		(layer "F.Cu")
		(net "GND")
	)
	(segment
		(start 200.399904 -70.306438)
		(end 200.004426 -70.701916)
		(width 0.254)
		(layer "F.Cu")
		(net "GND")
	)
	(segment
		(start 204.706474 -55.099966)
		(end 204.399896 -55.099966)
		(width 0.254)
		(layer "F.Cu")
		(net "GND")
	)
	(segment
		(start 185.999882 -74.299826)
		(end 185.599832 -73.899776)
		(width 0.3048)
		(layer "F.Cu")
		(net "GND")
	)
	(segment
		(start 189.200028 -58.299858)
		(end 189.200536 -58.299858)
		(width 0.254)
		(layer "F.Cu")
		(net "GND")
	)
	(segment
		(start 23.234396 -146.961606)
		(end 23.234396 -146.961352)
		(width 0.254)
		(layer "F.Cu")
		(net "GND")
	)
	(segment
		(start 190.799974 -72.69988)
		(end 190.799974 -73.49998)
		(width 0.254)
		(layer "F.Cu")
		(net "GND")
	)
	(segment
		(start 51.0159 -128.001522)
		(end 51.639978 -128.6256)
		(width 0.508)
		(layer "F.Cu")
		(net "GND")
	)
	(segment
		(start 200.399904 -67.900042)
		(end 200.400158 -67.900042)
		(width 0.254)
		(layer "F.Cu")
		(net "GND")
	)
	(segment
		(start 46.900084 -145.800064)
		(end 47.29988 -145.400268)
		(width 0.3556)
		(layer "F.Cu")
		(net "GND")
	)
	(segment
		(start 79.925164 -80.950054)
		(end 81.182464 -80.950054)
		(width 0.508)
		(layer "F.Cu")
		(net "GND")
	)
	(segment
		(start 192.52565 -71.099934)
		(end 192.603628 -71.021956)
		(width 0.254)
		(layer "F.Cu")
		(net "GND")
	)
	(segment
		(start 186.000136 -67.099942)
		(end 186.399932 -67.499738)
		(width 0.254)
		(layer "F.Cu")
		(net "GND")
	)
	(segment
		(start 205.14437 -123.625102)
		(end 205.14437 -124.487178)
		(width 0.254)
		(layer "F.Cu")
		(net "GND")
	)
	(segment
		(start 226.682046 -60.205112)
		(end 226.682046 -61.277246)
		(width 0.254)
		(layer "F.Cu")
		(net "GND")
	)
	(segment
		(start 83.441286 -140.74013)
		(end 84.03844 -140.142976)
		(width 0.508)
		(layer "F.Cu")
		(net "GND")
	)
	(segment
		(start 97.9424 -134.393178)
		(end 97.9424 -135.2423)
		(width 0.508)
		(layer "F.Cu")
		(net "GND")
	)
	(segment
		(start 77.490828 -62.959996)
		(end 77.837284 -62.959996)
		(width 0.254)
		(layer "F.Cu")
		(net "GND")
	)
	(segment
		(start 16.834612 -142.961614)
		(end 16.834104 -142.961614)
		(width 0.3048)
		(layer "F.Cu")
		(net "GND")
	)
	(segment
		(start 202.79995 -74.299826)
		(end 202.79995 -74.299572)
		(width 0.3048)
		(layer "F.Cu")
		(net "GND")
	)
	(segment
		(start 73.92162 -158.86684)
		(end 69.33946 -158.86684)
		(width 0.254)
		(layer "F.Cu")
		(net "GND")
	)
	(segment
		(start 94.6404 -146.356578)
		(end 94.46895 -146.528028)
		(width 0.254)
		(layer "F.Cu")
		(net "GND")
	)
	(segment
		(start 209.1055 -81.915)
		(end 209.1055 -81.1149)
		(width 0.508)
		(layer "F.Cu")
		(net "GND")
	)
	(segment
		(start 196.399912 -75.099926)
		(end 196.491098 -75.099926)
		(width 0.3048)
		(layer "F.Cu")
		(net "GND")
	)
	(segment
		(start 192.39992 -69.509132)
		(end 192.793874 -69.903086)
		(width 0.254)
		(layer "F.Cu")
		(net "GND")
	)
	(segment
		(start 90.17 -163.904676)
		(end 90.4748 -163.599876)
		(width 0.254)
		(layer "F.Cu")
		(net "GND")
	)
	(segment
		(start 191.600582 -58.299858)
		(end 192.000124 -57.900316)
		(width 0.254)
		(layer "F.Cu")
		(net "GND")
	)
	(segment
		(start 184.399936 -62.29985)
		(end 184.80024 -62.700154)
		(width 0.254)
		(layer "F.Cu")
		(net "GND")
	)
	(segment
		(start 89.092024 -166.76497)
		(end 89.092024 -166.95928)
		(width 0.508)
		(layer "F.Cu")
		(net "GND")
	)
	(segment
		(start 184.399936 -58.300112)
		(end 183.60009 -59.099958)
		(width 0.254)
		(layer "F.Cu")
		(net "GND")
	)
	(segment
		(start 201.5998 -60.300108)
		(end 201.600054 -60.300108)
		(width 0.254)
		(layer "F.Cu")
		(net "GND")
	)
	(segment
		(start 202.727814 -64.699896)
		(end 202.79995 -64.699896)
		(width 0.3048)
		(layer "F.Cu")
		(net "GND")
	)
	(segment
		(start 81.182464 -87.350092)
		(end 81.643728 -86.888828)
		(width 0.508)
		(layer "F.Cu")
		(net "GND")
	)
	(segment
		(start 186.799982 -71.900034)
		(end 186.800236 -71.900034)
		(width 0.254)
		(layer "F.Cu")
		(net "GND")
	)
	(segment
		(start 75.475084 -79.350108)
		(end 77.027278 -79.350108)
		(width 0.508)
		(layer "F.Cu")
		(net "GND")
	)
	(segment
		(start 198.799958 -71.099934)
		(end 198.799958 -71.090536)
		(width 0.254)
		(layer "F.Cu")
		(net "GND")
	)
	(segment
		(start 8.65378 -13.73378)
		(end 7.59206 -13.73378)
		(width 0.508)
		(layer "F.Cu")
		(net "GND")
	)
	(segment
		(start 79.925164 -83.3501)
		(end 81.177892 -83.3501)
		(width 0.508)
		(layer "F.Cu")
		(net "GND")
	)
	(segment
		(start 180.06314 -83.9724)
		(end 179.8574 -84.17814)
		(width 0.254)
		(layer "F.Cu")
		(net "GND")
	)
	(segment
		(start 203.60005 -54.299866)
		(end 203.611734 -54.299866)
		(width 0.254)
		(layer "F.Cu")
		(net "GND")
	)
	(segment
		(start 80.040734 -149.08276)
		(end 79.801974 -148.844)
		(width 0.381)
		(layer "F.Cu")
		(net "GND")
	)
	(segment
		(start 199.600058 -67.900042)
		(end 200.399904 -67.900042)
		(width 0.254)
		(layer "F.Cu")
		(net "GND")
	)
	(segment
		(start 187.600336 -63.90005)
		(end 188.000132 -64.299846)
		(width 0.254)
		(layer "F.Cu")
		(net "GND")
	)
	(segment
		(start 185.999882 -66.299842)
		(end 185.999882 -67.099942)
		(width 0.254)
		(layer "F.Cu")
		(net "GND")
	)
	(segment
		(start 202.392788 -65.097406)
		(end 202.392788 -65.034922)
		(width 0.3048)
		(layer "F.Cu")
		(net "GND")
	)
	(segment
		(start 191.600074 -66.299842)
		(end 191.200278 -65.900046)
		(width 0.254)
		(layer "F.Cu")
		(net "GND")
	)
	(segment
		(start 193.999866 -75.099926)
		(end 193.993262 -75.099926)
		(width 0.254)
		(layer "F.Cu")
		(net "GND")
	)
	(segment
		(start 201.53376 -62.67323)
		(end 201.53376 -62.633606)
		(width 0.254)
		(layer "F.Cu")
		(net "GND")
	)
	(segment
		(start 198.799958 -68.699888)
		(end 198.80961 -68.699888)
		(width 0.254)
		(layer "F.Cu")
		(net "GND")
	)
	(segment
		(start 189.200028 -60.699904)
		(end 189.200028 -60.700158)
		(width 0.254)
		(layer "F.Cu")
		(net "GND")
	)
	(segment
		(start 197.999858 -69.499988)
		(end 197.999858 -69.500496)
		(width 0.254)
		(layer "F.Cu")
		(net "GND")
	)
	(segment
		(start 201.200004 -55.900066)
		(end 201.600054 -56.300116)
		(width 0.254)
		(layer "F.Cu")
		(net "GND")
	)
	(segment
		(start 198.799958 -62.29985)
		(end 198.80961 -62.29985)
		(width 0.254)
		(layer "F.Cu")
		(net "GND")
	)
	(segment
		(start 195.600066 -70.299834)
		(end 194.799966 -70.299834)
		(width 0.254)
		(layer "F.Cu")
		(net "GND")
	)
	(segment
		(start 16.834104 -142.961614)
		(end 16.434054 -143.361664)
		(width 0.3048)
		(layer "F.Cu")
		(net "GND")
	)
	(segment
		(start 78.71841 -52.15001)
		(end 79.925164 -52.15001)
		(width 0.508)
		(layer "F.Cu")
		(net "GND")
	)
	(segment
		(start 198.799958 -64.699896)
		(end 198.80961 -64.699896)
		(width 0.254)
		(layer "F.Cu")
		(net "GND")
	)
	(segment
		(start 167.64 -110.9726)
		(end 166.3954 -110.9726)
		(width 0.508)
		(layer "F.Cu")
		(net "GND")
	)
	(segment
		(start 197.200012 -62.29985)
		(end 197.200012 -63.09995)
		(width 0.254)
		(layer "F.Cu")
		(net "GND")
	)
	(segment
		(start 192.39992 -65.50914)
		(end 192.793874 -65.903094)
		(width 0.254)
		(layer "F.Cu")
		(net "GND")
	)
	(segment
		(start 186.000136 -71.900034)
		(end 186.400186 -71.499984)
		(width 0.254)
		(layer "F.Cu")
		(net "GND")
	)
	(segment
		(start 186.799982 -67.900042)
		(end 186.800236 -67.900042)
		(width 0.254)
		(layer "F.Cu")
		(net "GND")
	)
	(segment
		(start 18.434558 -145.36166)
		(end 19.0627 -145.36166)
		(width 0.254)
		(layer "F.Cu")
		(net "GND")
	)
	(segment
		(start 196.399912 -60.69965)
		(end 196.00037 -60.300108)
		(width 0.254)
		(layer "F.Cu")
		(net "GND")
	)
	(segment
		(start 38.544246 -176.69891)
		(end 37.680646 -176.69891)
		(width 0.508)
		(layer "F.Cu")
		(net "GND")
	)
	(segment
		(start 185.200036 -58.299858)
		(end 185.200036 -58.29046)
		(width 0.254)
		(layer "F.Cu")
		(net "GND")
	)
	(segment
		(start 66.884042 -161.123122)
		(end 67.781678 -161.123122)
		(width 0.254)
		(layer "F.Cu")
		(net "GND")
	)
	(segment
		(start 217.822526 -98.649282)
		(end 217.822526 -99.420934)
		(width 0.508)
		(layer "F.Cu")
		(net "GND")
	)
	(segment
		(start 228.17074 -76.581)
		(end 228.731826 -76.019914)
		(width 0.508)
		(layer "F.Cu")
		(net "GND")
	)
	(segment
		(start 200.399904 -66.299842)
		(end 200.409556 -66.299842)
		(width 0.254)
		(layer "F.Cu")
		(net "GND")
	)
	(segment
		(start 42.926 -161.8361)
		(end 42.926 -162.6362)
		(width 0.254)
		(layer "F.Cu")
		(net "GND")
	)
	(segment
		(start 90.254582 -165.564058)
		(end 90.17 -165.64864)
		(width 0.254)
		(layer "F.Cu")
		(net "GND")
	)
	(segment
		(start 40.099488 -142.199868)
		(end 40.099996 -142.199868)
		(width 0.3556)
		(layer "F.Cu")
		(net "GND")
	)
	(segment
		(start 62.611 -152.781)
		(end 62.5856 -152.781)
		(width 0.254)
		(layer "F.Cu")
		(net "GND")
	)
	(segment
		(start 71.60514 -162.79114)
		(end 71.6026 -162.7886)
		(width 0.508)
		(layer "F.Cu")
		(net "GND")
	)
	(segment
		(start 199.600058 -63.096902)
		(end 199.206358 -62.703202)
		(width 0.254)
		(layer "F.Cu")
		(net "GND")
	)
	(segment
		(start 197.999858 -67.897248)
		(end 197.605904 -67.503294)
		(width 0.254)
		(layer "F.Cu")
		(net "GND")
	)
	(segment
		(start 54.713124 -162.926268)
		(end 53.773324 -162.926268)
		(width 0.508)
		(layer "F.Cu")
		(net "GND")
	)
	(segment
		(start 197.018656 -75.206352)
		(end 197.125082 -75.099926)
		(width 0.3048)
		(layer "F.Cu")
		(net "GND")
	)
	(segment
		(start 47.29988 -145.400268)
		(end 47.29988 -145.400014)
		(width 0.3556)
		(layer "F.Cu")
		(net "GND")
	)
	(segment
		(start 66.276474 -177.741326)
		(end 66.276474 -175.913796)
		(width 0.4064)
		(layer "F.Cu")
		(net "GND")
	)
	(segment
		(start 27.99588 -122.414792)
		(end 28.97378 -122.414792)
		(width 0.508)
		(layer "F.Cu")
		(net "GND")
	)
	(segment
		(start 195.60032 -75.099926)
		(end 195.600066 -75.099926)
		(width 0.3048)
		(layer "F.Cu")
		(net "GND")
	)
	(segment
		(start 195.600066 -57.500012)
		(end 196.399912 -57.500012)
		(width 0.254)
		(layer "F.Cu")
		(net "GND")
	)
	(segment
		(start 187.600082 -68.699888)
		(end 187.600336 -68.699888)
		(width 0.254)
		(layer "F.Cu")
		(net "GND")
	)
	(segment
		(start 187.600336 -71.900034)
		(end 188.000386 -71.499984)
		(width 0.254)
		(layer "F.Cu")
		(net "GND")
	)
	(segment
		(start 191.600074 -59.099958)
		(end 191.600328 -59.099958)
		(width 0.254)
		(layer "F.Cu")
		(net "GND")
	)
	(segment
		(start 181.399942 -62.3824)
		(end 181.800246 -62.3824)
		(width 0.254)
		(layer "F.Cu")
		(net "GND")
	)
	(segment
		(start 74.199242 -154.55392)
		(end 74.91984 -155.274518)
		(width 0.254)
		(layer "F.Cu")
		(net "GND")
	)
	(segment
		(start 95.0468 -166.633652)
		(end 95.0468 -164.051234)
		(width 0.508)
		(layer "F.Cu")
		(net "GND")
	)
	(segment
		(start 187.599828 -56.699912)
		(end 187.200032 -56.300116)
		(width 0.254)
		(layer "F.Cu")
		(net "GND")
	)
	(segment
		(start 186.799982 -61.500004)
		(end 186.800236 -61.500004)
		(width 0.254)
		(layer "F.Cu")
		(net "GND")
	)
	(segment
		(start 193.209164 -73.49998)
		(end 193.606166 -73.896982)
		(width 0.254)
		(layer "F.Cu")
		(net "GND")
	)
	(segment
		(start 88.383872 -178.60899)
		(end 88.527382 -178.46548)
		(width 0.508)
		(layer "F.Cu")
		(net "GND")
	)
	(segment
		(start 75.475084 -76.149962)
		(end 76.747624 -76.149962)
		(width 0.508)
		(layer "F.Cu")
		(net "GND")
	)
	(segment
		(start 196.399912 -68.699888)
		(end 196.409056 -68.699888)
		(width 0.254)
		(layer "F.Cu")
		(net "GND")
	)
	(segment
		(start 201.600054 -60.299854)
		(end 201.600054 -60.300108)
		(width 0.254)
		(layer "F.Cu")
		(net "GND")
	)
	(segment
		(start 194.801744 -71.099934)
		(end 195.196206 -71.494396)
		(width 0.254)
		(layer "F.Cu")
		(net "GND")
	)
	(segment
		(start 56.28005 -174.994824)
		(end 56.28005 -176.6316)
		(width 0.508)
		(layer "F.Cu")
		(net "GND")
	)
	(segment
		(start 193.20002 -73.49998)
		(end 193.209164 -73.49998)
		(width 0.254)
		(layer "F.Cu")
		(net "GND")
	)
	(segment
		(start 201.99985 -58.299858)
		(end 201.600054 -58.699654)
		(width 0.254)
		(layer "F.Cu")
		(net "GND")
	)
	(segment
		(start 184.399936 -66.299842)
		(end 184.40019 -66.299842)
		(width 0.254)
		(layer "F.Cu")
		(net "GND")
	)
	(segment
		(start 91.6432 -125.8062)
		(end 91.6432 -125.7935)
		(width 0.254)
		(layer "F.Cu")
		(net "GND")
	)
	(segment
		(start 59.436 -159.0675)
		(end 59.436 -159.912304)
		(width 0.508)
		(layer "F.Cu")
		(net "GND")
	)
	(segment
		(start 199.598026 -65.499996)
		(end 199.203818 -65.894204)
		(width 0.254)
		(layer "F.Cu")
		(net "GND")
	)
	(segment
		(start 186.800236 -57.500012)
		(end 187.200286 -57.900062)
		(width 0.254)
		(layer "F.Cu")
		(net "GND")
	)
	(segment
		(start 195.600066 -75.900026)
		(end 195.600066 -75.899772)
		(width 0.3048)
		(layer "F.Cu")
		(net "GND")
	)
	(segment
		(start 59.436 -159.0675)
		(end 60.452 -159.0675)
		(width 0.508)
		(layer "F.Cu")
		(net "GND")
	)
	(segment
		(start 68.3768 -144.1196)
		(end 68.3514 -144.0942)
		(width 0.254)
		(layer "F.Cu")
		(net "GND")
	)
	(segment
		(start 52.499768 -141.00048)
		(end 52.499514 -141.00048)
		(width 0.3556)
		(layer "F.Cu")
		(net "GND")
	)
	(segment
		(start 185.200036 -69.499988)
		(end 184.799986 -69.099938)
		(width 0.254)
		(layer "F.Cu")
		(net "GND")
	)
	(segment
		(start 16.834612 -141.361668)
		(end 17.234662 -141.761718)
		(width 0.3048)
		(layer "F.Cu")
		(net "GND")
	)
	(segment
		(start 77.648562 -51.34991)
		(end 77.91831 -51.34991)
		(width 0.508)
		(layer "F.Cu")
		(net "GND")
	)
	(segment
		(start 185.20029 -71.900034)
		(end 185.60034 -71.499984)
		(width 0.254)
		(layer "F.Cu")
		(net "GND")
	)
	(segment
		(start 190.79972 -56.699912)
		(end 190.399924 -56.300116)
		(width 0.254)
		(layer "F.Cu")
		(net "GND")
	)
	(segment
		(start 78.289912 -137.26541)
		(end 77.737208 -137.26541)
		(width 0.254)
		(layer "F.Cu")
		(net "GND")
	)
	(segment
		(start 194.80276 -20.71624)
		(end 194.80276 -20.0025)
		(width 0.4064)
		(layer "F.Cu")
		(net "GND")
	)
	(segment
		(start 22.43455 -143.76146)
		(end 22.0345 -144.16151)
		(width 0.3048)
		(layer "F.Cu")
		(net "GND")
	)
	(segment
		(start 192.400174 -71.900034)
		(end 193.20002 -72.69988)
		(width 0.254)
		(layer "F.Cu")
		(net "GND")
	)
	(segment
		(start 48.899826 -146.200114)
		(end 48.50003 -146.59991)
		(width 0.3556)
		(layer "F.Cu")
		(net "GND")
	)
	(segment
		(start 190.799974 -63.90894)
		(end 191.19088 -64.299846)
		(width 0.254)
		(layer "F.Cu")
		(net "GND")
	)
	(segment
		(start 81.304892 -80.149954)
		(end 81.643728 -80.48879)
		(width 0.508)
		(layer "F.Cu")
		(net "GND")
	)
	(segment
		(start 74.91984 -157.86862)
		(end 73.92162 -158.86684)
		(width 0.254)
		(layer "F.Cu")
		(net "GND")
	)
	(segment
		(start 186.799982 -67.099942)
		(end 186.800236 -67.099942)
		(width 0.254)
		(layer "F.Cu")
		(net "GND")
	)
	(segment
		(start 182.79999 -62.29985)
		(end 182.79872 -62.29985)
		(width 0.254)
		(layer "F.Cu")
		(net "GND")
	)
	(segment
		(start 198.08571 -63.185802)
		(end 198.714106 -63.185802)
		(width 0.254)
		(layer "F.Cu")
		(net "GND")
	)
	(segment
		(start 46.500034 -143.800068)
		(end 46.500288 -143.800068)
		(width 0.3556)
		(layer "F.Cu")
		(net "GND")
	)
	(segment
		(start 70.9549 -174.3329)
		(end 70.19544 -174.3329)
		(width 0.4064)
		(layer "F.Cu")
		(net "GND")
	)
	(segment
		(start 76.718414 -65.749932)
		(end 77.274674 -66.306192)
		(width 0.508)
		(layer "F.Cu")
		(net "GND")
	)
	(segment
		(start 200.579736 -74.92492)
		(end 200.579736 -74.565764)
		(width 0.254)
		(layer "F.Cu")
		(net "GND")
	)
	(segment
		(start 178.42484 -121.11736)
		(end 178.517296 -121.024904)
		(width 0.508)
		(layer "F.Cu")
		(net "GND")
	)
	(segment
		(start 16.834612 -136.561576)
		(end 16.833342 -136.561576)
		(width 0.3048)
		(layer "F.Cu")
		(net "GND")
	)
	(segment
		(start 193.20002 -57.500012)
		(end 193.999866 -57.500012)
		(width 0.254)
		(layer "F.Cu")
		(net "GND")
	)
	(segment
		(start 193.991484 -71.900034)
		(end 193.596006 -71.504556)
		(width 0.254)
		(layer "F.Cu")
		(net "GND")
	)
	(segment
		(start 193.20002 -54.299866)
		(end 193.200274 -54.299866)
		(width 0.254)
		(layer "F.Cu")
		(net "GND")
	)
	(segment
		(start 201.200004 -73.49998)
		(end 201.19975 -73.49998)
		(width 0.254)
		(layer "F.Cu")
		(net "GND")
	)
	(segment
		(start 193.7258 -20.955)
		(end 194.564 -20.955)
		(width 0.4064)
		(layer "F.Cu")
		(net "GND")
	)
	(segment
		(start 47.29988 -140.599922)
		(end 47.29988 -140.600684)
		(width 0.3048)
		(layer "F.Cu")
		(net "GND")
	)
	(segment
		(start 185.200036 -71.099934)
		(end 184.799986 -70.699884)
		(width 0.254)
		(layer "F.Cu")
		(net "GND")
	)
	(segment
		(start 121.2596 -17.6022)
		(end 121.2342 -17.5768)
		(width 0.508)
		(layer "F.Cu")
		(net "GND")
	)
	(segment
		(start 52.9971 -126.8222)
		(end 52.9971 -127.4699)
		(width 0.508)
		(layer "F.Cu")
		(net "GND")
	)
	(segment
		(start 196.000116 -64.3001)
		(end 196.399912 -64.699896)
		(width 0.254)
		(layer "F.Cu")
		(net "GND")
	)
	(segment
		(start 77.274928 -54.311296)
		(end 77.596492 -54.311296)
		(width 0.254)
		(layer "F.Cu")
		(net "GND")
	)
	(segment
		(start 201.99985 -53.36413)
		(end 201.99985 -53.50002)
		(width 0.254)
		(layer "F.Cu")
		(net "GND")
	)
	(segment
		(start 47.69993 -150.600156)
		(end 47.699676 -150.600156)
		(width 0.3556)
		(layer "F.Cu")
		(net "GND")
	)
	(segment
		(start 23.233888 -141.361668)
		(end 22.834346 -141.76121)
		(width 0.254)
		(layer "F.Cu")
		(net "GND")
	)
	(segment
		(start 70.9676 -174.3456)
		(end 70.9549 -174.3329)
		(width 0.4064)
		(layer "F.Cu")
		(net "GND")
	)
	(segment
		(start 191.200278 -62.700154)
		(end 191.600074 -63.09995)
		(width 0.254)
		(layer "F.Cu")
		(net "GND")
	)
	(segment
		(start 187.600336 -71.09968)
		(end 187.600336 -71.099934)
		(width 0.254)
		(layer "F.Cu")
		(net "GND")
	)
	(segment
		(start 198.799958 -63.09995)
		(end 198.80961 -63.09995)
		(width 0.254)
		(layer "F.Cu")
		(net "GND")
	)
	(segment
		(start 195.9102 -24.3078)
		(end 195.2498 -24.3078)
		(width 0.4064)
		(layer "F.Cu")
		(net "GND")
	)
	(segment
		(start 46.500288 -143.800068)
		(end 46.900084 -144.199864)
		(width 0.3556)
		(layer "F.Cu")
		(net "GND")
	)
	(segment
		(start 55.604664 -130.102864)
		(end 55.9054 -130.4036)
		(width 0.254)
		(layer "F.Cu")
		(net "GND")
	)
	(segment
		(start 195.600066 -63.90005)
		(end 196.000116 -64.3001)
		(width 0.254)
		(layer "F.Cu")
		(net "GND")
	)
	(segment
		(start 51.689 -131.2799)
		(end 51.689 -130.429)
		(width 0.508)
		(layer "F.Cu")
		(net "GND")
	)
	(segment
		(start 15.619222 -138.961622)
		(end 15.5194 -138.8618)
		(width 0.254)
		(layer "F.Cu")
		(net "GND")
	)
	(segment
		(start 196.399912 -58.299858)
		(end 196.400674 -58.299858)
		(width 0.254)
		(layer "F.Cu")
		(net "GND")
	)
	(segment
		(start 47.699676 -148.999956)
		(end 47.29988 -149.399752)
		(width 0.3556)
		(layer "F.Cu")
		(net "GND")
	)
	(segment
		(start 67.6656 -154.6606)
		(end 67.32778 -154.99842)
		(width 0.254)
		(layer "F.Cu")
		(net "GND")
	)
	(segment
		(start 88.647016 -47.066708)
		(end 88.412828 -47.300896)
		(width 0.508)
		(layer "F.Cu")
		(net "GND")
	)
	(segment
		(start 39.1922 -178.68011)
		(end 38.38702 -178.68011)
		(width 0.508)
		(layer "F.Cu")
		(net "GND")
	)
	(segment
		(start 184.658 -88.8365)
		(end 184.658 -89.662)
		(width 0.508)
		(layer "F.Cu")
		(net "GND")
	)
	(segment
		(start 50.500026 -151.799798)
		(end 50.500026 -151.800052)
		(width 0.3556)
		(layer "F.Cu")
		(net "GND")
	)
	(segment
		(start 197.290944 -75.099926)
		(end 197.39864 -75.207622)
		(width 0.3048)
		(layer "F.Cu")
		(net "GND")
	)
	(segment
		(start 201.200004 -57.499758)
		(end 201.99985 -56.699912)
		(width 0.254)
		(layer "F.Cu")
		(net "GND")
	)
	(segment
		(start 69.0499 -118.2116)
		(end 69.7738 -118.2116)
		(width 0.508)
		(layer "F.Cu")
		(net "GND")
	)
	(segment
		(start 98.484182 -151.90216)
		(end 98.113342 -152.273)
		(width 0.508)
		(layer "F.Cu")
		(net "GND")
	)
	(segment
		(start 46.900084 -141.00048)
		(end 46.900338 -141.00048)
		(width 0.3556)
		(layer "F.Cu")
		(net "GND")
	)
	(segment
		(start 21.717 -160.7185)
		(end 21.717 -159.639)
		(width 0.508)
		(layer "F.Cu")
		(net "GND")
	)
	(segment
		(start 190.793624 -75.101958)
		(end 190.797942 -75.101958)
		(width 0.3048)
		(layer "F.Cu")
		(net "GND")
	)
	(segment
		(start 192.39992 -69.499988)
		(end 192.39992 -69.509132)
		(width 0.254)
		(layer "F.Cu")
		(net "GND")
	)
	(segment
		(start 203.192888 -66.697352)
		(end 203.590398 -66.299842)
		(width 0.254)
		(layer "F.Cu")
		(net "GND")
	)
	(segment
		(start 185.200036 -62.29985)
		(end 185.200036 -62.300104)
		(width 0.254)
		(layer "F.Cu")
		(net "GND")
	)
	(segment
		(start 191.59093 -64.699896)
		(end 191.19088 -64.299846)
		(width 0.254)
		(layer "F.Cu")
		(net "GND")
	)
	(segment
		(start 190.799974 -73.49998)
		(end 190.799466 -73.49998)
		(width 0.3048)
		(layer "F.Cu")
		(net "GND")
	)
	(segment
		(start 197.202552 -67.099942)
		(end 197.605904 -67.503294)
		(width 0.254)
		(layer "F.Cu")
		(net "GND")
	)
	(segment
		(start 185.999882 -69.499988)
		(end 186.400186 -69.900292)
		(width 0.254)
		(layer "F.Cu")
		(net "GND")
	)
	(segment
		(start 199.600058 -71.099934)
		(end 199.606408 -71.099934)
		(width 0.254)
		(layer "F.Cu")
		(net "GND")
	)
	(segment
		(start 190.399924 -56.300116)
		(end 189.999874 -55.900066)
		(width 0.254)
		(layer "F.Cu")
		(net "GND")
	)
	(segment
		(start 187.600082 -65.499996)
		(end 188.000132 -65.099946)
		(width 0.254)
		(layer "F.Cu")
		(net "GND")
	)
	(segment
		(start 189.200282 -70.299834)
		(end 189.600078 -69.900038)
		(width 0.254)
		(layer "F.Cu")
		(net "GND")
	)
	(segment
		(start 67.31 -168.5925)
		(end 66.7131 -169.1894)
		(width 0.508)
		(layer "F.Cu")
		(net "GND")
	)
	(segment
		(start 199.600058 -69.499988)
		(end 199.600058 -69.490336)
		(width 0.254)
		(layer "F.Cu")
		(net "GND")
	)
	(segment
		(start 192.39992 -68.709286)
		(end 192.793874 -69.10324)
		(width 0.254)
		(layer "F.Cu")
		(net "GND")
	)
	(segment
		(start 49.699926 -136.600438)
		(end 49.699926 -136.59993)
		(width 0.254)
		(layer "F.Cu")
		(net "GND")
	)
	(segment
		(start 17.634712 -146.161506)
		(end 18.034508 -146.561302)
		(width 0.3048)
		(layer "F.Cu")
		(net "GND")
	)
	(segment
		(start 51.906678 -167.473122)
		(end 51.5112 -167.8686)
		(width 0.508)
		(layer "F.Cu")
		(net "GND")
	)
	(segment
		(start 196.399912 -63.900304)
		(end 196.000116 -64.3001)
		(width 0.254)
		(layer "F.Cu")
		(net "GND")
	)
	(segment
		(start 31.1531 -160.6042)
		(end 31.1531 -159.8549)
		(width 0.254)
		(layer "F.Cu")
		(net "GND")
	)
	(segment
		(start 48.90008 -143.800068)
		(end 49.299876 -144.199864)
		(width 0.3556)
		(layer "F.Cu")
		(net "GND")
	)
	(segment
		(start 182.0291 -47.7012)
		(end 182.0291 -46.8757)
		(width 0.508)
		(layer "F.Cu")
		(net "GND")
	)
	(segment
		(start 197.200012 -71.900034)
		(end 197.200012 -71.890382)
		(width 0.254)
		(layer "F.Cu")
		(net "GND")
	)
	(segment
		(start 74.880216 -176.581816)
		(end 74.44105 -177.020982)
		(width 0.254)
		(layer "F.Cu")
		(net "GND")
	)
	(segment
		(start 85.65896 -167.235886)
		(end 86.173564 -167.235886)
		(width 0.254)
		(layer "F.Cu")
		(net "GND")
	)
	(segment
		(start 225.1202 -56.1721)
		(end 227.1903 -56.1721)
		(width 0.254)
		(layer "F.Cu")
		(net "GND")
	)
	(segment
		(start 181.200044 -62.29985)
		(end 181.317392 -62.29985)
		(width 0.254)
		(layer "F.Cu")
		(net "GND")
	)
	(segment
		(start 203.690982 -64.699896)
		(end 203.789534 -64.601344)
		(width 0.3048)
		(layer "F.Cu")
		(net "GND")
	)
	(segment
		(start 206.888588 -99.984306)
		(end 206.046832 -99.984306)
		(width 0.508)
		(layer "F.Cu")
		(net "GND")
	)
	(segment
		(start 189.999874 -61.500004)
		(end 189.600078 -61.100208)
		(width 0.254)
		(layer "F.Cu")
		(net "GND")
	)
	(segment
		(start 81.304892 -86.549992)
		(end 81.643728 -86.888828)
		(width 0.508)
		(layer "F.Cu")
		(net "GND")
	)
	(segment
		(start 79.925164 -74.550016)
		(end 81.344008 -74.550016)
		(width 0.508)
		(layer "F.Cu")
		(net "GND")
	)
	(segment
		(start 199.600058 -59.099958)
		(end 199.200262 -58.700162)
		(width 0.254)
		(layer "F.Cu")
		(net "GND")
	)
	(segment
		(start 176.7967 -52.7304)
		(end 175.6664 -52.7304)
		(width 0.508)
		(layer "F.Cu")
		(net "GND")
	)
	(segment
		(start 198.799958 -59.900058)
		(end 198.799958 -59.900312)
		(width 0.254)
		(layer "F.Cu")
		(net "GND")
	)
	(segment
		(start 204.649832 -64.699896)
		(end 204.399896 -64.699896)
		(width 0.3048)
		(layer "F.Cu")
		(net "GND")
	)
	(segment
		(start 89.7382 -132.4356)
		(end 89.6239 -132.3213)
		(width 0.508)
		(layer "F.Cu")
		(net "GND")
	)
	(segment
		(start 17.634458 -148.561552)
		(end 17.234408 -148.961602)
		(width 0.3048)
		(layer "F.Cu")
		(net "GND")
	)
	(segment
		(start 79.925164 -80.149954)
		(end 81.304892 -80.149954)
		(width 0.508)
		(layer "F.Cu")
		(net "GND")
	)
	(segment
		(start 194.799966 -71.099934)
		(end 194.801744 -71.099934)
		(width 0.254)
		(layer "F.Cu")
		(net "GND")
	)
	(segment
		(start 49.699926 -146.99996)
		(end 49.464722 -147.235164)
		(width 0.3556)
		(layer "F.Cu")
		(net "GND")
	)
	(segment
		(start 201.99985 -66.304414)
		(end 201.99985 -66.299842)
		(width 0.254)
		(layer "F.Cu")
		(net "GND")
	)
	(segment
		(start 85.349334 -147.265898)
		(end 84.069682 -147.265898)
		(width 0.254)
		(layer "F.Cu")
		(net "GND")
	)
	(segment
		(start 189.200028 -56.699912)
		(end 188.800232 -56.300116)
		(width 0.254)
		(layer "F.Cu")
		(net "GND")
	)
	(segment
		(start 125.2855 -7.62)
		(end 125.6284 -7.62)
		(width 0.254)
		(layer "F.Cu")
		(net "GND")
	)
	(segment
		(start 199.600058 -62.29985)
		(end 199.600058 -62.296802)
		(width 0.254)
		(layer "F.Cu")
		(net "GND")
	)
	(segment
		(start 193.999866 -59.900058)
		(end 194.000374 -59.900058)
		(width 0.254)
		(layer "F.Cu")
		(net "GND")
	)
	(segment
		(start 23.234396 -139.761468)
		(end 26.2636 -139.761468)
		(width 0.3048)
		(layer "F.Cu")
		(net "GND")
	)
	(segment
		(start 194.000374 -59.900058)
		(end 194.40017 -59.500262)
		(width 0.254)
		(layer "F.Cu")
		(net "GND")
	)
	(segment
		(start 197.200012 -58.299858)
		(end 197.20052 -58.299858)
		(width 0.254)
		(layer "F.Cu")
		(net "GND")
	)
	(segment
		(start 186.000136 -70.299834)
		(end 186.400186 -70.699884)
		(width 0.254)
		(layer "F.Cu")
		(net "GND")
	)
	(segment
		(start 174.9044 -123.403614)
		(end 173.630082 -123.403614)
		(width 0.508)
		(layer "F.Cu")
		(net "GND")
	)
	(segment
		(start 38.38702 -178.68011)
		(end 38.38702 -178.67376)
		(width 0.508)
		(layer "F.Cu")
		(net "GND")
	)
	(segment
		(start 90.734896 -129.567178)
		(end 90.247978 -129.567178)
		(width 0.254)
		(layer "F.Cu")
		(net "GND")
	)
	(segment
		(start 202.682856 -56.699912)
		(end 202.79995 -56.699912)
		(width 0.254)
		(layer "F.Cu")
		(net "GND")
	)
	(segment
		(start 200.399904 -70.299834)
		(end 200.399904 -70.306438)
		(width 0.254)
		(layer "F.Cu")
		(net "GND")
	)
	(segment
		(start 217.822526 -99.420934)
		(end 217.825574 -99.423982)
		(width 0.508)
		(layer "F.Cu")
		(net "GND")
	)
	(segment
		(start 79.925164 -68.150232)
		(end 81.142586 -68.150232)
		(width 0.508)
		(layer "F.Cu")
		(net "GND")
	)
	(segment
		(start 190.800228 -65.499996)
		(end 191.200278 -65.900046)
		(width 0.254)
		(layer "F.Cu")
		(net "GND")
	)
	(segment
		(start 51.299872 -153.40457)
		(end 51.299872 -153.399998)
		(width 0.3556)
		(layer "F.Cu")
		(net "GND")
	)
	(segment
		(start 197.317614 -64.699896)
		(end 197.200012 -64.699896)
		(width 0.254)
		(layer "F.Cu")
		(net "GND")
	)
	(segment
		(start 201.200004 -71.099934)
		(end 200.399904 -71.900034)
		(width 0.254)
		(layer "F.Cu")
		(net "GND")
	)
	(segment
		(start 179.787804 -153.651966)
		(end 179.787804 -154.362404)
		(width 0.508)
		(layer "F.Cu")
		(net "GND")
	)
	(segment
		(start 186.799982 -71.09968)
		(end 186.400186 -70.699884)
		(width 0.254)
		(layer "F.Cu")
		(net "GND")
	)
	(segment
		(start 28.9052 -132.8166)
		(end 28.9052 -130.5052)
		(width 0.381)
		(layer "F.Cu")
		(net "GND")
	)
	(segment
		(start 51.33594 -161.6964)
		(end 50.94224 -161.3154)
		(width 0.508)
		(layer "F.Cu")
		(net "GND")
	)
	(segment
		(start 188.399928 -69.49948)
		(end 188.000132 -69.099684)
		(width 0.254)
		(layer "F.Cu")
		(net "GND")
	)
	(segment
		(start 193.20002 -73.49998)
		(end 193.20002 -73.499472)
		(width 0.254)
		(layer "F.Cu")
		(net "GND")
	)
	(segment
		(start 189.590934 -64.290956)
		(end 189.590934 -64.299846)
		(width 0.254)
		(layer "F.Cu")
		(net "GND")
	)
	(segment
		(start 186.799982 -55.900066)
		(end 187.200032 -56.300116)
		(width 0.254)
		(layer "F.Cu")
		(net "GND")
	)
	(segment
		(start 47.29988 -142.999968)
		(end 47.69993 -143.400018)
		(width 0.3556)
		(layer "F.Cu")
		(net "GND")
	)
	(segment
		(start 201.200004 -60.699904)
		(end 201.5998 -60.300108)
		(width 0.254)
		(layer "F.Cu")
		(net "GND")
	)
	(segment
		(start 197.927468 -75.099926)
		(end 197.999858 -75.099926)
		(width 0.3048)
		(layer "F.Cu")
		(net "GND")
	)
	(segment
		(start 48.899826 -137.40003)
		(end 49.299876 -136.99998)
		(width 0.254)
		(layer "F.Cu")
		(net "GND")
	)
	(segment
		(start 62.3062 -161.4678)
		(end 62.3824 -161.4678)
		(width 0.254)
		(layer "F.Cu")
		(net "GND")
	)
	(segment
		(start 51.0159 -127.7112)
		(end 51.0159 -128.001522)
		(width 0.508)
		(layer "F.Cu")
		(net "GND")
	)
	(segment
		(start 189.999874 -64.699896)
		(end 189.599824 -64.299846)
		(width 0.254)
		(layer "F.Cu")
		(net "GND")
	)
	(segment
		(start 67.00139 -164.75075)
		(end 67.06616 -164.68598)
		(width 0.508)
		(layer "F.Cu")
		(net "GND")
	)
	(segment
		(start 198.799958 -56.699912)
		(end 198.400162 -56.300116)
		(width 0.254)
		(layer "F.Cu")
		(net "GND")
	)
	(segment
		(start 50.899822 -149.799802)
		(end 50.500026 -149.400006)
		(width 0.3556)
		(layer "F.Cu")
		(net "GND")
	)
	(segment
		(start 191.600074 -70.299834)
		(end 191.200278 -69.900038)
		(width 0.254)
		(layer "F.Cu")
		(net "GND")
	)
	(segment
		(start 193.999866 -70.29958)
		(end 193.600324 -69.900038)
		(width 0.254)
		(layer "F.Cu")
		(net "GND")
	)
	(segment
		(start 122.5169 -17.265142)
		(end 122.184668 -17.265142)
		(width 0.508)
		(layer "F.Cu")
		(net "GND")
	)
	(segment
		(start 199.600058 -66.290444)
		(end 199.203818 -65.894204)
		(width 0.254)
		(layer "F.Cu")
		(net "GND")
	)
	(segment
		(start 193.999866 -60.699904)
		(end 194.399662 -60.300108)
		(width 0.254)
		(layer "F.Cu")
		(net "GND")
	)
	(segment
		(start 190.402464 -75.502516)
		(end 190.393066 -75.502516)
		(width 0.3048)
		(layer "F.Cu")
		(net "GND")
	)
	(segment
		(start 46.500034 -142.999968)
		(end 46.684438 -142.815564)
		(width 0.3556)
		(layer "F.Cu")
		(net "GND")
	)
	(segment
		(start 193.20002 -68.709286)
		(end 193.593974 -69.10324)
		(width 0.254)
		(layer "F.Cu")
		(net "GND")
	)
	(segment
		(start 197.999858 -66.297048)
		(end 197.605904 -65.903094)
		(width 0.254)
		(layer "F.Cu")
		(net "GND")
	)
	(segment
		(start 189.200028 -74.299826)
		(end 189.199774 -74.299826)
		(width 0.3048)
		(layer "F.Cu")
		(net "GND")
	)
	(segment
		(start 81.162144 -170.278044)
		(end 81.162144 -169.190416)
		(width 0.508)
		(layer "F.Cu")
		(net "GND")
	)
	(segment
		(start 189.199774 -74.299826)
		(end 188.799724 -73.899776)
		(width 0.3048)
		(layer "F.Cu")
		(net "GND")
	)
	(segment
		(start 68.712334 -157.10281)
		(end 68.712334 -158.178246)
		(width 0.508)
		(layer "F.Cu")
		(net "GND")
	)
	(segment
		(start 50.986944 -177.38217)
		(end 50.00117 -177.38217)
		(width 0.508)
		(layer "F.Cu")
		(net "GND")
	)
	(segment
		(start 81.585308 -95.729044)
		(end 81.585308 -95.729298)
		(width 0.254)
		(layer "F.Cu")
		(net "GND")
	)
	(segment
		(start 189.200282 -57.500012)
		(end 189.600078 -57.100216)
		(width 0.254)
		(layer "F.Cu")
		(net "GND")
	)
	(segment
		(start 189.200028 -60.700158)
		(end 189.600078 -61.100208)
		(width 0.254)
		(layer "F.Cu")
		(net "GND")
	)
	(segment
		(start 143.09725 -17.4625)
		(end 143.9545 -17.4625)
		(width 0.508)
		(layer "F.Cu")
		(net "GND")
	)
	(segment
		(start 187.600336 -63.09995)
		(end 188.000132 -63.499746)
		(width 0.254)
		(layer "F.Cu")
		(net "GND")
	)
	(segment
		(start 197.200012 -71.099934)
		(end 197.200012 -71.109586)
		(width 0.254)
		(layer "F.Cu")
		(net "GND")
	)
	(segment
		(start 196.399912 -54.299866)
		(end 196.000116 -53.90007)
		(width 0.254)
		(layer "F.Cu")
		(net "GND")
	)
	(segment
		(start 54.619652 -166.887652)
		(end 53.96103 -166.887652)
		(width 0.254)
		(layer "F.Cu")
		(net "GND")
	)
	(segment
		(start 192.39992 -71.900034)
		(end 192.400174 -71.900034)
		(width 0.254)
		(layer "F.Cu")
		(net "GND")
	)
	(segment
		(start 48.703484 -166.901368)
		(end 48.703484 -167.1066)
		(width 0.508)
		(layer "F.Cu")
		(net "GND")
	)
	(segment
		(start 186.799982 -68.699888)
		(end 186.800236 -68.699888)
		(width 0.254)
		(layer "F.Cu")
		(net "GND")
	)
	(segment
		(start 156.556202 -95.65005)
		(end 156.556202 -96.384872)
		(width 0.254)
		(layer "F.Cu")
		(net "GND")
	)
	(segment
		(start 57.785 -163.9697)
		(end 58.7502 -163.9697)
		(width 0.508)
		(layer "F.Cu")
		(net "GND")
	)
	(segment
		(start 50.899822 -151.399748)
		(end 50.899822 -151.400002)
		(width 0.3556)
		(layer "F.Cu")
		(net "GND")
	)
	(segment
		(start 195.600066 -58.299858)
		(end 196.399912 -58.299858)
		(width 0.254)
		(layer "F.Cu")
		(net "GND")
	)
	(segment
		(start 75.475084 -92.14993)
		(end 77.029056 -92.14993)
		(width 0.508)
		(layer "F.Cu")
		(net "GND")
	)
	(segment
		(start 47.299626 -150.199852)
		(end 47.29988 -150.199852)
		(width 0.3556)
		(layer "F.Cu")
		(net "GND")
	)
	(segment
		(start 192.799716 -56.300116)
		(end 192.79997 -56.300116)
		(width 0.254)
		(layer "F.Cu")
		(net "GND")
	)
	(segment
		(start 190.799974 -70.299834)
		(end 190.800482 -70.299834)
		(width 0.254)
		(layer "F.Cu")
		(net "GND")
	)
	(segment
		(start 182.79999 -62.29985)
		(end 183.200294 -62.700154)
		(width 0.254)
		(layer "F.Cu")
		(net "GND")
	)
	(segment
		(start 46.500034 -146.19986)
		(end 46.500288 -146.19986)
		(width 0.3556)
		(layer "F.Cu")
		(net "GND")
	)
	(segment
		(start 204.969872 -64.379856)
		(end 204.649832 -64.699896)
		(width 0.3048)
		(layer "F.Cu")
		(net "GND")
	)
	(segment
		(start 196.399912 -56.699912)
		(end 196.800216 -57.100216)
		(width 0.254)
		(layer "F.Cu")
		(net "GND")
	)
	(segment
		(start 200.399904 -71.900034)
		(end 200.799954 -72.300084)
		(width 0.254)
		(layer "F.Cu")
		(net "GND")
	)
	(segment
		(start 80.8736 -172.3136)
		(end 80.13446 -172.3136)
		(width 0.254)
		(layer "F.Cu")
		(net "GND")
	)
	(segment
		(start 159.200088 -94.319344)
		(end 159.200088 -93.504512)
		(width 0.508)
		(layer "F.Cu")
		(net "GND")
	)
	(via
		(at 28.1686 -189.1792)
		(size 0.7112)
		(drill 0.4064)
		(layers "F.Cu" "B.Cu")
		(net "GND")
	)
	(via
		(at 212.82533 -2.159)
		(size 0.7112)
		(drill 0.4064)
		(layers "F.Cu" "B.Cu")
		(net "GND")
	)
	(via
		(at 180.456586 -140.750036)
		(size 0.508)
		(drill 0.254)
		(layers "F.Cu" "B.Cu")
		(net "GND")
	)
	(via
		(at 98.877374 -188.817504)
		(size 0.7112)
		(drill 0.4064)
		(layers "F.Cu" "B.Cu")
		(net "GND")
	)
	(via
		(at 184.808876 -57.8993)
		(size 0.508)
		(drill 0.254)
		(layers "F.Cu" "B.Cu")
		(net "GND")
	)
	(via
		(at 16.691356 -169.1259)
		(size 0.5588)
		(drill 0.3048)
		(layers "F.Cu" "B.Cu")
		(net "GND")
	)
	(via
		(at 146.45894 -135.487664)
		(size 0.7112)
		(drill 0.4064)
		(layers "F.Cu" "B.Cu")
		(net "GND")
	)
	(via
		(at 2.159 -145.612866)
		(size 0.7112)
		(drill 0.4064)
		(layers "F.Cu" "B.Cu")
		(net "GND")
	)
	(via
		(at 55.5752 -161.4424)
		(size 0.508)
		(drill 0.254)
		(layers "F.Cu" "B.Cu")
		(net "GND")
	)
	(via
		(at 78.500478 -191.84112)
		(size 0.7112)
		(drill 0.4064)
		(layers "F.Cu" "B.Cu")
		(net "GND")
	)
	(via
		(at 186.400186 -60.300362)
		(size 0.508)
		(drill 0.254)
		(layers "F.Cu" "B.Cu")
		(net "GND")
	)
	(via
		(at 194.400424 -69.100192)
		(size 0.508)
		(drill 0.254)
		(layers "F.Cu" "B.Cu")
		(net "GND")
	)
	(via
		(at 17.45742 -17.25422)
		(size 0.508)
		(drill 0.254)
		(layers "F.Cu" "B.Cu")
		(net "GND")
	)
	(via
		(at 21.350478 -191.84112)
		(size 0.7112)
		(drill 0.4064)
		(layers "F.Cu" "B.Cu")
		(net "GND")
	)
	(via
		(at 146.45894 -163.427664)
		(size 0.7112)
		(drill 0.4064)
		(layers "F.Cu" "B.Cu")
		(net "GND")
	)
	(via
		(at 67.070478 -191.84112)
		(size 0.7112)
		(drill 0.4064)
		(layers "F.Cu" "B.Cu")
		(net "GND")
	)
	(via
		(at 185.60034 -64.300608)
		(size 0.508)
		(drill 0.254)
		(layers "F.Cu" "B.Cu")
		(net "GND")
	)
	(via
		(at 80.14208 -180.77688)
		(size 0.7112)
		(drill 0.4064)
		(layers "F.Cu" "B.Cu")
		(net "GND")
	)
	(via
		(at 158.877 -136.1694)
		(size 0.5588)
		(drill 0.3048)
		(layers "F.Cu" "B.Cu")
		(net "GND")
	)
	(via
		(at 187.200032 -63.499746)
		(size 0.508)
		(drill 0.254)
		(layers "F.Cu" "B.Cu")
		(net "GND")
	)
	(via
		(at 93.726 -130.2258)
		(size 0.508)
		(drill 0.254)
		(layers "F.Cu" "B.Cu")
		(net "GND")
	)
	(via
		(at 203.129388 -191.84112)
		(size 0.7112)
		(drill 0.4064)
		(layers "F.Cu" "B.Cu")
		(net "GND")
	)
	(via
		(at 50.560478 -191.84112)
		(size 0.7112)
		(drill 0.4064)
		(layers "F.Cu" "B.Cu")
		(net "GND")
	)
	(via
		(at 26.993088 -139.03198)
		(size 0.508)
		(drill 0.254)
		(layers "F.Cu" "B.Cu")
		(net "GND")
	)
	(via
		(at 90.173048 -147.910296)
		(size 0.508)
		(drill 0.254)
		(layers "F.Cu" "B.Cu")
		(net "GND")
	)
	(via
		(at 232.841038 -104.063292)
		(size 0.7112)
		(drill 0.4064)
		(layers "F.Cu" "B.Cu")
		(net "GND")
	)
	(via
		(at 146.45894 -110.087664)
		(size 0.7112)
		(drill 0.4064)
		(layers "F.Cu" "B.Cu")
		(net "GND")
	)
	(via
		(at 2.159 -5.912866)
		(size 0.7112)
		(drill 0.4064)
		(layers "F.Cu" "B.Cu")
		(net "GND")
	)
	(via
		(at 167.132 -109.601)
		(size 0.7112)
		(drill 0.4064)
		(layers "F.Cu" "B.Cu")
		(net "GND")
	)
	(via
		(at 2.159 -64.332866)
		(size 0.7112)
		(drill 0.4064)
		(layers "F.Cu" "B.Cu")
		(net "GND")
	)
	(via
		(at 2.159 -91.002866)
		(size 0.7112)
		(drill 0.4064)
		(layers "F.Cu" "B.Cu")
		(net "GND")
	)
	(via
		(at 232.841038 -182.803292)
		(size 0.7112)
		(drill 0.4064)
		(layers "F.Cu" "B.Cu")
		(net "GND")
	)
	(via
		(at 146.45894 -101.197664)
		(size 0.7112)
		(drill 0.4064)
		(layers "F.Cu" "B.Cu")
		(net "GND")
	)
	(via
		(at 95.590868 -180.66004)
		(size 0.508)
		(drill 0.254)
		(layers "F.Cu" "B.Cu")
		(net "GND")
	)
	(via
		(at 144.272 -17.78)
		(size 0.508)
		(drill 0.254)
		(layers "F.Cu" "B.Cu")
		(net "GND")
	)
	(via
		(at 46.89983 -149.800056)
		(size 0.4572)
		(drill 0.2032)
		(layers "F.Cu" "B.Cu")
		(net "GND")
	)
	(via
		(at 185.599832 -73.899776)
		(size 0.508)
		(drill 0.254)
		(layers "F.Cu" "B.Cu")
		(net "GND")
	)
	(via
		(at 2.159 -14.802866)
		(size 0.7112)
		(drill 0.4064)
		(layers "F.Cu" "B.Cu")
		(net "GND")
	)
	(via
		(at 232.841038 -46.913292)
		(size 0.7112)
		(drill 0.4064)
		(layers "F.Cu" "B.Cu")
		(net "GND")
	)
	(via
		(at 197.59041 -71.499984)
		(size 0.508)
		(drill 0.254)
		(layers "F.Cu" "B.Cu")
		(net "GND")
	)
	(via
		(at 176.572926 -147.953984)
		(size 0.5588)
		(drill 0.3048)
		(layers "F.Cu" "B.Cu")
		(net "GND")
	)
	(via
		(at 185.60034 -68.300346)
		(size 0.508)
		(drill 0.254)
		(layers "F.Cu" "B.Cu")
		(net "GND")
	)
	(via
		(at 28.498038 -96.623124)
		(size 0.7112)
		(drill 0.4064)
		(layers "F.Cu" "B.Cu")
		(net "GND")
	)
	(via
		(at 2.159 -118.942866)
		(size 0.7112)
		(drill 0.4064)
		(layers "F.Cu" "B.Cu")
		(net "GND")
	)
	(via
		(at 33.024826 -181.17693)
		(size 0.5588)
		(drill 0.3048)
		(layers "F.Cu" "B.Cu")
		(net "GND")
	)
	(via
		(at 2.159 -74.492866)
		(size 0.7112)
		(drill 0.4064)
		(layers "F.Cu" "B.Cu")
		(net "GND")
	)
	(via
		(at 232.841038 -119.303292)
		(size 0.7112)
		(drill 0.4064)
		(layers "F.Cu" "B.Cu")
		(net "GND")
	)
	(via
		(at 39.699946 -144.999964)
		(size 0.4572)
		(drill 0.2032)
		(layers "F.Cu" "B.Cu")
		(net "GND")
	)
	(via
		(at 166.37 -179.07)
		(size 0.7112)
		(drill 0.4064)
		(layers "F.Cu" "B.Cu")
		(net "GND")
	)
	(via
		(at 185.60034 -71.499984)
		(size 0.508)
		(drill 0.254)
		(layers "F.Cu" "B.Cu")
		(net "GND")
	)
	(via
		(at 204.5462 -125.7046)
		(size 0.5588)
		(drill 0.3048)
		(layers "F.Cu" "B.Cu")
		(net "GND")
	)
	(via
		(at 64.6684 -151.6634)
		(size 0.508)
		(drill 0.254)
		(layers "F.Cu" "B.Cu")
		(net "GND")
	)
	(via
		(at 146.45894 -99.927664)
		(size 0.7112)
		(drill 0.4064)
		(layers "F.Cu" "B.Cu")
		(net "GND")
	)
	(via
		(at 167.132 -103.886)
		(size 0.7112)
		(drill 0.4064)
		(layers "F.Cu" "B.Cu")
		(net "GND")
	)
	(via
		(at 163.9062 -165.2016)
		(size 0.7112)
		(drill 0.4064)
		(layers "F.Cu" "B.Cu")
		(net "GND")
	)
	(via
		(at 55.640478 -191.84112)
		(size 0.7112)
		(drill 0.4064)
		(layers "F.Cu" "B.Cu")
		(net "GND")
	)
	(via
		(at 193.2178 -102.9716)
		(size 0.7112)
		(drill 0.4064)
		(layers "F.Cu" "B.Cu")
		(net "GND")
	)
	(via
		(at 184.658 -89.662)
		(size 0.508)
		(drill 0.254)
		(layers "F.Cu" "B.Cu")
		(net "GND")
	)
	(via
		(at 185.60034 -62.700408)
		(size 0.508)
		(drill 0.254)
		(layers "F.Cu" "B.Cu")
		(net "GND")
	)
	(via
		(at 209.0928 -116.6622)
		(size 0.7112)
		(drill 0.4064)
		(layers "F.Cu" "B.Cu")
		(net "GND")
	)
	(via
		(at 201.8411 -21.8567)
		(size 0.508)
		(drill 0.254)
		(layers "F.Cu" "B.Cu")
		(net "GND")
	)
	(via
		(at 196.800216 -56.30037)
		(size 0.508)
		(drill 0.254)
		(layers "F.Cu" "B.Cu")
		(net "GND")
	)
	(via
		(at 56.910478 -191.84112)
		(size 0.7112)
		(drill 0.4064)
		(layers "F.Cu" "B.Cu")
		(net "GND")
	)
	(via
		(at 56.5658 -179.06619)
		(size 0.7112)
		(drill 0.4064)
		(layers "F.Cu" "B.Cu")
		(net "GND")
	)
	(via
		(at 94.6404 -146.356578)
		(size 0.508)
		(drill 0.254)
		(layers "F.Cu" "B.Cu")
		(net "GND")
	)
	(via
		(at 79.1464 -170.269916)
		(size 0.508)
		(drill 0.254)
		(layers "F.Cu" "B.Cu")
		(net "GND")
	)
	(via
		(at 186.812936 -111.500412)
		(size 0.7112)
		(drill 0.4064)
		(layers "F.Cu" "B.Cu")
		(net "GND")
	)
	(via
		(at 201.665078 -28.812744)
		(size 0.508)
		(drill 0.254)
		(layers "F.Cu" "B.Cu")
		(net "GND")
	)
	(via
		(at 197.1802 -12.0904)
		(size 0.508)
		(drill 0.254)
		(layers "F.Cu" "B.Cu")
		(net "GND")
	)
	(via
		(at 46.89983 -136.99998)
		(size 0.4572)
		(drill 0.2032)
		(layers "F.Cu" "B.Cu")
		(net "GND")
	)
	(via
		(at 47.69993 -150.600156)
		(size 0.4572)
		(drill 0.2032)
		(layers "F.Cu" "B.Cu")
		(net "GND")
	)
	(via
		(at 56.3626 -160.2232)
		(size 0.508)
		(drill 0.254)
		(layers "F.Cu" "B.Cu")
		(net "GND")
	)
	(via
		(at 201.859388 -191.84112)
		(size 0.7112)
		(drill 0.4064)
		(layers "F.Cu" "B.Cu")
		(net "GND")
	)
	(via
		(at 48.020478 -191.84112)
		(size 0.7112)
		(drill 0.4064)
		(layers "F.Cu" "B.Cu")
		(net "GND")
	)
	(via
		(at 28.498038 -29.313124)
		(size 0.7112)
		(drill 0.4064)
		(layers "F.Cu" "B.Cu")
		(net "GND")
	)
	(via
		(at 199.203818 -65.894204)
		(size 0.508)
		(drill 0.254)
		(layers "F.Cu" "B.Cu")
		(net "GND")
	)
	(via
		(at 62.7634 -147.9296)
		(size 0.508)
		(drill 0.254)
		(layers "F.Cu" "B.Cu")
		(net "GND")
	)
	(via
		(at 31.8262 -189.1792)
		(size 0.7112)
		(drill 0.4064)
		(layers "F.Cu" "B.Cu")
		(net "GND")
	)
	(via
		(at 59.450478 -191.84112)
		(size 0.7112)
		(drill 0.4064)
		(layers "F.Cu" "B.Cu")
		(net "GND")
	)
	(via
		(at 232.841038 -78.663292)
		(size 0.7112)
		(drill 0.4064)
		(layers "F.Cu" "B.Cu")
		(net "GND")
	)
	(via
		(at 51.830478 -191.84112)
		(size 0.7112)
		(drill 0.4064)
		(layers "F.Cu" "B.Cu")
		(net "GND")
	)
	(via
		(at 160.02 -43.0784)
		(size 0.508)
		(drill 0.254)
		(layers "F.Cu" "B.Cu")
		(net "GND")
	)
	(via
		(at 17.234408 -148.161502)
		(size 0.508)
		(drill 0.254)
		(layers "F.Cu" "B.Cu")
		(net "GND")
	)
	(via
		(at 28.498038 -58.523124)
		(size 0.7112)
		(drill 0.4064)
		(layers "F.Cu" "B.Cu")
		(net "GND")
	)
	(via
		(at 192.800732 -76.305156)
		(size 0.508)
		(drill 0.254)
		(layers "F.Cu" "B.Cu")
		(net "GND")
	)
	(via
		(at 193.591942 -74.698606)
		(size 0.4572)
		(drill 0.2032)
		(layers "F.Cu" "B.Cu")
		(net "GND")
	)
	(via
		(at 167.569388 -191.84112)
		(size 0.7112)
		(drill 0.4064)
		(layers "F.Cu" "B.Cu")
		(net "GND")
	)
	(via
		(at 146.45894 -126.597664)
		(size 0.7112)
		(drill 0.4064)
		(layers "F.Cu" "B.Cu")
		(net "GND")
	)
	(via
		(at 116.8273 -14.732)
		(size 0.508)
		(drill 0.254)
		(layers "F.Cu" "B.Cu")
		(net "GND")
	)
	(via
		(at 232.841038 -142.163292)
		(size 0.7112)
		(drill 0.4064)
		(layers "F.Cu" "B.Cu")
		(net "GND")
	)
	(via
		(at 69.96938 -154.55392)
		(size 0.508)
		(drill 0.254)
		(layers "F.Cu" "B.Cu")
		(net "GND")
	)
	(via
		(at 191.897 -125.1204)
		(size 0.508)
		(drill 0.254)
		(layers "F.Cu" "B.Cu")
		(net "GND")
	)
	(via
		(at 17.455134 -2.159)
		(size 0.7112)
		(drill 0.4064)
		(layers "F.Cu" "B.Cu")
		(net "GND")
	)
	(via
		(at 77.230478 -191.84112)
		(size 0.7112)
		(drill 0.4064)
		(layers "F.Cu" "B.Cu")
		(net "GND")
	)
	(via
		(at 207.0862 -125.6538)
		(size 0.5588)
		(drill 0.3048)
		(layers "F.Cu" "B.Cu")
		(net "GND")
	)
	(via
		(at 81.585308 -95.729298)
		(size 0.508)
		(drill 0.254)
		(layers "F.Cu" "B.Cu")
		(net "GND")
	)
	(via
		(at 197.605904 -67.503294)
		(size 0.508)
		(drill 0.254)
		(layers "F.Cu" "B.Cu")
		(net "GND")
	)
	(via
		(at 199.319388 -191.84112)
		(size 0.7112)
		(drill 0.4064)
		(layers "F.Cu" "B.Cu")
		(net "GND")
	)
	(via
		(at 135.042656 -19.929602)
		(size 0.7112)
		(drill 0.4064)
		(layers "F.Cu" "B.Cu")
		(net "GND")
	)
	(via
		(at 2.159 -75.762866)
		(size 0.7112)
		(drill 0.4064)
		(layers "F.Cu" "B.Cu")
		(net "GND")
	)
	(via
		(at 60.720478 -191.84112)
		(size 0.7112)
		(drill 0.4064)
		(layers "F.Cu" "B.Cu")
		(net "GND")
	)
	(via
		(at 148.277834 -187.12815)
		(size 0.7112)
		(drill 0.4064)
		(layers "F.Cu" "B.Cu")
		(net "GND")
	)
	(via
		(at 183.20893 -56.299354)
		(size 0.508)
		(drill 0.254)
		(layers "F.Cu" "B.Cu")
		(net "GND")
	)
	(via
		(at 182.785004 -150.070566)
		(size 0.508)
		(drill 0.254)
		(layers "F.Cu" "B.Cu")
		(net "GND")
	)
	(via
		(at 163.9062 -172.5168)
		(size 0.7112)
		(drill 0.4064)
		(layers "F.Cu" "B.Cu")
		(net "GND")
	)
	(via
		(at 146.45894 -138.027664)
		(size 0.7112)
		(drill 0.4064)
		(layers "F.Cu" "B.Cu")
		(net "GND")
	)
	(via
		(at 2.159 -63.062866)
		(size 0.7112)
		(drill 0.4064)
		(layers "F.Cu" "B.Cu")
		(net "GND")
	)
	(via
		(at 85.339428 -99.281996)
		(size 0.508)
		(drill 0.254)
		(layers "F.Cu" "B.Cu")
		(net "GND")
	)
	(via
		(at 84.850478 -191.84112)
		(size 0.7112)
		(drill 0.4064)
		(layers "F.Cu" "B.Cu")
		(net "GND")
	)
	(via
		(at 172.02785 -123.34875)
		(size 0.508)
		(drill 0.254)
		(layers "F.Cu" "B.Cu")
		(net "GND")
	)
	(via
		(at 187.200286 -69.899784)
		(size 0.508)
		(drill 0.254)
		(layers "F.Cu" "B.Cu")
		(net "GND")
	)
	(via
		(at 192.303146 -134.640828)
		(size 0.508)
		(drill 0.254)
		(layers "F.Cu" "B.Cu")
		(net "GND")
	)
	(via
		(at 184.242964 -119.563388)
		(size 0.508)
		(drill 0.254)
		(layers "F.Cu" "B.Cu")
		(net "GND")
	)
	(via
		(at 199.203818 -65.094104)
		(size 0.508)
		(drill 0.254)
		(layers "F.Cu" "B.Cu")
		(net "GND")
	)
	(via
		(at 220.910658 -101.208332)
		(size 0.7112)
		(drill 0.4064)
		(layers "F.Cu" "B.Cu")
		(net "GND")
	)
	(via
		(at 2.159 -97.352866)
		(size 0.7112)
		(drill 0.4064)
		(layers "F.Cu" "B.Cu")
		(net "GND")
	)
	(via
		(at 89.1794 -180.8734)
		(size 0.508)
		(drill 0.254)
		(layers "F.Cu" "B.Cu")
		(net "GND")
	)
	(via
		(at 195.20027 -61.900308)
		(size 0.508)
		(drill 0.254)
		(layers "F.Cu" "B.Cu")
		(net "GND")
	)
	(via
		(at 28.498038 -44.553124)
		(size 0.7112)
		(drill 0.4064)
		(layers "F.Cu" "B.Cu")
		(net "GND")
	)
	(via
		(at 8.669528 -132.39623)
		(size 0.508)
		(drill 0.254)
		(layers "F.Cu" "B.Cu")
		(net "GND")
	)
	(via
		(at 163.9062 -166.4208)
		(size 0.7112)
		(drill 0.4064)
		(layers "F.Cu" "B.Cu")
		(net "GND")
	)
	(via
		(at 190.399924 -70.699884)
		(size 0.508)
		(drill 0.254)
		(layers "F.Cu" "B.Cu")
		(net "GND")
	)
	(via
		(at 100.053648 -144.398746)
		(size 0.508)
		(drill 0.254)
		(layers "F.Cu" "B.Cu")
		(net "GND")
	)
	(via
		(at 168.021 -131.4704)
		(size 0.7112)
		(drill 0.4064)
		(layers "F.Cu" "B.Cu")
		(net "GND")
	)
	(via
		(at 26.289 -163.957)
		(size 0.7112)
		(drill 0.4064)
		(layers "F.Cu" "B.Cu")
		(net "GND")
	)
	(via
		(at 22.021546 -127.5842)
		(size 0.508)
		(drill 0.254)
		(layers "F.Cu" "B.Cu")
		(net "GND")
	)
	(via
		(at 28.498038 -99.163124)
		(size 0.7112)
		(drill 0.4064)
		(layers "F.Cu" "B.Cu")
		(net "GND")
	)
	(via
		(at 146.45894 -115.167664)
		(size 0.7112)
		(drill 0.4064)
		(layers "F.Cu" "B.Cu")
		(net "GND")
	)
	(via
		(at 46.981618 -163.571682)
		(size 0.508)
		(drill 0.254)
		(layers "F.Cu" "B.Cu")
		(net "GND")
	)
	(via
		(at 2.159 -143.072866)
		(size 0.7112)
		(drill 0.4064)
		(layers "F.Cu" "B.Cu")
		(net "GND")
	)
	(via
		(at 196.805804 -68.30314)
		(size 0.508)
		(drill 0.254)
		(layers "F.Cu" "B.Cu")
		(net "GND")
	)
	(via
		(at 187.200032 -68.299838)
		(size 0.508)
		(drill 0.254)
		(layers "F.Cu" "B.Cu")
		(net "GND")
	)
	(via
		(at 146.5834 -19.9644)
		(size 0.508)
		(drill 0.254)
		(layers "F.Cu" "B.Cu")
		(net "GND")
	)
	(via
		(at 194.399662 -60.300108)
		(size 0.508)
		(drill 0.254)
		(layers "F.Cu" "B.Cu")
		(net "GND")
	)
	(via
		(at 22.0345 -145.761456)
		(size 0.508)
		(drill 0.254)
		(layers "F.Cu" "B.Cu")
		(net "GND")
	)
	(via
		(at 184.799986 -65.900046)
		(size 0.508)
		(drill 0.254)
		(layers "F.Cu" "B.Cu")
		(net "GND")
	)
	(via
		(at 178.517296 -121.024904)
		(size 0.508)
		(drill 0.254)
		(layers "F.Cu" "B.Cu")
		(net "GND")
	)
	(via
		(at 87.519256 -159.538416)
		(size 0.508)
		(drill 0.254)
		(layers "F.Cu" "B.Cu")
		(net "GND")
	)
	(via
		(at 186.399932 -64.299846)
		(size 0.508)
		(drill 0.254)
		(layers "F.Cu" "B.Cu")
		(net "GND")
	)
	(via
		(at 85.09 -156.3116)
		(size 0.7112)
		(drill 0.4064)
		(layers "F.Cu" "B.Cu")
		(net "GND")
	)
	(via
		(at 79.041244 -162.1917)
		(size 0.5588)
		(drill 0.3048)
		(layers "F.Cu" "B.Cu")
		(net "GND")
	)
	(via
		(at 232.841038 -116.763292)
		(size 0.7112)
		(drill 0.4064)
		(layers "F.Cu" "B.Cu")
		(net "GND")
	)
	(via
		(at 193.5226 -20.7518)
		(size 0.508)
		(drill 0.254)
		(layers "F.Cu" "B.Cu")
		(net "GND")
	)
	(via
		(at 94.3356 -154.0256)
		(size 0.5588)
		(drill 0.3048)
		(layers "F.Cu" "B.Cu")
		(net "GND")
	)
	(via
		(at 97.741486 -191.089534)
		(size 0.7112)
		(drill 0.4064)
		(layers "F.Cu" "B.Cu")
		(net "GND")
	)
	(via
		(at 74.880216 -176.581816)
		(size 0.508)
		(drill 0.254)
		(layers "F.Cu" "B.Cu")
		(net "GND")
	)
	(via
		(at 146.45894 -118.977664)
		(size 0.7112)
		(drill 0.4064)
		(layers "F.Cu" "B.Cu")
		(net "GND")
	)
	(via
		(at 192.793874 -69.903086)
		(size 0.508)
		(drill 0.254)
		(layers "F.Cu" "B.Cu")
		(net "GND")
	)
	(via
		(at 55.4228 -165.4556)
		(size 0.508)
		(drill 0.254)
		(layers "F.Cu" "B.Cu")
		(net "GND")
	)
	(via
		(at 146.45894 -165.967664)
		(size 0.7112)
		(drill 0.4064)
		(layers "F.Cu" "B.Cu")
		(net "GND")
	)
	(via
		(at 51.689 -130.429)
		(size 0.508)
		(drill 0.254)
		(layers "F.Cu" "B.Cu")
		(net "GND")
	)
	(via
		(at 2.159 -7.182866)
		(size 0.7112)
		(drill 0.4064)
		(layers "F.Cu" "B.Cu")
		(net "GND")
	)
	(via
		(at 232.841038 -83.743292)
		(size 0.7112)
		(drill 0.4064)
		(layers "F.Cu" "B.Cu")
		(net "GND")
	)
	(via
		(at 37.150802 -119.014748)
		(size 0.508)
		(drill 0.254)
		(layers "F.Cu" "B.Cu")
		(net "GND")
	)
	(via
		(at 177.729388 -191.84112)
		(size 0.7112)
		(drill 0.4064)
		(layers "F.Cu" "B.Cu")
		(net "GND")
	)
	(via
		(at 21.9964 -179.9082)
		(size 0.7112)
		(drill 0.4064)
		(layers "F.Cu" "B.Cu")
		(net "GND")
	)
	(via
		(at 187.990988 -61.8998)
		(size 0.508)
		(drill 0.254)
		(layers "F.Cu" "B.Cu")
		(net "GND")
	)
	(via
		(at 43.43908 -155.19908)
		(size 0.508)
		(drill 0.254)
		(layers "F.Cu" "B.Cu")
		(net "GND")
	)
	(via
		(at 186.399932 -62.699646)
		(size 0.508)
		(drill 0.254)
		(layers "F.Cu" "B.Cu")
		(net "GND")
	)
	(via
		(at 2.159 -106.242866)
		(size 0.7112)
		(drill 0.4064)
		(layers "F.Cu" "B.Cu")
		(net "GND")
	)
	(via
		(at 232.841038 -170.103292)
		(size 0.7112)
		(drill 0.4064)
		(layers "F.Cu" "B.Cu")
		(net "GND")
	)
	(via
		(at 192.000124 -57.900316)
		(size 0.508)
		(drill 0.254)
		(layers "F.Cu" "B.Cu")
		(net "GND")
	)
	(via
		(at 28.498038 -66.143124)
		(size 0.7112)
		(drill 0.4064)
		(layers "F.Cu" "B.Cu")
		(net "GND")
	)
	(via
		(at 200.799954 -65.909444)
		(size 0.508)
		(drill 0.254)
		(layers "F.Cu" "B.Cu")
		(net "GND")
	)
	(via
		(at 84.03844 -140.142976)
		(size 0.508)
		(drill 0.254)
		(layers "F.Cu" "B.Cu")
		(net "GND")
	)
	(via
		(at 37.120322 -122.188478)
		(size 0.508)
		(drill 0.254)
		(layers "F.Cu" "B.Cu")
		(net "GND")
	)
	(via
		(at 146.45894 -102.467664)
		(size 0.7112)
		(drill 0.4064)
		(layers "F.Cu" "B.Cu")
		(net "GND")
	)
	(via
		(at 156.337 -134.5692)
		(size 0.7112)
		(drill 0.4064)
		(layers "F.Cu" "B.Cu")
		(net "GND")
	)
	(via
		(at 191.200278 -67.500246)
		(size 0.508)
		(drill 0.254)
		(layers "F.Cu" "B.Cu")
		(net "GND")
	)
	(via
		(at 200.533 -102.9716)
		(size 0.7112)
		(drill 0.4064)
		(layers "F.Cu" "B.Cu")
		(net "GND")
	)
	(via
		(at 2.159 -45.282866)
		(size 0.7112)
		(drill 0.4064)
		(layers "F.Cu" "B.Cu")
		(net "GND")
	)
	(via
		(at 232.841038 -102.793292)
		(size 0.7112)
		(drill 0.4064)
		(layers "F.Cu" "B.Cu")
		(net "GND")
	)
	(via
		(at 15.4178 -169.1386)
		(size 0.5588)
		(drill 0.3048)
		(layers "F.Cu" "B.Cu")
		(net "GND")
	)
	(via
		(at 198.1454 -2.159)
		(size 0.7112)
		(drill 0.4064)
		(layers "F.Cu" "B.Cu")
		(net "GND")
	)
	(via
		(at 58.6486 -164.8714)
		(size 0.508)
		(drill 0.254)
		(layers "F.Cu" "B.Cu")
		(net "GND")
	)
	(via
		(at 195.50634 -31.7881)
		(size 0.508)
		(drill 0.254)
		(layers "F.Cu" "B.Cu")
		(net "GND")
	)
	(via
		(at 56.515 -136.184894)
		(size 0.508)
		(drill 0.254)
		(layers "F.Cu" "B.Cu")
		(net "GND")
	)
	(via
		(at 165.2016 -131.4704)
		(size 0.7112)
		(drill 0.4064)
		(layers "F.Cu" "B.Cu")
		(net "GND")
	)
	(via
		(at 191.193674 -69.10324)
		(size 0.508)
		(drill 0.254)
		(layers "F.Cu" "B.Cu")
		(net "GND")
	)
	(via
		(at 203.9112 -116.6622)
		(size 0.7112)
		(drill 0.4064)
		(layers "F.Cu" "B.Cu")
		(net "GND")
	)
	(via
		(at 81.643728 -86.888828)
		(size 0.508)
		(drill 0.254)
		(layers "F.Cu" "B.Cu")
		(net "GND")
	)
	(via
		(at 191.699388 -191.84112)
		(size 0.7112)
		(drill 0.4064)
		(layers "F.Cu" "B.Cu")
		(net "GND")
	)
	(via
		(at 187.200032 -69.099684)
		(size 0.508)
		(drill 0.254)
		(layers "F.Cu" "B.Cu")
		(net "GND")
	)
	(via
		(at 232.841038 -60.883292)
		(size 0.7112)
		(drill 0.4064)
		(layers "F.Cu" "B.Cu")
		(net "GND")
	)
	(via
		(at 200.796652 -67.493642)
		(size 0.508)
		(drill 0.254)
		(layers "F.Cu" "B.Cu")
		(net "GND")
	)
	(via
		(at 12.9032 -169.6466)
		(size 0.508)
		(drill 0.254)
		(layers "F.Cu" "B.Cu")
		(net "GND")
	)
	(via
		(at 52.705 -127.762)
		(size 0.508)
		(drill 0.254)
		(layers "F.Cu" "B.Cu")
		(net "GND")
	)
	(via
		(at 192.800224 -64.3001)
		(size 0.508)
		(drill 0.254)
		(layers "F.Cu" "B.Cu")
		(net "GND")
	)
	(via
		(at 17.9324 -169.1132)
		(size 0.5588)
		(drill 0.3048)
		(layers "F.Cu" "B.Cu")
		(net "GND")
	)
	(via
		(at 180.6321 -46.8757)
		(size 0.508)
		(drill 0.254)
		(layers "F.Cu" "B.Cu")
		(net "GND")
	)
	(via
		(at 14.46784 -14.9606)
		(size 0.508)
		(drill 0.254)
		(layers "F.Cu" "B.Cu")
		(net "GND")
	)
	(via
		(at 146.45894 -107.547664)
		(size 0.7112)
		(drill 0.4064)
		(layers "F.Cu" "B.Cu")
		(net "GND")
	)
	(via
		(at 146.45894 -140.567664)
		(size 0.7112)
		(drill 0.4064)
		(layers "F.Cu" "B.Cu")
		(net "GND")
	)
	(via
		(at 85.826346 -149.319996)
		(size 0.508)
		(drill 0.254)
		(layers "F.Cu" "B.Cu")
		(net "GND")
	)
	(via
		(at 188.0362 -109.7026)
		(size 0.7112)
		(drill 0.4064)
		(layers "F.Cu" "B.Cu")
		(net "GND")
	)
	(via
		(at 13.7287 -16.06804)
		(size 0.508)
		(drill 0.254)
		(layers "F.Cu" "B.Cu")
		(net "GND")
	)
	(via
		(at 232.841038 -92.633292)
		(size 0.7112)
		(drill 0.4064)
		(layers "F.Cu" "B.Cu")
		(net "GND")
	)
	(via
		(at 167.132 -106.807)
		(size 0.7112)
		(drill 0.4064)
		(layers "F.Cu" "B.Cu")
		(net "GND")
	)
	(via
		(at 2.159 -139.262866)
		(size 0.7112)
		(drill 0.4064)
		(layers "F.Cu" "B.Cu")
		(net "GND")
	)
	(via
		(at 86.901782 -153.164032)
		(size 0.508)
		(drill 0.254)
		(layers "F.Cu" "B.Cu")
		(net "GND")
	)
	(via
		(at 2.159 -158.312866)
		(size 0.7112)
		(drill 0.4064)
		(layers "F.Cu" "B.Cu")
		(net "GND")
	)
	(via
		(at 196.800216 -57.900316)
		(size 0.508)
		(drill 0.254)
		(layers "F.Cu" "B.Cu")
		(net "GND")
	)
	(via
		(at 81.584038 -64.625982)
		(size 0.508)
		(drill 0.254)
		(layers "F.Cu" "B.Cu")
		(net "GND")
	)
	(via
		(at 92.204032 -139.016486)
		(size 0.508)
		(drill 0.254)
		(layers "F.Cu" "B.Cu")
		(net "GND")
	)
	(via
		(at 85.09 -157.7848)
		(size 0.7112)
		(drill 0.4064)
		(layers "F.Cu" "B.Cu")
		(net "GND")
	)
	(via
		(at 50.099722 -150.599902)
		(size 0.4572)
		(drill 0.2032)
		(layers "F.Cu" "B.Cu")
		(net "GND")
	)
	(via
		(at 232.841038 -71.043292)
		(size 0.7112)
		(drill 0.4064)
		(layers "F.Cu" "B.Cu")
		(net "GND")
	)
	(via
		(at 188.799978 -56.300116)
		(size 0.508)
		(drill 0.254)
		(layers "F.Cu" "B.Cu")
		(net "GND")
	)
	(via
		(at 2.159 -107.512866)
		(size 0.7112)
		(drill 0.4064)
		(layers "F.Cu" "B.Cu")
		(net "GND")
	)
	(via
		(at 73.420478 -191.84112)
		(size 0.7112)
		(drill 0.4064)
		(layers "F.Cu" "B.Cu")
		(net "GND")
	)
	(via
		(at 191.7954 -2.159)
		(size 0.7112)
		(drill 0.4064)
		(layers "F.Cu" "B.Cu")
		(net "GND")
	)
	(via
		(at 191.200024 -57.900316)
		(size 0.508)
		(drill 0.254)
		(layers "F.Cu" "B.Cu")
		(net "GND")
	)
	(via
		(at 192.969388 -191.84112)
		(size 0.7112)
		(drill 0.4064)
		(layers "F.Cu" "B.Cu")
		(net "GND")
	)
	(via
		(at 188.000132 -67.499738)
		(size 0.508)
		(drill 0.254)
		(layers "F.Cu" "B.Cu")
		(net "GND")
	)
	(via
		(at 203.770484 -52.279804)
		(size 0.508)
		(drill 0.254)
		(layers "F.Cu" "B.Cu")
		(net "GND")
	)
	(via
		(at 23.634192 -146.561556)
		(size 0.508)
		(drill 0.254)
		(layers "F.Cu" "B.Cu")
		(net "GND")
	)
	(via
		(at 2.159 -80.842866)
		(size 0.7112)
		(drill 0.4064)
		(layers "F.Cu" "B.Cu")
		(net "GND")
	)
	(via
		(at 217.825574 -99.423982)
		(size 0.508)
		(drill 0.254)
		(layers "F.Cu" "B.Cu")
		(net "GND")
	)
	(via
		(at 81.643728 -70.88886)
		(size 0.508)
		(drill 0.254)
		(layers "F.Cu" "B.Cu")
		(net "GND")
	)
	(via
		(at 2.159 -16.072866)
		(size 0.7112)
		(drill 0.4064)
		(layers "F.Cu" "B.Cu")
		(net "GND")
	)
	(via
		(at 164.7698 -74.3966)
		(size 0.508)
		(drill 0.254)
		(layers "F.Cu" "B.Cu")
		(net "GND")
	)
	(via
		(at 2.159 -154.502866)
		(size 0.7112)
		(drill 0.4064)
		(layers "F.Cu" "B.Cu")
		(net "GND")
	)
	(via
		(at 169.3418 -52.2224)
		(size 0.508)
		(drill 0.254)
		(layers "F.Cu" "B.Cu")
		(net "GND")
	)
	(via
		(at 204.5208 -126.9746)
		(size 0.5588)
		(drill 0.3048)
		(layers "F.Cu" "B.Cu")
		(net "GND")
	)
	(via
		(at 226.79533 -2.159)
		(size 0.7112)
		(drill 0.4064)
		(layers "F.Cu" "B.Cu")
		(net "GND")
	)
	(via
		(at 159.8676 -55.1942)
		(size 0.508)
		(drill 0.254)
		(layers "F.Cu" "B.Cu")
		(net "GND")
	)
	(via
		(at 2.159 -4.642866)
		(size 0.7112)
		(drill 0.4064)
		(layers "F.Cu" "B.Cu")
		(net "GND")
	)
	(via
		(at 10.819638 -145.234406)
		(size 0.508)
		(drill 0.254)
		(layers "F.Cu" "B.Cu")
		(net "GND")
	)
	(via
		(at 2.159 -169.742866)
		(size 0.7112)
		(drill 0.4064)
		(layers "F.Cu" "B.Cu")
		(net "GND")
	)
	(via
		(at 163.9062 -168.8592)
		(size 0.7112)
		(drill 0.4064)
		(layers "F.Cu" "B.Cu")
		(net "GND")
	)
	(via
		(at 28.498038 -24.233124)
		(size 0.7112)
		(drill 0.4064)
		(layers "F.Cu" "B.Cu")
		(net "GND")
	)
	(via
		(at 2.159 -98.622866)
		(size 0.7112)
		(drill 0.4064)
		(layers "F.Cu" "B.Cu")
		(net "GND")
	)
	(via
		(at 232.841038 -16.433292)
		(size 0.7112)
		(drill 0.4064)
		(layers "F.Cu" "B.Cu")
		(net "GND")
	)
	(via
		(at 170.2816 -137.541)
		(size 0.7112)
		(drill 0.4064)
		(layers "F.Cu" "B.Cu")
		(net "GND")
	)
	(via
		(at 200.8124 -116.332)
		(size 0.7112)
		(drill 0.4064)
		(layers "F.Cu" "B.Cu")
		(net "GND")
	)
	(via
		(at 2.159 -121.482866)
		(size 0.7112)
		(drill 0.4064)
		(layers "F.Cu" "B.Cu")
		(net "GND")
	)
	(via
		(at 186.812936 -112.719612)
		(size 0.7112)
		(drill 0.4064)
		(layers "F.Cu" "B.Cu")
		(net "GND")
	)
	(via
		(at 214.0204 -86.2076)
		(size 0.7112)
		(drill 0.4064)
		(layers "F.Cu" "B.Cu")
		(net "GND")
	)
	(via
		(at 232.841038 -72.313292)
		(size 0.7112)
		(drill 0.4064)
		(layers "F.Cu" "B.Cu")
		(net "GND")
	)
	(via
		(at 187.199778 -73.899776)
		(size 0.508)
		(drill 0.254)
		(layers "F.Cu" "B.Cu")
		(net "GND")
	)
	(via
		(at 175.716184 -146.710146)
		(size 0.5588)
		(drill 0.3048)
		(layers "F.Cu" "B.Cu")
		(net "GND")
	)
	(via
		(at 182.809388 -191.84112)
		(size 0.7112)
		(drill 0.4064)
		(layers "F.Cu" "B.Cu")
		(net "GND")
	)
	(via
		(at 197.4977 -15.8369)
		(size 0.508)
		(drill 0.254)
		(layers "F.Cu" "B.Cu")
		(net "GND")
	)
	(via
		(at 84.24037 -153.26487)
		(size 0.508)
		(drill 0.254)
		(layers "F.Cu" "B.Cu")
		(net "GND")
	)
	(via
		(at 16.7386 -170.434)
		(size 0.5588)
		(drill 0.3048)
		(layers "F.Cu" "B.Cu")
		(net "GND")
	)
	(via
		(at 185.7756 -92.1258)
		(size 0.508)
		(drill 0.254)
		(layers "F.Cu" "B.Cu")
		(net "GND")
	)
	(via
		(at 54.1274 -179.06619)
		(size 0.7112)
		(drill 0.4064)
		(layers "F.Cu" "B.Cu")
		(net "GND")
	)
	(via
		(at 177.487326 -147.953984)
		(size 0.5588)
		(drill 0.3048)
		(layers "F.Cu" "B.Cu")
		(net "GND")
	)
	(via
		(at 90.17 -165.64864)
		(size 0.508)
		(drill 0.254)
		(layers "F.Cu" "B.Cu")
		(net "GND")
	)
	(via
		(at 146.45894 -120.247664)
		(size 0.7112)
		(drill 0.4064)
		(layers "F.Cu" "B.Cu")
		(net "GND")
	)
	(via
		(at 186.400186 -71.499984)
		(size 0.508)
		(drill 0.254)
		(layers "F.Cu" "B.Cu")
		(net "GND")
	)
	(via
		(at 149.413722 -189.40018)
		(size 0.7112)
		(drill 0.4064)
		(layers "F.Cu" "B.Cu")
		(net "GND")
	)
	(via
		(at 34.294826 -183.79313)
		(size 0.5588)
		(drill 0.3048)
		(layers "F.Cu" "B.Cu")
		(net "GND")
	)
	(via
		(at 33.024826 -180.26253)
		(size 0.5588)
		(drill 0.3048)
		(layers "F.Cu" "B.Cu")
		(net "GND")
	)
	(via
		(at 200.799954 -72.300084)
		(size 0.508)
		(drill 0.254)
		(layers "F.Cu" "B.Cu")
		(net "GND")
	)
	(via
		(at 18.73504 -17.25422)
		(size 0.508)
		(drill 0.254)
		(layers "F.Cu" "B.Cu")
		(net "GND")
	)
	(via
		(at 207.0608 -128.27)
		(size 0.5588)
		(drill 0.3048)
		(layers "F.Cu" "B.Cu")
		(net "GND")
	)
	(via
		(at 232.841038 -29.133292)
		(size 0.7112)
		(drill 0.4064)
		(layers "F.Cu" "B.Cu")
		(net "GND")
	)
	(via
		(at 72.639428 -137.795508)
		(size 0.508)
		(drill 0.254)
		(layers "F.Cu" "B.Cu")
		(net "GND")
	)
	(via
		(at 24.511 -189.1792)
		(size 0.7112)
		(drill 0.4064)
		(layers "F.Cu" "B.Cu")
		(net "GND")
	)
	(via
		(at 11.105134 -2.159)
		(size 0.7112)
		(drill 0.4064)
		(layers "F.Cu" "B.Cu")
		(net "GND")
	)
	(via
		(at 36.590478 -191.84112)
		(size 0.7112)
		(drill 0.4064)
		(layers "F.Cu" "B.Cu")
		(net "GND")
	)
	(via
		(at 2.159 -12.262866)
		(size 0.7112)
		(drill 0.4064)
		(layers "F.Cu" "B.Cu")
		(net "GND")
	)
	(via
		(at 146.45894 -172.317664)
		(size 0.7112)
		(drill 0.4064)
		(layers "F.Cu" "B.Cu")
		(net "GND")
	)
	(via
		(at 232.841038 -97.713292)
		(size 0.7112)
		(drill 0.4064)
		(layers "F.Cu" "B.Cu")
		(net "GND")
	)
	(via
		(at 28.498038 -71.223124)
		(size 0.7112)
		(drill 0.4064)
		(layers "F.Cu" "B.Cu")
		(net "GND")
	)
	(via
		(at 187.200032 -61.8998)
		(size 0.508)
		(drill 0.254)
		(layers "F.Cu" "B.Cu")
		(net "GND")
	)
	(via
		(at 199.197722 -70.692772)
		(size 0.508)
		(drill 0.254)
		(layers "F.Cu" "B.Cu")
		(net "GND")
	)
	(via
		(at 52.499768 -141.00048)
		(size 0.4572)
		(drill 0.2032)
		(layers "F.Cu" "B.Cu")
		(net "GND")
	)
	(via
		(at 193.599816 -73.099676)
		(size 0.508)
		(drill 0.254)
		(layers "F.Cu" "B.Cu")
		(net "GND")
	)
	(via
		(at 31.1785 -156.7053)
		(size 0.508)
		(drill 0.254)
		(layers "F.Cu" "B.Cu")
		(net "GND")
	)
	(via
		(at 207.284066 -63.617856)
		(size 0.508)
		(drill 0.254)
		(layers "F.Cu" "B.Cu")
		(net "GND")
	)
	(via
		(at 193.60007 -53.90007)
		(size 0.508)
		(drill 0.254)
		(layers "F.Cu" "B.Cu")
		(net "GND")
	)
	(via
		(at 89.7382 -132.4356)
		(size 0.508)
		(drill 0.254)
		(layers "F.Cu" "B.Cu")
		(net "GND")
	)
	(via
		(at 21.971 -178.5874)
		(size 0.7112)
		(drill 0.4064)
		(layers "F.Cu" "B.Cu")
		(net "GND")
	)
	(via
		(at 146.45894 -144.377664)
		(size 0.7112)
		(drill 0.4064)
		(layers "F.Cu" "B.Cu")
		(net "GND")
	)
	(via
		(at 28.498038 -45.823124)
		(size 0.7112)
		(drill 0.4064)
		(layers "F.Cu" "B.Cu")
		(net "GND")
	)
	(via
		(at 2.159 -94.812866)
		(size 0.7112)
		(drill 0.4064)
		(layers "F.Cu" "B.Cu")
		(net "GND")
	)
	(via
		(at 2.159 -163.392866)
		(size 0.7112)
		(drill 0.4064)
		(layers "F.Cu" "B.Cu")
		(net "GND")
	)
	(via
		(at 166.0144 -137.2362)
		(size 0.508)
		(drill 0.254)
		(layers "F.Cu" "B.Cu")
		(net "GND")
	)
	(via
		(at 92.7862 -154.051)
		(size 0.5588)
		(drill 0.3048)
		(layers "F.Cu" "B.Cu")
		(net "GND")
	)
	(via
		(at 171.379388 -191.84112)
		(size 0.7112)
		(drill 0.4064)
		(layers "F.Cu" "B.Cu")
		(net "GND")
	)
	(via
		(at 199.206358 -61.903102)
		(size 0.508)
		(drill 0.254)
		(layers "F.Cu" "B.Cu")
		(net "GND")
	)
	(via
		(at 232.841038 -135.813292)
		(size 0.7112)
		(drill 0.4064)
		(layers "F.Cu" "B.Cu")
		(net "GND")
	)
	(via
		(at 191.9986 -102.9716)
		(size 0.7112)
		(drill 0.4064)
		(layers "F.Cu" "B.Cu")
		(net "GND")
	)
	(via
		(at 27.2034 -126.3142)
		(size 0.508)
		(drill 0.254)
		(layers "F.Cu" "B.Cu")
		(net "GND")
	)
	(via
		(at 81.643728 -83.688936)
		(size 0.508)
		(drill 0.254)
		(layers "F.Cu" "B.Cu")
		(net "GND")
	)
	(via
		(at 47.69993 -153.000202)
		(size 0.4572)
		(drill 0.2032)
		(layers "F.Cu" "B.Cu")
		(net "GND")
	)
	(via
		(at 159.55264 -144.55013)
		(size 0.508)
		(drill 0.254)
		(layers "F.Cu" "B.Cu")
		(net "GND")
	)
	(via
		(at 185.60034 -63.500508)
		(size 0.508)
		(drill 0.254)
		(layers "F.Cu" "B.Cu")
		(net "GND")
	)
	(via
		(at 33.5534 -125.222)
		(size 0.508)
		(drill 0.254)
		(layers "F.Cu" "B.Cu")
		(net "GND")
	)
	(via
		(at 2.159 -32.582866)
		(size 0.7112)
		(drill 0.4064)
		(layers "F.Cu" "B.Cu")
		(net "GND")
	)
	(via
		(at 191.200278 -62.700154)
		(size 0.508)
		(drill 0.254)
		(layers "F.Cu" "B.Cu")
		(net "GND")
	)
	(via
		(at 93.8784 -176.1236)
		(size 0.508)
		(drill 0.254)
		(layers "F.Cu" "B.Cu")
		(net "GND")
	)
	(via
		(at 227.830126 -76.581)
		(size 0.508)
		(drill 0.254)
		(layers "F.Cu" "B.Cu")
		(net "GND")
	)
	(via
		(at 44.4754 -121.158)
		(size 0.508)
		(drill 0.254)
		(layers "F.Cu" "B.Cu")
		(net "GND")
	)
	(via
		(at 8.559038 -142.459964)
		(size 0.508)
		(drill 0.254)
		(layers "F.Cu" "B.Cu")
		(net "GND")
	)
	(via
		(at 232.841038 -15.163292)
		(size 0.7112)
		(drill 0.4064)
		(layers "F.Cu" "B.Cu")
		(net "GND")
	)
	(via
		(at 51.689 -179.06619)
		(size 0.7112)
		(drill 0.4064)
		(layers "F.Cu" "B.Cu")
		(net "GND")
	)
	(via
		(at 232.841038 -176.453292)
		(size 0.7112)
		(drill 0.4064)
		(layers "F.Cu" "B.Cu")
		(net "GND")
	)
	(via
		(at 23.890478 -191.84112)
		(size 0.7112)
		(drill 0.4064)
		(layers "F.Cu" "B.Cu")
		(net "GND")
	)
	(via
		(at 46.900084 -145.800064)
		(size 0.4572)
		(drill 0.2032)
		(layers "F.Cu" "B.Cu")
		(net "GND")
	)
	(via
		(at 77.8002 -162.2044)
		(size 0.5588)
		(drill 0.3048)
		(layers "F.Cu" "B.Cu")
		(net "GND")
	)
	(via
		(at 28.498038 -40.743124)
		(size 0.7112)
		(drill 0.4064)
		(layers "F.Cu" "B.Cu")
		(net "GND")
	)
	(via
		(at 2.159 -26.232866)
		(size 0.7112)
		(drill 0.4064)
		(layers "F.Cu" "B.Cu")
		(net "GND")
	)
	(via
		(at 121.539 -5.02285)
		(size 0.508)
		(drill 0.254)
		(layers "F.Cu" "B.Cu")
		(net "GND")
	)
	(via
		(at 79.066644 -163.5125)
		(size 0.5588)
		(drill 0.3048)
		(layers "F.Cu" "B.Cu")
		(net "GND")
	)
	(via
		(at 2.159 -146.882866)
		(size 0.7112)
		(drill 0.4064)
		(layers "F.Cu" "B.Cu")
		(net "GND")
	)
	(via
		(at 75.960478 -191.84112)
		(size 0.7112)
		(drill 0.4064)
		(layers "F.Cu" "B.Cu")
		(net "GND")
	)
	(via
		(at 2.159 -168.472866)
		(size 0.7112)
		(drill 0.4064)
		(layers "F.Cu" "B.Cu")
		(net "GND")
	)
	(via
		(at 154.686 -120.269)
		(size 0.7112)
		(drill 0.4064)
		(layers "F.Cu" "B.Cu")
		(net "GND")
	)
	(via
		(at 232.841038 -39.293292)
		(size 0.7112)
		(drill 0.4064)
		(layers "F.Cu" "B.Cu")
		(net "GND")
	)
	(via
		(at 28.498038 -39.473124)
		(size 0.7112)
		(drill 0.4064)
		(layers "F.Cu" "B.Cu")
		(net "GND")
	)
	(via
		(at 201.39533 -2.159)
		(size 0.7112)
		(drill 0.4064)
		(layers "F.Cu" "B.Cu")
		(net "GND")
	)
	(via
		(at 149.981666 -190.536068)
		(size 0.7112)
		(drill 0.4064)
		(layers "F.Cu" "B.Cu")
		(net "GND")
	)
	(via
		(at 67.6656 -171.538646)
		(size 0.508)
		(drill 0.254)
		(layers "F.Cu" "B.Cu")
		(net "GND")
	)
	(via
		(at 54.099968 -148.999956)
		(size 0.4572)
		(drill 0.2032)
		(layers "F.Cu" "B.Cu")
		(net "GND")
	)
	(via
		(at 198.399908 -75.499976)
		(size 0.508)
		(drill 0.254)
		(layers "F.Cu" "B.Cu")
		(net "GND")
	)
	(via
		(at 100.581206 -185.40984)
		(size 0.7112)
		(drill 0.4064)
		(layers "F.Cu" "B.Cu")
		(net "GND")
	)
	(via
		(at 99.445318 -187.681616)
		(size 0.7112)
		(drill 0.4064)
		(layers "F.Cu" "B.Cu")
		(net "GND")
	)
	(via
		(at 205.980284 -98.992436)
		(size 0.508)
		(drill 0.254)
		(layers "F.Cu" "B.Cu")
		(net "GND")
	)
	(via
		(at 2.159 -46.552866)
		(size 0.7112)
		(drill 0.4064)
		(layers "F.Cu" "B.Cu")
		(net "GND")
	)
	(via
		(at 206.8703 -77.9653)
		(size 0.508)
		(drill 0.254)
		(layers "F.Cu" "B.Cu")
		(net "GND")
	)
	(via
		(at 62.611 -152.781)
		(size 0.508)
		(drill 0.254)
		(layers "F.Cu" "B.Cu")
		(net "GND")
	)
	(via
		(at 232.841038 -21.513292)
		(size 0.7112)
		(drill 0.4064)
		(layers "F.Cu" "B.Cu")
		(net "GND")
	)
	(via
		(at 188.0362 -112.141)
		(size 0.7112)
		(drill 0.4064)
		(layers "F.Cu" "B.Cu")
		(net "GND")
	)
	(via
		(at 204.0382 -77.1398)
		(size 0.508)
		(drill 0.254)
		(layers "F.Cu" "B.Cu")
		(net "GND")
	)
	(via
		(at 30.988 -159.6898)
		(size 0.508)
		(drill 0.254)
		(layers "F.Cu" "B.Cu")
		(net "GND")
	)
	(via
		(at 146.45894 -111.357664)
		(size 0.7112)
		(drill 0.4064)
		(layers "F.Cu" "B.Cu")
		(net "GND")
	)
	(via
		(at 213.6394 -84.4042)
		(size 0.7112)
		(drill 0.4064)
		(layers "F.Cu" "B.Cu")
		(net "GND")
	)
	(via
		(at 2.159 -44.012866)
		(size 0.7112)
		(drill 0.4064)
		(layers "F.Cu" "B.Cu")
		(net "GND")
	)
	(via
		(at 76.526644 -162.2171)
		(size 0.5588)
		(drill 0.3048)
		(layers "F.Cu" "B.Cu")
		(net "GND")
	)
	(via
		(at 77.827378 -52.338478)
		(size 0.508)
		(drill 0.254)
		(layers "F.Cu" "B.Cu")
		(net "GND")
	)
	(via
		(at 95.0468 -164.051234)
		(size 0.508)
		(drill 0.254)
		(layers "F.Cu" "B.Cu")
		(net "GND")
	)
	(via
		(at 47.69993 -144.999964)
		(size 0.4572)
		(drill 0.2032)
		(layers "F.Cu" "B.Cu")
		(net "GND")
	)
	(via
		(at 49.299876 -144.199864)
		(size 0.4572)
		(drill 0.2032)
		(layers "F.Cu" "B.Cu")
		(net "GND")
	)
	(via
		(at 88.00211 -178.60899)
		(size 0.508)
		(drill 0.254)
		(layers "F.Cu" "B.Cu")
		(net "GND")
	)
	(via
		(at 199.200262 -57.900062)
		(size 0.508)
		(drill 0.254)
		(layers "F.Cu" "B.Cu")
		(net "GND")
	)
	(via
		(at 80.04048 -2.159)
		(size 0.7112)
		(drill 0.4064)
		(layers "F.Cu" "B.Cu")
		(net "GND")
	)
	(via
		(at 163.9062 -173.736)
		(size 0.7112)
		(drill 0.4064)
		(layers "F.Cu" "B.Cu")
		(net "GND")
	)
	(via
		(at 34.294826 -181.57063)
		(size 0.5588)
		(drill 0.3048)
		(layers "F.Cu" "B.Cu")
		(net "GND")
	)
	(via
		(at 232.841038 -85.013292)
		(size 0.7112)
		(drill 0.4064)
		(layers "F.Cu" "B.Cu")
		(net "GND")
	)
	(via
		(at 232.841038 -112.953292)
		(size 0.7112)
		(drill 0.4064)
		(layers "F.Cu" "B.Cu")
		(net "GND")
	)
	(via
		(at 232.841038 -65.963292)
		(size 0.7112)
		(drill 0.4064)
		(layers "F.Cu" "B.Cu")
		(net "GND")
	)
	(via
		(at 63.260478 -191.84112)
		(size 0.7112)
		(drill 0.4064)
		(layers "F.Cu" "B.Cu")
		(net "GND")
	)
	(via
		(at 188.000132 -69.099684)
		(size 0.508)
		(drill 0.254)
		(layers "F.Cu" "B.Cu")
		(net "GND")
	)
	(via
		(at 33.024826 -182.09133)
		(size 0.5588)
		(drill 0.3048)
		(layers "F.Cu" "B.Cu")
		(net "GND")
	)
	(via
		(at 163.759388 -191.84112)
		(size 0.7112)
		(drill 0.4064)
		(layers "F.Cu" "B.Cu")
		(net "GND")
	)
	(via
		(at 203.193396 -69.102732)
		(size 0.508)
		(drill 0.254)
		(layers "F.Cu" "B.Cu")
		(net "GND")
	)
	(via
		(at 76.501244 -163.4871)
		(size 0.5588)
		(drill 0.3048)
		(layers "F.Cu" "B.Cu")
		(net "GND")
	)
	(via
		(at 196.800216 -57.100216)
		(size 0.508)
		(drill 0.254)
		(layers "F.Cu" "B.Cu")
		(net "GND")
	)
	(via
		(at 2.159 -141.802866)
		(size 0.7112)
		(drill 0.4064)
		(layers "F.Cu" "B.Cu")
		(net "GND")
	)
	(via
		(at 52.8066 -163.9824)
		(size 0.508)
		(drill 0.254)
		(layers "F.Cu" "B.Cu")
		(net "GND")
	)
	(via
		(at 159.200088 -94.319344)
		(size 0.508)
		(drill 0.254)
		(layers "F.Cu" "B.Cu")
		(net "GND")
	)
	(via
		(at 187.200286 -58.700162)
		(size 0.508)
		(drill 0.254)
		(layers "F.Cu" "B.Cu")
		(net "GND")
	)
	(via
		(at 154.94 -118.745)
		(size 0.7112)
		(drill 0.4064)
		(layers "F.Cu" "B.Cu")
		(net "GND")
	)
	(via
		(at 201.600054 -56.300116)
		(size 0.508)
		(drill 0.254)
		(layers "F.Cu" "B.Cu")
		(net "GND")
	)
	(via
		(at 48.50003 -146.59991)
		(size 0.4572)
		(drill 0.2032)
		(layers "F.Cu" "B.Cu")
		(net "GND")
	)
	(via
		(at 202.141328 -16.9545)
		(size 0.508)
		(drill 0.254)
		(layers "F.Cu" "B.Cu")
		(net "GND")
	)
	(via
		(at 42.099992 -141.800072)
		(size 0.4572)
		(drill 0.2032)
		(layers "F.Cu" "B.Cu")
		(net "GND")
	)
	(via
		(at 182.394606 -61.895736)
		(size 0.508)
		(drill 0.254)
		(layers "F.Cu" "B.Cu")
		(net "GND")
	)
	(via
		(at 205.8162 -82.9183)
		(size 0.508)
		(drill 0.254)
		(layers "F.Cu" "B.Cu")
		(net "GND")
	)
	(via
		(at 232.841038 -3.733292)
		(size 0.7112)
		(drill 0.4064)
		(layers "F.Cu" "B.Cu")
		(net "GND")
	)
	(via
		(at 77.847444 -163.5125)
		(size 0.5588)
		(drill 0.3048)
		(layers "F.Cu" "B.Cu")
		(net "GND")
	)
	(via
		(at 197.600316 -57.900062)
		(size 0.508)
		(drill 0.254)
		(layers "F.Cu" "B.Cu")
		(net "GND")
	)
	(via
		(at 166.3954 -110.9726)
		(size 0.508)
		(drill 0.254)
		(layers "F.Cu" "B.Cu")
		(net "GND")
	)
	(via
		(at 2.159 -125.292866)
		(size 0.7112)
		(drill 0.4064)
		(layers "F.Cu" "B.Cu")
		(net "GND")
	)
	(via
		(at 46.750478 -191.84112)
		(size 0.7112)
		(drill 0.4064)
		(layers "F.Cu" "B.Cu")
		(net "GND")
	)
	(via
		(at 28.498038 -101.703124)
		(size 0.7112)
		(drill 0.4064)
		(layers "F.Cu" "B.Cu")
		(net "GND")
	)
	(via
		(at 206.47533 -2.159)
		(size 0.7112)
		(drill 0.4064)
		(layers "F.Cu" "B.Cu")
		(net "GND")
	)
	(via
		(at 190.429388 -191.84112)
		(size 0.7112)
		(drill 0.4064)
		(layers "F.Cu" "B.Cu")
		(net "GND")
	)
	(via
		(at 15.4432 -167.8686)
		(size 0.5588)
		(drill 0.3048)
		(layers "F.Cu" "B.Cu")
		(net "GND")
	)
	(via
		(at 205.8416 -128.27)
		(size 0.5588)
		(drill 0.3048)
		(layers "F.Cu" "B.Cu")
		(net "GND")
	)
	(via
		(at 183.4642 -154.4828)
		(size 0.508)
		(drill 0.254)
		(layers "F.Cu" "B.Cu")
		(net "GND")
	)
	(via
		(at 154.686 -122.809)
		(size 0.7112)
		(drill 0.4064)
		(layers "F.Cu" "B.Cu")
		(net "GND")
	)
	(via
		(at 28.498038 -92.813124)
		(size 0.7112)
		(drill 0.4064)
		(layers "F.Cu" "B.Cu")
		(net "GND")
	)
	(via
		(at 50.94224 -161.3154)
		(size 0.508)
		(drill 0.254)
		(layers "F.Cu" "B.Cu")
		(net "GND")
	)
	(via
		(at 28.498038 -83.923124)
		(size 0.7112)
		(drill 0.4064)
		(layers "F.Cu" "B.Cu")
		(net "GND")
	)
	(via
		(at 158.8262 -137.1346)
		(size 0.5588)
		(drill 0.3048)
		(layers "F.Cu" "B.Cu")
		(net "GND")
	)
	(via
		(at 28.498038 -105.513124)
		(size 0.7112)
		(drill 0.4064)
		(layers "F.Cu" "B.Cu")
		(net "GND")
	)
	(via
		(at 154.9908 -141.0716)
		(size 0.508)
		(drill 0.254)
		(layers "F.Cu" "B.Cu")
		(net "GND")
	)
	(via
		(at 2.159 -23.692866)
		(size 0.7112)
		(drill 0.4064)
		(layers "F.Cu" "B.Cu")
		(net "GND")
	)
	(via
		(at 176.44745 -82.2706)
		(size 0.508)
		(drill 0.254)
		(layers "F.Cu" "B.Cu")
		(net "GND")
	)
	(via
		(at 51.71567 -153.7843)
		(size 0.4572)
		(drill 0.2032)
		(layers "F.Cu" "B.Cu")
		(net "GND")
	)
	(via
		(at 150.54961 -191.671956)
		(size 0.7112)
		(drill 0.4064)
		(layers "F.Cu" "B.Cu")
		(net "GND")
	)
	(via
		(at 216.63533 -2.159)
		(size 0.7112)
		(drill 0.4064)
		(layers "F.Cu" "B.Cu")
		(net "GND")
	)
	(via
		(at 194.3354 -2.159)
		(size 0.7112)
		(drill 0.4064)
		(layers "F.Cu" "B.Cu")
		(net "GND")
	)
	(via
		(at 20.597876 -127.550164)
		(size 0.508)
		(drill 0.254)
		(layers "F.Cu" "B.Cu")
		(net "GND")
	)
	(via
		(at 28.498038 -54.713124)
		(size 0.7112)
		(drill 0.4064)
		(layers "F.Cu" "B.Cu")
		(net "GND")
	)
	(via
		(at 186.400186 -70.699884)
		(size 0.508)
		(drill 0.254)
		(layers "F.Cu" "B.Cu")
		(net "GND")
	)
	(via
		(at 159.893 -47.625)
		(size 0.508)
		(drill 0.254)
		(layers "F.Cu" "B.Cu")
		(net "GND")
	)
	(via
		(at 37.860478 -191.84112)
		(size 0.7112)
		(drill 0.4064)
		(layers "F.Cu" "B.Cu")
		(net "GND")
	)
	(via
		(at 75.18908 -4.93268)
		(size 0.7112)
		(drill 0.4064)
		(layers "F.Cu" "B.Cu")
		(net "GND")
	)
	(via
		(at 2.159 -182.442866)
		(size 0.7112)
		(drill 0.4064)
		(layers "F.Cu" "B.Cu")
		(net "GND")
	)
	(via
		(at 232.841038 -156.133292)
		(size 0.7112)
		(drill 0.4064)
		(layers "F.Cu" "B.Cu")
		(net "GND")
	)
	(via
		(at 2.159 -10.992866)
		(size 0.7112)
		(drill 0.4064)
		(layers "F.Cu" "B.Cu")
		(net "GND")
	)
	(via
		(at 97.64014 -160.91662)
		(size 0.508)
		(drill 0.254)
		(layers "F.Cu" "B.Cu")
		(net "GND")
	)
	(via
		(at 194.399916 -62.6999)
		(size 0.508)
		(drill 0.254)
		(layers "F.Cu" "B.Cu")
		(net "GND")
	)
	(via
		(at 19.100038 -145.398998)
		(size 0.508)
		(drill 0.254)
		(layers "F.Cu" "B.Cu")
		(net "GND")
	)
	(via
		(at 159.8168 -136.15416)
		(size 0.5588)
		(drill 0.3048)
		(layers "F.Cu" "B.Cu")
		(net "GND")
	)
	(via
		(at 173.3296 -117.7036)
		(size 0.508)
		(drill 0.254)
		(layers "F.Cu" "B.Cu")
		(net "GND")
	)
	(via
		(at 81.643728 -80.48879)
		(size 0.508)
		(drill 0.254)
		(layers "F.Cu" "B.Cu")
		(net "GND")
	)
	(via
		(at 22.535134 -2.159)
		(size 0.7112)
		(drill 0.4064)
		(layers "F.Cu" "B.Cu")
		(net "GND")
	)
	(via
		(at 232.841038 -18.973292)
		(size 0.7112)
		(drill 0.4064)
		(layers "F.Cu" "B.Cu")
		(net "GND")
	)
	(via
		(at 146.45894 -162.157664)
		(size 0.7112)
		(drill 0.4064)
		(layers "F.Cu" "B.Cu")
		(net "GND")
	)
	(via
		(at 189.2554 -2.159)
		(size 0.7112)
		(drill 0.4064)
		(layers "F.Cu" "B.Cu")
		(net "GND")
	)
	(via
		(at 232.841038 -91.363292)
		(size 0.7112)
		(drill 0.4064)
		(layers "F.Cu" "B.Cu")
		(net "GND")
	)
	(via
		(at 188.2902 -47.1678)
		(size 0.508)
		(drill 0.254)
		(layers "F.Cu" "B.Cu")
		(net "GND")
	)
	(via
		(at 58.200798 -161.259774)
		(size 0.508)
		(drill 0.254)
		(layers "F.Cu" "B.Cu")
		(net "GND")
	)
	(via
		(at 205.669388 -191.84112)
		(size 0.7112)
		(drill 0.4064)
		(layers "F.Cu" "B.Cu")
		(net "GND")
	)
	(via
		(at 191.200024 -56.300116)
		(size 0.508)
		(drill 0.254)
		(layers "F.Cu" "B.Cu")
		(net "GND")
	)
	(via
		(at 185.60034 -60.300362)
		(size 0.508)
		(drill 0.254)
		(layers "F.Cu" "B.Cu")
		(net "GND")
	)
	(via
		(at 180.161184 -146.710146)
		(size 0.5588)
		(drill 0.3048)
		(layers "F.Cu" "B.Cu")
		(net "GND")
	)
	(via
		(at 173.8376 -79.6036)
		(size 0.508)
		(drill 0.254)
		(layers "F.Cu" "B.Cu")
		(net "GND")
	)
	(via
		(at 185.60034 -67.5005)
		(size 0.508)
		(drill 0.254)
		(layers "F.Cu" "B.Cu")
		(net "GND")
	)
	(via
		(at 2.159 -50.362866)
		(size 0.7112)
		(drill 0.4064)
		(layers "F.Cu" "B.Cu")
		(net "GND")
	)
	(via
		(at 232.841038 -98.983292)
		(size 0.7112)
		(drill 0.4064)
		(layers "F.Cu" "B.Cu")
		(net "GND")
	)
	(via
		(at 2.159 -66.872866)
		(size 0.7112)
		(drill 0.4064)
		(layers "F.Cu" "B.Cu")
		(net "GND")
	)
	(via
		(at 215.829388 -191.84112)
		(size 0.7112)
		(drill 0.4064)
		(layers "F.Cu" "B.Cu")
		(net "GND")
	)
	(via
		(at 28.498038 -17.883124)
		(size 0.7112)
		(drill 0.4064)
		(layers "F.Cu" "B.Cu")
		(net "GND")
	)
	(via
		(at 2.159 -24.962866)
		(size 0.7112)
		(drill 0.4064)
		(layers "F.Cu" "B.Cu")
		(net "GND")
	)
	(via
		(at 192.79997 -56.300116)
		(size 0.508)
		(drill 0.254)
		(layers "F.Cu" "B.Cu")
		(net "GND")
	)
	(via
		(at 28.498038 -20.423124)
		(size 0.7112)
		(drill 0.4064)
		(layers "F.Cu" "B.Cu")
		(net "GND")
	)
	(via
		(at 41.670478 -191.84112)
		(size 0.7112)
		(drill 0.4064)
		(layers "F.Cu" "B.Cu")
		(net "GND")
	)
	(via
		(at 184.799986 -61.099954)
		(size 0.508)
		(drill 0.254)
		(layers "F.Cu" "B.Cu")
		(net "GND")
	)
	(via
		(at 74.3839 -148.8694)
		(size 0.508)
		(drill 0.254)
		(layers "F.Cu" "B.Cu")
		(net "GND")
	)
	(via
		(at 201.600054 -60.300108)
		(size 0.508)
		(drill 0.254)
		(layers "F.Cu" "B.Cu")
		(net "GND")
	)
	(via
		(at 188.000132 -69.900038)
		(size 0.508)
		(drill 0.254)
		(layers "F.Cu" "B.Cu")
		(net "GND")
	)
	(via
		(at 206.5401 -135.4963)
		(size 0.508)
		(drill 0.254)
		(layers "F.Cu" "B.Cu")
		(net "GND")
	)
	(via
		(at 35.538664 -183.850788)
		(size 0.5588)
		(drill 0.3048)
		(layers "F.Cu" "B.Cu")
		(net "GND")
	)
	(via
		(at 188.000386 -70.69963)
		(size 0.508)
		(drill 0.254)
		(layers "F.Cu" "B.Cu")
		(net "GND")
	)
	(via
		(at 146.45894 -169.777664)
		(size 0.7112)
		(drill 0.4064)
		(layers "F.Cu" "B.Cu")
		(net "GND")
	)
	(via
		(at 179.9844 -154.559)
		(size 0.508)
		(drill 0.254)
		(layers "F.Cu" "B.Cu")
		(net "GND")
	)
	(via
		(at 188.000132 -64.299846)
		(size 0.508)
		(drill 0.254)
		(layers "F.Cu" "B.Cu")
		(net "GND")
	)
	(via
		(at 232.841038 -17.703292)
		(size 0.7112)
		(drill 0.4064)
		(layers "F.Cu" "B.Cu")
		(net "GND")
	)
	(via
		(at 28.498038 -100.433124)
		(size 0.7112)
		(drill 0.4064)
		(layers "F.Cu" "B.Cu")
		(net "GND")
	)
	(via
		(at 187.200032 -64.299846)
		(size 0.508)
		(drill 0.254)
		(layers "F.Cu" "B.Cu")
		(net "GND")
	)
	(via
		(at 48.708564 -172.69968)
		(size 0.508)
		(drill 0.254)
		(layers "F.Cu" "B.Cu")
		(net "GND")
	)
	(via
		(at 12.375134 -2.159)
		(size 0.7112)
		(drill 0.4064)
		(layers "F.Cu" "B.Cu")
		(net "GND")
	)
	(via
		(at 232.841038 -121.843292)
		(size 0.7112)
		(drill 0.4064)
		(layers "F.Cu" "B.Cu")
		(net "GND")
	)
	(via
		(at 232.841038 -13.893292)
		(size 0.7112)
		(drill 0.4064)
		(layers "F.Cu" "B.Cu")
		(net "GND")
	)
	(via
		(at 17.234662 -141.761718)
		(size 0.508)
		(drill 0.254)
		(layers "F.Cu" "B.Cu")
		(net "GND")
	)
	(via
		(at 175.589184 -145.440146)
		(size 0.5588)
		(drill 0.3048)
		(layers "F.Cu" "B.Cu")
		(net "GND")
	)
	(via
		(at 81.643728 -93.288866)
		(size 0.508)
		(drill 0.254)
		(layers "F.Cu" "B.Cu")
		(net "GND")
	)
	(via
		(at 92.751656 -155.60548)
		(size 0.5588)
		(drill 0.3048)
		(layers "F.Cu" "B.Cu")
		(net "GND")
	)
	(via
		(at 199.5932 -116.332)
		(size 0.7112)
		(drill 0.4064)
		(layers "F.Cu" "B.Cu")
		(net "GND")
	)
	(via
		(at 66.709036 -180.653182)
		(size 0.508)
		(drill 0.254)
		(layers "F.Cu" "B.Cu")
		(net "GND")
	)
	(via
		(at 51.699668 -149.800056)
		(size 0.4572)
		(drill 0.2032)
		(layers "F.Cu" "B.Cu")
		(net "GND")
	)
	(via
		(at 199.192134 -72.301608)
		(size 0.508)
		(drill 0.254)
		(layers "F.Cu" "B.Cu")
		(net "GND")
	)
	(via
		(at 146.45894 -149.457664)
		(size 0.7112)
		(drill 0.4064)
		(layers "F.Cu" "B.Cu")
		(net "GND")
	)
	(via
		(at 146.45894 -168.507664)
		(size 0.7112)
		(drill 0.4064)
		(layers "F.Cu" "B.Cu")
		(net "GND")
	)
	(via
		(at 94.291658 -143.97482)
		(size 0.508)
		(drill 0.254)
		(layers "F.Cu" "B.Cu")
		(net "GND")
	)
	(via
		(at 232.841038 -63.423292)
		(size 0.7112)
		(drill 0.4064)
		(layers "F.Cu" "B.Cu")
		(net "GND")
	)
	(via
		(at 75.13828 -181.66588)
		(size 0.5588)
		(drill 0.3048)
		(layers "F.Cu" "B.Cu")
		(net "GND")
	)
	(via
		(at 2.159 -173.552866)
		(size 0.7112)
		(drill 0.4064)
		(layers "F.Cu" "B.Cu")
		(net "GND")
	)
	(via
		(at 76.552044 -160.9471)
		(size 0.5588)
		(drill 0.3048)
		(layers "F.Cu" "B.Cu")
		(net "GND")
	)
	(via
		(at 189.159388 -191.84112)
		(size 0.7112)
		(drill 0.4064)
		(layers "F.Cu" "B.Cu")
		(net "GND")
	)
	(via
		(at 2.159 -164.662866)
		(size 0.7112)
		(drill 0.4064)
		(layers "F.Cu" "B.Cu")
		(net "GND")
	)
	(via
		(at 7.3152 -139.566396)
		(size 0.508)
		(drill 0.254)
		(layers "F.Cu" "B.Cu")
		(net "GND")
	)
	(via
		(at 219.17533 -2.159)
		(size 0.7112)
		(drill 0.4064)
		(layers "F.Cu" "B.Cu")
		(net "GND")
	)
	(via
		(at 186.400186 -69.900292)
		(size 0.508)
		(drill 0.254)
		(layers "F.Cu" "B.Cu")
		(net "GND")
	)
	(via
		(at 55.3466 -179.06619)
		(size 0.7112)
		(drill 0.4064)
		(layers "F.Cu" "B.Cu")
		(net "GND")
	)
	(via
		(at 50.95494 -162.461194)
		(size 0.508)
		(drill 0.254)
		(layers "F.Cu" "B.Cu")
		(net "GND")
	)
	(via
		(at 196.796406 -69.894196)
		(size 0.508)
		(drill 0.254)
		(layers "F.Cu" "B.Cu")
		(net "GND")
	)
	(via
		(at 2.159 -27.502866)
		(size 0.7112)
		(drill 0.4064)
		(layers "F.Cu" "B.Cu")
		(net "GND")
	)
	(via
		(at 232.841038 -54.533292)
		(size 0.7112)
		(drill 0.4064)
		(layers "F.Cu" "B.Cu")
		(net "GND")
	)
	(via
		(at 146.45894 -141.837664)
		(size 0.7112)
		(drill 0.4064)
		(layers "F.Cu" "B.Cu")
		(net "GND")
	)
	(via
		(at 89.027 -164.4904)
		(size 0.508)
		(drill 0.254)
		(layers "F.Cu" "B.Cu")
		(net "GND")
	)
	(via
		(at 185.60034 -65.100708)
		(size 0.508)
		(drill 0.254)
		(layers "F.Cu" "B.Cu")
		(net "GND")
	)
	(via
		(at 28.498038 -67.413124)
		(size 0.7112)
		(drill 0.4064)
		(layers "F.Cu" "B.Cu")
		(net "GND")
	)
	(via
		(at 183.34228 -80.2005)
		(size 0.508)
		(drill 0.254)
		(layers "F.Cu" "B.Cu")
		(net "GND")
	)
	(via
		(at 34.85134 -157.99562)
		(size 0.508)
		(drill 0.254)
		(layers "F.Cu" "B.Cu")
		(net "GND")
	)
	(via
		(at 203.4032 -133.8326)
		(size 0.508)
		(drill 0.254)
		(layers "F.Cu" "B.Cu")
		(net "GND")
	)
	(via
		(at 28.2702 -179.197)
		(size 0.508)
		(drill 0.254)
		(layers "F.Cu" "B.Cu")
		(net "GND")
	)
	(via
		(at 146.45894 -129.137664)
		(size 0.7112)
		(drill 0.4064)
		(layers "F.Cu" "B.Cu")
		(net "GND")
	)
	(via
		(at 2.159 -181.172866)
		(size 0.7112)
		(drill 0.4064)
		(layers "F.Cu" "B.Cu")
		(net "GND")
	)
	(via
		(at 52.9082 -179.06619)
		(size 0.7112)
		(drill 0.4064)
		(layers "F.Cu" "B.Cu")
		(net "GND")
	)
	(via
		(at 40.132 -122.0978)
		(size 0.508)
		(drill 0.254)
		(layers "F.Cu" "B.Cu")
		(net "GND")
	)
	(via
		(at 14.915134 -2.159)
		(size 0.7112)
		(drill 0.4064)
		(layers "F.Cu" "B.Cu")
		(net "GND")
	)
	(via
		(at 186.400186 -61.100208)
		(size 0.508)
		(drill 0.254)
		(layers "F.Cu" "B.Cu")
		(net "GND")
	)
	(via
		(at 232.841038 -95.173292)
		(size 0.7112)
		(drill 0.4064)
		(layers "F.Cu" "B.Cu")
		(net "GND")
	)
	(via
		(at 190.393066 -75.502516)
		(size 0.508)
		(drill 0.254)
		(layers "F.Cu" "B.Cu")
		(net "GND")
	)
	(via
		(at 146.45894 -160.887664)
		(size 0.7112)
		(drill 0.4064)
		(layers "F.Cu" "B.Cu")
		(net "GND")
	)
	(via
		(at 2.159 -136.722866)
		(size 0.7112)
		(drill 0.4064)
		(layers "F.Cu" "B.Cu")
		(net "GND")
	)
	(via
		(at 232.841038 -148.513292)
		(size 0.7112)
		(drill 0.4064)
		(layers "F.Cu" "B.Cu")
		(net "GND")
	)
	(via
		(at 189.590934 -64.299846)
		(size 0.508)
		(drill 0.254)
		(layers "F.Cu" "B.Cu")
		(net "GND")
	)
	(via
		(at 49.6062 -134.4676)
		(size 0.508)
		(drill 0.254)
		(layers "F.Cu" "B.Cu")
		(net "GND")
	)
	(via
		(at 50.099722 -137.000234)
		(size 0.4572)
		(drill 0.2032)
		(layers "F.Cu" "B.Cu")
		(net "GND")
	)
	(via
		(at 50.899822 -151.400002)
		(size 0.4572)
		(drill 0.2032)
		(layers "F.Cu" "B.Cu")
		(net "GND")
	)
	(via
		(at 146.45894 -176.127664)
		(size 0.7112)
		(drill 0.4064)
		(layers "F.Cu" "B.Cu")
		(net "GND")
	)
	(via
		(at 163.9062 -170.0784)
		(size 0.7112)
		(drill 0.4064)
		(layers "F.Cu" "B.Cu")
		(net "GND")
	)
	(via
		(at 199.3138 -102.9716)
		(size 0.7112)
		(drill 0.4064)
		(layers "F.Cu" "B.Cu")
		(net "GND")
	)
	(via
		(at 232.841038 -51.993292)
		(size 0.7112)
		(drill 0.4064)
		(layers "F.Cu" "B.Cu")
		(net "GND")
	)
	(via
		(at 28.498038 -81.383124)
		(size 0.7112)
		(drill 0.4064)
		(layers "F.Cu" "B.Cu")
		(net "GND")
	)
	(via
		(at 81.758028 -74.135996)
		(size 0.508)
		(drill 0.254)
		(layers "F.Cu" "B.Cu")
		(net "GND")
	)
	(via
		(at 146.45894 -116.437664)
		(size 0.7112)
		(drill 0.4064)
		(layers "F.Cu" "B.Cu")
		(net "GND")
	)
	(via
		(at 2.159 -111.322866)
		(size 0.7112)
		(drill 0.4064)
		(layers "F.Cu" "B.Cu")
		(net "GND")
	)
	(via
		(at 146.45894 -179.937664)
		(size 0.7112)
		(drill 0.4064)
		(layers "F.Cu" "B.Cu")
		(net "GND")
	)
	(via
		(at 191.3636 -47.0916)
		(size 0.508)
		(drill 0.254)
		(layers "F.Cu" "B.Cu")
		(net "GND")
	)
	(via
		(at 196.8754 -2.159)
		(size 0.7112)
		(drill 0.4064)
		(layers "F.Cu" "B.Cu")
		(net "GND")
	)
	(via
		(at 146.45894 -113.897664)
		(size 0.7112)
		(drill 0.4064)
		(layers "F.Cu" "B.Cu")
		(net "GND")
	)
	(via
		(at 132.15874 -19.4818)
		(size 0.7112)
		(drill 0.4064)
		(layers "F.Cu" "B.Cu")
		(net "GND")
	)
	(via
		(at 217.099388 -191.84112)
		(size 0.7112)
		(drill 0.4064)
		(layers "F.Cu" "B.Cu")
		(net "GND")
	)
	(via
		(at 28.498038 -75.033124)
		(size 0.7112)
		(drill 0.4064)
		(layers "F.Cu" "B.Cu")
		(net "GND")
	)
	(via
		(at 146.574002 -183.720486)
		(size 0.7112)
		(drill 0.4064)
		(layers "F.Cu" "B.Cu")
		(net "GND")
	)
	(via
		(at 83.57489 -131.90855)
		(size 0.508)
		(drill 0.254)
		(layers "F.Cu" "B.Cu")
		(net "GND")
	)
	(via
		(at 85.1789 -173.9011)
		(size 0.7112)
		(drill 0.4064)
		(layers "F.Cu" "B.Cu")
		(net "GND")
	)
	(via
		(at 73.787 -162.7124)
		(size 0.508)
		(drill 0.254)
		(layers "F.Cu" "B.Cu")
		(net "GND")
	)
	(via
		(at 214.884 -120.9294)
		(size 0.508)
		(drill 0.254)
		(layers "F.Cu" "B.Cu")
		(net "GND")
	)
	(via
		(at 232.841038 -181.533292)
		(size 0.7112)
		(drill 0.4064)
		(layers "F.Cu" "B.Cu")
		(net "GND")
	)
	(via
		(at 2.159 -178.632866)
		(size 0.7112)
		(drill 0.4064)
		(layers "F.Cu" "B.Cu")
		(net "GND")
	)
	(via
		(at 190.3984 -50.6222)
		(size 0.508)
		(drill 0.254)
		(layers "F.Cu" "B.Cu")
		(net "GND")
	)
	(via
		(at 232.841038 -153.593292)
		(size 0.7112)
		(drill 0.4064)
		(layers "F.Cu" "B.Cu")
		(net "GND")
	)
	(via
		(at 28.498038 -48.363124)
		(size 0.7112)
		(drill 0.4064)
		(layers "F.Cu" "B.Cu")
		(net "GND")
	)
	(via
		(at 146.45894 -158.347664)
		(size 0.7112)
		(drill 0.4064)
		(layers "F.Cu" "B.Cu")
		(net "GND")
	)
	(via
		(at 173.919388 -191.84112)
		(size 0.7112)
		(drill 0.4064)
		(layers "F.Cu" "B.Cu")
		(net "GND")
	)
	(via
		(at 37.160454 -116.8908)
		(size 0.508)
		(drill 0.254)
		(layers "F.Cu" "B.Cu")
		(net "GND")
	)
	(via
		(at 232.841038 -133.273292)
		(size 0.7112)
		(drill 0.4064)
		(layers "F.Cu" "B.Cu")
		(net "GND")
	)
	(via
		(at 2.159 -93.542866)
		(size 0.7112)
		(drill 0.4064)
		(layers "F.Cu" "B.Cu")
		(net "GND")
	)
	(via
		(at 42.900092 -149.800056)
		(size 0.4572)
		(drill 0.2032)
		(layers "F.Cu" "B.Cu")
		(net "GND")
	)
	(via
		(at 26.430478 -191.84112)
		(size 0.7112)
		(drill 0.4064)
		(layers "F.Cu" "B.Cu")
		(net "GND")
	)
	(via
		(at 46.900084 -141.00048)
		(size 0.4572)
		(drill 0.2032)
		(layers "F.Cu" "B.Cu")
		(net "GND")
	)
	(via
		(at 190.36157 -51.3588)
		(size 0.508)
		(drill 0.254)
		(layers "F.Cu" "B.Cu")
		(net "GND")
	)
	(via
		(at 2.159 -150.692866)
		(size 0.7112)
		(drill 0.4064)
		(layers "F.Cu" "B.Cu")
		(net "GND")
	)
	(via
		(at 201.600054 -76.299822)
		(size 0.508)
		(drill 0.254)
		(layers "F.Cu" "B.Cu")
		(net "GND")
	)
	(via
		(at 68.04152 -179.04968)
		(size 0.508)
		(drill 0.254)
		(layers "F.Cu" "B.Cu")
		(net "GND")
	)
	(via
		(at 232.841038 -180.263292)
		(size 0.7112)
		(drill 0.4064)
		(layers "F.Cu" "B.Cu")
		(net "GND")
	)
	(via
		(at 33.820608 -122.954796)
		(size 0.508)
		(drill 0.254)
		(layers "F.Cu" "B.Cu")
		(net "GND")
	)
	(via
		(at 202.66533 -2.159)
		(size 0.7112)
		(drill 0.4064)
		(layers "F.Cu" "B.Cu")
		(net "GND")
	)
	(via
		(at 146.45894 -125.327664)
		(size 0.7112)
		(drill 0.4064)
		(layers "F.Cu" "B.Cu")
		(net "GND")
	)
	(via
		(at 2.159 -19.882866)
		(size 0.7112)
		(drill 0.4064)
		(layers "F.Cu" "B.Cu")
		(net "GND")
	)
	(via
		(at 2.159 -115.132866)
		(size 0.7112)
		(drill 0.4064)
		(layers "F.Cu" "B.Cu")
		(net "GND")
	)
	(via
		(at 190.396622 -72.30618)
		(size 0.508)
		(drill 0.254)
		(layers "F.Cu" "B.Cu")
		(net "GND")
	)
	(via
		(at 191.200278 -69.900038)
		(size 0.508)
		(drill 0.254)
		(layers "F.Cu" "B.Cu")
		(net "GND")
	)
	(via
		(at 28.498038 -68.683124)
		(size 0.7112)
		(drill 0.4064)
		(layers "F.Cu" "B.Cu")
		(net "GND")
	)
	(via
		(at 28.498038 -42.013124)
		(size 0.7112)
		(drill 0.4064)
		(layers "F.Cu" "B.Cu")
		(net "GND")
	)
	(via
		(at 180.953918 -89.6112)
		(size 0.508)
		(drill 0.254)
		(layers "F.Cu" "B.Cu")
		(net "GND")
	)
	(via
		(at 232.841038 -110.413292)
		(size 0.7112)
		(drill 0.4064)
		(layers "F.Cu" "B.Cu")
		(net "GND")
	)
	(via
		(at 211.5312 -116.6622)
		(size 0.7112)
		(drill 0.4064)
		(layers "F.Cu" "B.Cu")
		(net "GND")
	)
	(via
		(at 216.1794 -103.505)
		(size 0.508)
		(drill 0.254)
		(layers "F.Cu" "B.Cu")
		(net "GND")
	)
	(via
		(at 185.60034 -61.100462)
		(size 0.508)
		(drill 0.254)
		(layers "F.Cu" "B.Cu")
		(net "GND")
	)
	(via
		(at 205.20533 -2.159)
		(size 0.7112)
		(drill 0.4064)
		(layers "F.Cu" "B.Cu")
		(net "GND")
	)
	(via
		(at 232.841038 -79.933292)
		(size 0.7112)
		(drill 0.4064)
		(layers "F.Cu" "B.Cu")
		(net "GND")
	)
	(via
		(at 162.489388 -191.84112)
		(size 0.7112)
		(drill 0.4064)
		(layers "F.Cu" "B.Cu")
		(net "GND")
	)
	(via
		(at 146.45894 -151.997664)
		(size 0.7112)
		(drill 0.4064)
		(layers "F.Cu" "B.Cu")
		(net "GND")
	)
	(via
		(at 232.841038 -134.543292)
		(size 0.7112)
		(drill 0.4064)
		(layers "F.Cu" "B.Cu")
		(net "GND")
	)
	(via
		(at 28.498038 -49.633124)
		(size 0.7112)
		(drill 0.4064)
		(layers "F.Cu" "B.Cu")
		(net "GND")
	)
	(via
		(at 28.498038 -21.693124)
		(size 0.7112)
		(drill 0.4064)
		(layers "F.Cu" "B.Cu")
		(net "GND")
	)
	(via
		(at 189.600078 -69.099938)
		(size 0.508)
		(drill 0.254)
		(layers "F.Cu" "B.Cu")
		(net "GND")
	)
	(via
		(at 231.87533 -2.159)
		(size 0.7112)
		(drill 0.4064)
		(layers "F.Cu" "B.Cu")
		(net "GND")
	)
	(via
		(at 174.752 -79.5528)
		(size 0.508)
		(drill 0.254)
		(layers "F.Cu" "B.Cu")
		(net "GND")
	)
	(via
		(at 65.752726 -153.1747)
		(size 0.508)
		(drill 0.254)
		(layers "F.Cu" "B.Cu")
		(net "GND")
	)
	(via
		(at 77.50048 -2.159)
		(size 0.7112)
		(drill 0.4064)
		(layers "F.Cu" "B.Cu")
		(net "GND")
	)
	(via
		(at 2.159 -116.402866)
		(size 0.7112)
		(drill 0.4064)
		(layers "F.Cu" "B.Cu")
		(net "GND")
	)
	(via
		(at 45.480478 -191.84112)
		(size 0.7112)
		(drill 0.4064)
		(layers "F.Cu" "B.Cu")
		(net "GND")
	)
	(via
		(at 193.60007 -54.70017)
		(size 0.508)
		(drill 0.254)
		(layers "F.Cu" "B.Cu")
		(net "GND")
	)
	(via
		(at 76.23048 -2.159)
		(size 0.7112)
		(drill 0.4064)
		(layers "F.Cu" "B.Cu")
		(net "GND")
	)
	(via
		(at 2.81686 -184.862724)
		(size 0.7112)
		(drill 0.4064)
		(layers "F.Cu" "B.Cu")
		(net "GND")
	)
	(via
		(at 7.406132 -138.13917)
		(size 0.508)
		(drill 0.254)
		(layers "F.Cu" "B.Cu")
		(net "GND")
	)
	(via
		(at 198.400162 -57.900316)
		(size 0.508)
		(drill 0.254)
		(layers "F.Cu" "B.Cu")
		(net "GND")
	)
	(via
		(at 68.5546 -144.175226)
		(size 0.508)
		(drill 0.254)
		(layers "F.Cu" "B.Cu")
		(net "GND")
	)
	(via
		(at 184.6961 -46.8757)
		(size 0.508)
		(drill 0.254)
		(layers "F.Cu" "B.Cu")
		(net "GND")
	)
	(via
		(at 28.498038 -82.653124)
		(size 0.7112)
		(drill 0.4064)
		(layers "F.Cu" "B.Cu")
		(net "GND")
	)
	(via
		(at 25.2984 -171.069)
		(size 0.7112)
		(drill 0.4064)
		(layers "F.Cu" "B.Cu")
		(net "GND")
	)
	(via
		(at 146.45894 -154.537664)
		(size 0.7112)
		(drill 0.4064)
		(layers "F.Cu" "B.Cu")
		(net "GND")
	)
	(via
		(at 2.159 -83.382866)
		(size 0.7112)
		(drill 0.4064)
		(layers "F.Cu" "B.Cu")
		(net "GND")
	)
	(via
		(at 34.294826 -182.65013)
		(size 0.5588)
		(drill 0.3048)
		(layers "F.Cu" "B.Cu")
		(net "GND")
	)
	(via
		(at 22.834346 -143.36141)
		(size 0.508)
		(drill 0.254)
		(layers "F.Cu" "B.Cu")
		(net "GND")
	)
	(via
		(at 163.9062 -162.7632)
		(size 0.7112)
		(drill 0.4064)
		(layers "F.Cu" "B.Cu")
		(net "GND")
	)
	(via
		(at 34.294826 -180.49113)
		(size 0.5588)
		(drill 0.3048)
		(layers "F.Cu" "B.Cu")
		(net "GND")
	)
	(via
		(at 175.658526 -147.953984)
		(size 0.5588)
		(drill 0.3048)
		(layers "F.Cu" "B.Cu")
		(net "GND")
	)
	(via
		(at 48.54194 -155.2067)
		(size 0.508)
		(drill 0.254)
		(layers "F.Cu" "B.Cu")
		(net "GND")
	)
	(via
		(at 29.3878 -189.1792)
		(size 0.7112)
		(drill 0.4064)
		(layers "F.Cu" "B.Cu")
		(net "GND")
	)
	(via
		(at 47.43069 -117.791992)
		(size 0.508)
		(drill 0.254)
		(layers "F.Cu" "B.Cu")
		(net "GND")
	)
	(via
		(at 196.000116 -64.3001)
		(size 0.508)
		(drill 0.254)
		(layers "F.Cu" "B.Cu")
		(net "GND")
	)
	(via
		(at 28.498038 -59.793124)
		(size 0.7112)
		(drill 0.4064)
		(layers "F.Cu" "B.Cu")
		(net "GND")
	)
	(via
		(at 209.01533 -2.159)
		(size 0.7112)
		(drill 0.4064)
		(layers "F.Cu" "B.Cu")
		(net "GND")
	)
	(via
		(at 79.770478 -191.84112)
		(size 0.7112)
		(drill 0.4064)
		(layers "F.Cu" "B.Cu")
		(net "GND")
	)
	(via
		(at 167.132 -108.204)
		(size 0.7112)
		(drill 0.4064)
		(layers "F.Cu" "B.Cu")
		(net "GND")
	)
	(via
		(at 55.0164 -167.2336)
		(size 0.508)
		(drill 0.254)
		(layers "F.Cu" "B.Cu")
		(net "GND")
	)
	(via
		(at 62.8396 -149.7584)
		(size 0.508)
		(drill 0.254)
		(layers "F.Cu" "B.Cu")
		(net "GND")
	)
	(via
		(at 189.600078 -57.900316)
		(size 0.508)
		(drill 0.254)
		(layers "F.Cu" "B.Cu")
		(net "GND")
	)
	(via
		(at 184.00014 -71.499984)
		(size 0.508)
		(drill 0.254)
		(layers "F.Cu" "B.Cu")
		(net "GND")
	)
	(via
		(at 232.841038 -24.053292)
		(size 0.7112)
		(drill 0.4064)
		(layers "F.Cu" "B.Cu")
		(net "GND")
	)
	(via
		(at 28.498038 -61.063124)
		(size 0.7112)
		(drill 0.4064)
		(layers "F.Cu" "B.Cu")
		(net "GND")
	)
	(via
		(at 75.18908 -6.20268)
		(size 0.7112)
		(drill 0.4064)
		(layers "F.Cu" "B.Cu")
		(net "GND")
	)
	(via
		(at 4.755134 -2.159)
		(size 0.7112)
		(drill 0.4064)
		(layers "F.Cu" "B.Cu")
		(net "GND")
	)
	(via
		(at 36.7792 -167.1066)
		(size 0.508)
		(drill 0.254)
		(layers "F.Cu" "B.Cu")
		(net "GND")
	)
	(via
		(at 146.45894 -121.517664)
		(size 0.7112)
		(drill 0.4064)
		(layers "F.Cu" "B.Cu")
		(net "GND")
	)
	(via
		(at 166.37 -176.6316)
		(size 0.7112)
		(drill 0.4064)
		(layers "F.Cu" "B.Cu")
		(net "GND")
	)
	(via
		(at 54.370478 -191.84112)
		(size 0.7112)
		(drill 0.4064)
		(layers "F.Cu" "B.Cu")
		(net "GND")
	)
	(via
		(at 68.340478 -191.84112)
		(size 0.7112)
		(drill 0.4064)
		(layers "F.Cu" "B.Cu")
		(net "GND")
	)
	(via
		(at 232.841038 -172.643292)
		(size 0.7112)
		(drill 0.4064)
		(layers "F.Cu" "B.Cu")
		(net "GND")
	)
	(via
		(at 88.664288 -48.202596)
		(size 0.508)
		(drill 0.254)
		(layers "F.Cu" "B.Cu")
		(net "GND")
	)
	(via
		(at 221.71533 -2.159)
		(size 0.7112)
		(drill 0.4064)
		(layers "F.Cu" "B.Cu")
		(net "GND")
	)
	(via
		(at 28.498038 -104.243124)
		(size 0.7112)
		(drill 0.4064)
		(layers "F.Cu" "B.Cu")
		(net "GND")
	)
	(via
		(at 2.159 -113.862866)
		(size 0.7112)
		(drill 0.4064)
		(layers "F.Cu" "B.Cu")
		(net "GND")
	)
	(via
		(at 146.45894 -146.917664)
		(size 0.7112)
		(drill 0.4064)
		(layers "F.Cu" "B.Cu")
		(net "GND")
	)
	(via
		(at 61.468 -176.1236)
		(size 0.508)
		(drill 0.254)
		(layers "F.Cu" "B.Cu")
		(net "GND")
	)
	(via
		(at 81.643728 -90.088974)
		(size 0.508)
		(drill 0.254)
		(layers "F.Cu" "B.Cu")
		(net "GND")
	)
	(via
		(at 2.159 -31.312866)
		(size 0.7112)
		(drill 0.4064)
		(layers "F.Cu" "B.Cu")
		(net "GND")
	)
	(via
		(at 192.000124 -58.700162)
		(size 0.508)
		(drill 0.254)
		(layers "F.Cu" "B.Cu")
		(net "GND")
	)
	(via
		(at 186.812936 -117.596412)
		(size 0.7112)
		(drill 0.4064)
		(layers "F.Cu" "B.Cu")
		(net "GND")
	)
	(via
		(at 2.159 -22.422866)
		(size 0.7112)
		(drill 0.4064)
		(layers "F.Cu" "B.Cu")
		(net "GND")
	)
	(via
		(at 170.2816 -141.1986)
		(size 0.7112)
		(drill 0.4064)
		(layers "F.Cu" "B.Cu")
		(net "GND")
	)
	(via
		(at 188.000132 -63.499746)
		(size 0.508)
		(drill 0.254)
		(layers "F.Cu" "B.Cu")
		(net "GND")
	)
	(via
		(at 78.8289 -136.726422)
		(size 0.508)
		(drill 0.254)
		(layers "F.Cu" "B.Cu")
		(net "GND")
	)
	(via
		(at 166.37 -174.1932)
		(size 0.7112)
		(drill 0.4064)
		(layers "F.Cu" "B.Cu")
		(net "GND")
	)
	(via
		(at 191.200024 -58.700162)
		(size 0.508)
		(drill 0.254)
		(layers "F.Cu" "B.Cu")
		(net "GND")
	)
	(via
		(at 20.080478 -191.84112)
		(size 0.7112)
		(drill 0.4064)
		(layers "F.Cu" "B.Cu")
		(net "GND")
	)
	(via
		(at 170.2816 -143.637)
		(size 0.7112)
		(drill 0.4064)
		(layers "F.Cu" "B.Cu")
		(net "GND")
	)
	(via
		(at 28.498038 -16.613124)
		(size 0.7112)
		(drill 0.4064)
		(layers "F.Cu" "B.Cu")
		(net "GND")
	)
	(via
		(at 188.000132 -65.099946)
		(size 0.508)
		(drill 0.254)
		(layers "F.Cu" "B.Cu")
		(net "GND")
	)
	(via
		(at 146.45894 -139.297664)
		(size 0.7112)
		(drill 0.4064)
		(layers "F.Cu" "B.Cu")
		(net "GND")
	)
	(via
		(at 96.3676 -163.0172)
		(size 0.508)
		(drill 0.254)
		(layers "F.Cu" "B.Cu")
		(net "GND")
	)
	(via
		(at 191.200024 -57.100216)
		(size 0.508)
		(drill 0.254)
		(layers "F.Cu" "B.Cu")
		(net "GND")
	)
	(via
		(at 24.8412 -154.0002)
		(size 0.508)
		(drill 0.254)
		(layers "F.Cu" "B.Cu")
		(net "GND")
	)
	(via
		(at 2.159 -153.232866)
		(size 0.7112)
		(drill 0.4064)
		(layers "F.Cu" "B.Cu")
		(net "GND")
	)
	(via
		(at 96.647 -7.62)
		(size 0.508)
		(drill 0.254)
		(layers "F.Cu" "B.Cu")
		(net "GND")
	)
	(via
		(at 95.3262 -18.3261)
		(size 0.508)
		(drill 0.254)
		(layers "F.Cu" "B.Cu")
		(net "GND")
	)
	(via
		(at 192.800224 -67.500246)
		(size 0.508)
		(drill 0.254)
		(layers "F.Cu" "B.Cu")
		(net "GND")
	)
	(via
		(at 199.9996 -73.09993)
		(size 0.508)
		(drill 0.254)
		(layers "F.Cu" "B.Cu")
		(net "GND")
	)
	(via
		(at 188.0362 -113.3602)
		(size 0.7112)
		(drill 0.4064)
		(layers "F.Cu" "B.Cu")
		(net "GND")
	)
	(via
		(at 92.5068 -181.1274)
		(size 0.508)
		(drill 0.254)
		(layers "F.Cu" "B.Cu")
		(net "GND")
	)
	(via
		(at 146.45894 -143.107664)
		(size 0.7112)
		(drill 0.4064)
		(layers "F.Cu" "B.Cu")
		(net "GND")
	)
	(via
		(at 87.390478 -191.84112)
		(size 0.7112)
		(drill 0.4064)
		(layers "F.Cu" "B.Cu")
		(net "GND")
	)
	(via
		(at 198.374 -116.332)
		(size 0.7112)
		(drill 0.4064)
		(layers "F.Cu" "B.Cu")
		(net "GND")
	)
	(via
		(at 232.841038 -173.913292)
		(size 0.7112)
		(drill 0.4064)
		(layers "F.Cu" "B.Cu")
		(net "GND")
	)
	(via
		(at 53.643784 -123.891548)
		(size 0.508)
		(drill 0.254)
		(layers "F.Cu" "B.Cu")
		(net "GND")
	)
	(via
		(at 221.6785 -102.4636)
		(size 0.508)
		(drill 0.254)
		(layers "F.Cu" "B.Cu")
		(net "GND")
	)
	(via
		(at 162.91052 -176.04486)
		(size 0.6604)
		(drill 0.3302)
		(layers "F.Cu" "B.Cu")
		(net "GND")
	)
	(via
		(at 213.289388 -191.84112)
		(size 0.7112)
		(drill 0.4064)
		(layers "F.Cu" "B.Cu")
		(net "GND")
	)
	(via
		(at 48.50003 -144.199864)
		(size 0.4572)
		(drill 0.2032)
		(layers "F.Cu" "B.Cu")
		(net "GND")
	)
	(via
		(at 28.498038 -76.303124)
		(size 0.7112)
		(drill 0.4064)
		(layers "F.Cu" "B.Cu")
		(net "GND")
	)
	(via
		(at 183.200294 -62.700154)
		(size 0.508)
		(drill 0.254)
		(layers "F.Cu" "B.Cu")
		(net "GND")
	)
	(via
		(at 77.84338 -188.86678)
		(size 0.508)
		(drill 0.254)
		(layers "F.Cu" "B.Cu")
		(net "GND")
	)
	(via
		(at 78.070456 -128.4605)
		(size 0.508)
		(drill 0.254)
		(layers "F.Cu" "B.Cu")
		(net "GND")
	)
	(via
		(at 91.948 -31.496)
		(size 0.508)
		(drill 0.254)
		(layers "F.Cu" "B.Cu")
		(net "GND")
	)
	(via
		(at 232.841038 -6.273292)
		(size 0.7112)
		(drill 0.4064)
		(layers "F.Cu" "B.Cu")
		(net "GND")
	)
	(via
		(at 194.40017 -59.500262)
		(size 0.508)
		(drill 0.254)
		(layers "F.Cu" "B.Cu")
		(net "GND")
	)
	(via
		(at 96.817942 -12.460732)
		(size 0.508)
		(drill 0.254)
		(layers "F.Cu" "B.Cu")
		(net "GND")
	)
	(via
		(at 190.400178 -69.900038)
		(size 0.508)
		(drill 0.254)
		(layers "F.Cu" "B.Cu")
		(net "GND")
	)
	(via
		(at 185.133996 -119.59844)
		(size 0.508)
		(drill 0.254)
		(layers "F.Cu" "B.Cu")
		(net "GND")
	)
	(via
		(at 146.45894 -130.407664)
		(size 0.7112)
		(drill 0.4064)
		(layers "F.Cu" "B.Cu")
		(net "GND")
	)
	(via
		(at 33.024826 -179.34813)
		(size 0.5588)
		(drill 0.3048)
		(layers "F.Cu" "B.Cu")
		(net "GND")
	)
	(via
		(at 83.9216 -162.5854)
		(size 0.7112)
		(drill 0.4064)
		(layers "F.Cu" "B.Cu")
		(net "GND")
	)
	(via
		(at 190.399924 -56.300116)
		(size 0.508)
		(drill 0.254)
		(layers "F.Cu" "B.Cu")
		(net "GND")
	)
	(via
		(at 146.45894 -103.737664)
		(size 0.7112)
		(drill 0.4064)
		(layers "F.Cu" "B.Cu")
		(net "GND")
	)
	(via
		(at 16.185134 -2.159)
		(size 0.7112)
		(drill 0.4064)
		(layers "F.Cu" "B.Cu")
		(net "GND")
	)
	(via
		(at 47.69993 -144.199864)
		(size 0.4572)
		(drill 0.2032)
		(layers "F.Cu" "B.Cu")
		(net "GND")
	)
	(via
		(at 2.159 -127.832866)
		(size 0.7112)
		(drill 0.4064)
		(layers "F.Cu" "B.Cu")
		(net "GND")
	)
	(via
		(at 146.45894 -108.817664)
		(size 0.7112)
		(drill 0.4064)
		(layers "F.Cu" "B.Cu")
		(net "GND")
	)
	(via
		(at 38.899846 -136.200134)
		(size 0.4572)
		(drill 0.2032)
		(layers "F.Cu" "B.Cu")
		(net "GND")
	)
	(via
		(at 4.5974 -188.341)
		(size 0.7112)
		(drill 0.4064)
		(layers "F.Cu" "B.Cu")
		(net "GND")
	)
	(via
		(at 146.45894 -181.207664)
		(size 0.7112)
		(drill 0.4064)
		(layers "F.Cu" "B.Cu")
		(net "GND")
	)
	(via
		(at 81.758028 -77.310996)
		(size 0.508)
		(drill 0.254)
		(layers "F.Cu" "B.Cu")
		(net "GND")
	)
	(via
		(at 172.0342 -79.9846)
		(size 0.508)
		(drill 0.254)
		(layers "F.Cu" "B.Cu")
		(net "GND")
	)
	(via
		(at 2.159 -54.172866)
		(size 0.7112)
		(drill 0.4064)
		(layers "F.Cu" "B.Cu")
		(net "GND")
	)
	(via
		(at 191.200024 -70.699884)
		(size 0.508)
		(drill 0.254)
		(layers "F.Cu" "B.Cu")
		(net "GND")
	)
	(via
		(at 140.34516 -16.39062)
		(size 0.508)
		(drill 0.254)
		(layers "F.Cu" "B.Cu")
		(net "GND")
	)
	(via
		(at 142.0368 -9.21131)
		(size 0.508)
		(drill 0.254)
		(layers "F.Cu" "B.Cu")
		(net "GND")
	)
	(via
		(at 96.813624 -13.745464)
		(size 0.508)
		(drill 0.254)
		(layers "F.Cu" "B.Cu")
		(net "GND")
	)
	(via
		(at 128.77038 -4.748022)
		(size 0.508)
		(drill 0.254)
		(layers "F.Cu" "B.Cu")
		(net "GND")
	)
	(via
		(at 86.736936 -28.023312)
		(size 0.508)
		(drill 0.254)
		(layers "F.Cu" "B.Cu")
		(net "GND")
	)
	(via
		(at 183.20004 -59.500008)
		(size 0.508)
		(drill 0.254)
		(layers "F.Cu" "B.Cu")
		(net "GND")
	)
	(via
		(at 2.159 -77.032866)
		(size 0.7112)
		(drill 0.4064)
		(layers "F.Cu" "B.Cu")
		(net "GND")
	)
	(via
		(at 184.799986 -70.699884)
		(size 0.508)
		(drill 0.254)
		(layers "F.Cu" "B.Cu")
		(net "GND")
	)
	(via
		(at 37.655246 -176.72431)
		(size 0.508)
		(drill 0.254)
		(layers "F.Cu" "B.Cu")
		(net "GND")
	)
	(via
		(at 199.999854 -54.699916)
		(size 0.508)
		(drill 0.254)
		(layers "F.Cu" "B.Cu")
		(net "GND")
	)
	(via
		(at 197.600316 -58.700162)
		(size 0.508)
		(drill 0.254)
		(layers "F.Cu" "B.Cu")
		(net "GND")
	)
	(via
		(at 211.55533 -2.159)
		(size 0.7112)
		(drill 0.4064)
		(layers "F.Cu" "B.Cu")
		(net "GND")
	)
	(via
		(at 2.159 -3.372866)
		(size 0.7112)
		(drill 0.4064)
		(layers "F.Cu" "B.Cu")
		(net "GND")
	)
	(via
		(at 35.2806 -133.603746)
		(size 0.508)
		(drill 0.254)
		(layers "F.Cu" "B.Cu")
		(net "GND")
	)
	(via
		(at 196.000116 -54.70017)
		(size 0.508)
		(drill 0.254)
		(layers "F.Cu" "B.Cu")
		(net "GND")
	)
	(via
		(at 2.159 -88.462866)
		(size 0.7112)
		(drill 0.4064)
		(layers "F.Cu" "B.Cu")
		(net "GND")
	)
	(via
		(at 200.791826 -69.101462)
		(size 0.508)
		(drill 0.254)
		(layers "F.Cu" "B.Cu")
		(net "GND")
	)
	(via
		(at 215.6587 -122.1867)
		(size 0.508)
		(drill 0.254)
		(layers "F.Cu" "B.Cu")
		(net "GND")
	)
	(via
		(at 23.996142 -138.961622)
		(size 0.508)
		(drill 0.254)
		(layers "F.Cu" "B.Cu")
		(net "GND")
	)
	(via
		(at 192.000124 -57.100216)
		(size 0.508)
		(drill 0.254)
		(layers "F.Cu" "B.Cu")
		(net "GND")
	)
	(via
		(at 25.781 -151.638)
		(size 0.508)
		(drill 0.254)
		(layers "F.Cu" "B.Cu")
		(net "GND")
	)
	(via
		(at 2.159 -110.052866)
		(size 0.7112)
		(drill 0.4064)
		(layers "F.Cu" "B.Cu")
		(net "GND")
	)
	(via
		(at 228.8032 -191.4398)
		(size 0.7112)
		(drill 0.4064)
		(layers "F.Cu" "B.Cu")
		(net "GND")
	)
	(via
		(at 166.37 -175.4124)
		(size 0.7112)
		(drill 0.4064)
		(layers "F.Cu" "B.Cu")
		(net "GND")
	)
	(via
		(at 28.498038 -50.903124)
		(size 0.7112)
		(drill 0.4064)
		(layers "F.Cu" "B.Cu")
		(net "GND")
	)
	(via
		(at 170.109388 -191.84112)
		(size 0.7112)
		(drill 0.4064)
		(layers "F.Cu" "B.Cu")
		(net "GND")
	)
	(via
		(at 163.9062 -171.2976)
		(size 0.7112)
		(drill 0.4064)
		(layers "F.Cu" "B.Cu")
		(net "GND")
	)
	(via
		(at 32.780478 -191.84112)
		(size 0.7112)
		(drill 0.4064)
		(layers "F.Cu" "B.Cu")
		(net "GND")
	)
	(via
		(at 227.259388 -191.84112)
		(size 0.7112)
		(drill 0.4064)
		(layers "F.Cu" "B.Cu")
		(net "GND")
	)
	(via
		(at 198.399908 -56.300116)
		(size 0.508)
		(drill 0.254)
		(layers "F.Cu" "B.Cu")
		(net "GND")
	)
	(via
		(at 51.699668 -138.600434)
		(size 0.4572)
		(drill 0.2032)
		(layers "F.Cu" "B.Cu")
		(net "GND")
	)
	(via
		(at 81.896204 -58.758074)
		(size 0.508)
		(drill 0.254)
		(layers "F.Cu" "B.Cu")
		(net "GND")
	)
	(via
		(at 62.484 -131.23418)
		(size 0.508)
		(drill 0.254)
		(layers "F.Cu" "B.Cu")
		(net "GND")
	)
	(via
		(at 2.159 -8.452866)
		(size 0.7112)
		(drill 0.4064)
		(layers "F.Cu" "B.Cu")
		(net "GND")
	)
	(via
		(at 232.841038 -154.863292)
		(size 0.7112)
		(drill 0.4064)
		(layers "F.Cu" "B.Cu")
		(net "GND")
	)
	(via
		(at 190.399924 -57.100216)
		(size 0.508)
		(drill 0.254)
		(layers "F.Cu" "B.Cu")
		(net "GND")
	)
	(via
		(at 94.4626 -122.313192)
		(size 0.508)
		(drill 0.254)
		(layers "F.Cu" "B.Cu")
		(net "GND")
	)
	(via
		(at 196.2658 -28.702)
		(size 0.508)
		(drill 0.254)
		(layers "F.Cu" "B.Cu")
		(net "GND")
	)
	(via
		(at 194.40017 -65.900046)
		(size 0.508)
		(drill 0.254)
		(layers "F.Cu" "B.Cu")
		(net "GND")
	)
	(via
		(at 19.995134 -2.159)
		(size 0.7112)
		(drill 0.4064)
		(layers "F.Cu" "B.Cu")
		(net "GND")
	)
	(via
		(at 203.197714 -63.492888)
		(size 0.508)
		(drill 0.254)
		(layers "F.Cu" "B.Cu")
		(net "GND")
	)
	(via
		(at 187.57011 -89.64549)
		(size 0.508)
		(drill 0.254)
		(layers "F.Cu" "B.Cu")
		(net "GND")
	)
	(via
		(at 201.600054 -58.700162)
		(size 0.508)
		(drill 0.254)
		(layers "F.Cu" "B.Cu")
		(net "GND")
	)
	(via
		(at 27.556968 -137.654538)
		(size 0.6096)
		(drill 0.3048)
		(layers "F.Cu" "B.Cu")
		(net "GND")
	)
	(via
		(at 85.1662 -154.8892)
		(size 0.7112)
		(drill 0.4064)
		(layers "F.Cu" "B.Cu")
		(net "GND")
	)
	(via
		(at 28.498038 -57.253124)
		(size 0.7112)
		(drill 0.4064)
		(layers "F.Cu" "B.Cu")
		(net "GND")
	)
	(via
		(at 232.841038 -143.433292)
		(size 0.7112)
		(drill 0.4064)
		(layers "F.Cu" "B.Cu")
		(net "GND")
	)
	(via
		(at 232.841038 -68.503292)
		(size 0.7112)
		(drill 0.4064)
		(layers "F.Cu" "B.Cu")
		(net "GND")
	)
	(via
		(at 69.610478 -191.84112)
		(size 0.7112)
		(drill 0.4064)
		(layers "F.Cu" "B.Cu")
		(net "GND")
	)
	(via
		(at 2.159 -33.852866)
		(size 0.7112)
		(drill 0.4064)
		(layers "F.Cu" "B.Cu")
		(net "GND")
	)
	(via
		(at 218.694 -104.267)
		(size 0.508)
		(drill 0.254)
		(layers "F.Cu" "B.Cu")
		(net "GND")
	)
	(via
		(at 195.199762 -73.099676)
		(size 0.508)
		(drill 0.254)
		(layers "F.Cu" "B.Cu")
		(net "GND")
	)
	(via
		(at 2.159 -132.912866)
		(size 0.7112)
		(drill 0.4064)
		(layers "F.Cu" "B.Cu")
		(net "GND")
	)
	(via
		(at 16.434054 -143.361664)
		(size 0.508)
		(drill 0.254)
		(layers "F.Cu" "B.Cu")
		(net "GND")
	)
	(via
		(at 94.43085 -50.946558)
		(size 0.508)
		(drill 0.254)
		(layers "F.Cu" "B.Cu")
		(net "GND")
	)
	(via
		(at 75.18908 -2.39268)
		(size 0.7112)
		(drill 0.4064)
		(layers "F.Cu" "B.Cu")
		(net "GND")
	)
	(via
		(at 232.841038 -87.553292)
		(size 0.7112)
		(drill 0.4064)
		(layers "F.Cu" "B.Cu")
		(net "GND")
	)
	(via
		(at 2.159 -144.342866)
		(size 0.7112)
		(drill 0.4064)
		(layers "F.Cu" "B.Cu")
		(net "GND")
	)
	(via
		(at 232.841038 -40.563292)
		(size 0.7112)
		(drill 0.4064)
		(layers "F.Cu" "B.Cu")
		(net "GND")
	)
	(via
		(at 203.192888 -66.697352)
		(size 0.508)
		(drill 0.254)
		(layers "F.Cu" "B.Cu")
		(net "GND")
	)
	(via
		(at 170.2816 -142.4178)
		(size 0.7112)
		(drill 0.4064)
		(layers "F.Cu" "B.Cu")
		(net "GND")
	)
	(via
		(at 198.400162 -58.700162)
		(size 0.508)
		(drill 0.254)
		(layers "F.Cu" "B.Cu")
		(net "GND")
	)
	(via
		(at 232.841038 -58.343292)
		(size 0.7112)
		(drill 0.4064)
		(layers "F.Cu" "B.Cu")
		(net "GND")
	)
	(via
		(at 232.841038 -93.903292)
		(size 0.7112)
		(drill 0.4064)
		(layers "F.Cu" "B.Cu")
		(net "GND")
	)
	(via
		(at 28.498038 -106.783124)
		(size 0.7112)
		(drill 0.4064)
		(layers "F.Cu" "B.Cu")
		(net "GND")
	)
	(via
		(at 28.498038 -38.203124)
		(size 0.7112)
		(drill 0.4064)
		(layers "F.Cu" "B.Cu")
		(net "GND")
	)
	(via
		(at 212.019388 -191.84112)
		(size 0.7112)
		(drill 0.4064)
		(layers "F.Cu" "B.Cu")
		(net "GND")
	)
	(via
		(at 147.883626 -98.199448)
		(size 0.508)
		(drill 0.254)
		(layers "F.Cu" "B.Cu")
		(net "GND")
	)
	(via
		(at 220.44533 -2.159)
		(size 0.7112)
		(drill 0.4064)
		(layers "F.Cu" "B.Cu")
		(net "GND")
	)
	(via
		(at 85.0011 -175.1838)
		(size 0.7112)
		(drill 0.4064)
		(layers "F.Cu" "B.Cu")
		(net "GND")
	)
	(via
		(at 193.596006 -71.504556)
		(size 0.508)
		(drill 0.254)
		(layers "F.Cu" "B.Cu")
		(net "GND")
	)
	(via
		(at 2.159 -122.752866)
		(size 0.7112)
		(drill 0.4064)
		(layers "F.Cu" "B.Cu")
		(net "GND")
	)
	(via
		(at 146.45894 -173.587664)
		(size 0.7112)
		(drill 0.4064)
		(layers "F.Cu" "B.Cu")
		(net "GND")
	)
	(via
		(at 2.159 -120.212866)
		(size 0.7112)
		(drill 0.4064)
		(layers "F.Cu" "B.Cu")
		(net "GND")
	)
	(via
		(at 188.906404 -122.888502)
		(size 0.508)
		(drill 0.254)
		(layers "F.Cu" "B.Cu")
		(net "GND")
	)
	(via
		(at 16.326358 -127.552958)
		(size 0.508)
		(drill 0.254)
		(layers "F.Cu" "B.Cu")
		(net "GND")
	)
	(via
		(at 186.399932 -67.499738)
		(size 0.508)
		(drill 0.254)
		(layers "F.Cu" "B.Cu")
		(net "GND")
	)
	(via
		(at 146.45894 -167.237664)
		(size 0.7112)
		(drill 0.4064)
		(layers "F.Cu" "B.Cu")
		(net "GND")
	)
	(via
		(at 2.159 -84.652866)
		(size 0.7112)
		(drill 0.4064)
		(layers "F.Cu" "B.Cu")
		(net "GND")
	)
	(via
		(at 22.834854 -149.216364)
		(size 0.508)
		(drill 0.254)
		(layers "F.Cu" "B.Cu")
		(net "GND")
	)
	(via
		(at 232.841038 -111.683292)
		(size 0.7112)
		(drill 0.4064)
		(layers "F.Cu" "B.Cu")
		(net "GND")
	)
	(via
		(at 186.812936 -116.377212)
		(size 0.7112)
		(drill 0.4064)
		(layers "F.Cu" "B.Cu")
		(net "GND")
	)
	(via
		(at 81.040478 -191.84112)
		(size 0.7112)
		(drill 0.4064)
		(layers "F.Cu" "B.Cu")
		(net "GND")
	)
	(via
		(at 232.841038 -73.583292)
		(size 0.7112)
		(drill 0.4064)
		(layers "F.Cu" "B.Cu")
		(net "GND")
	)
	(via
		(at 193.606166 -73.896982)
		(size 0.508)
		(drill 0.254)
		(layers "F.Cu" "B.Cu")
		(net "GND")
	)
	(via
		(at 21.49094 -16.37538)
		(size 0.508)
		(drill 0.254)
		(layers "F.Cu" "B.Cu")
		(net "GND")
	)
	(via
		(at 232.841038 -106.603292)
		(size 0.7112)
		(drill 0.4064)
		(layers "F.Cu" "B.Cu")
		(net "GND")
	)
	(via
		(at 2.159 -96.082866)
		(size 0.7112)
		(drill 0.4064)
		(layers "F.Cu" "B.Cu")
		(net "GND")
	)
	(via
		(at 179.9082 -113.2332)
		(size 0.508)
		(drill 0.254)
		(layers "F.Cu" "B.Cu")
		(net "GND")
	)
	(via
		(at 2.159 -148.152866)
		(size 0.7112)
		(drill 0.4064)
		(layers "F.Cu" "B.Cu")
		(net "GND")
	)
	(via
		(at 97.831402 -162.903916)
		(size 0.508)
		(drill 0.254)
		(layers "F.Cu" "B.Cu")
		(net "GND")
	)
	(via
		(at 28.97378 -122.414792)
		(size 0.508)
		(drill 0.254)
		(layers "F.Cu" "B.Cu")
		(net "GND")
	)
	(via
		(at 197.600316 -60.300108)
		(size 0.508)
		(drill 0.254)
		(layers "F.Cu" "B.Cu")
		(net "GND")
	)
	(via
		(at 17.540478 -191.84112)
		(size 0.7112)
		(drill 0.4064)
		(layers "F.Cu" "B.Cu")
		(net "GND")
	)
	(via
		(at 70.880478 -191.84112)
		(size 0.7112)
		(drill 0.4064)
		(layers "F.Cu" "B.Cu")
		(net "GND")
	)
	(via
		(at 183.4261 -46.8757)
		(size 0.508)
		(drill 0.254)
		(layers "F.Cu" "B.Cu")
		(net "GND")
	)
	(via
		(at 16.6878 -167.8686)
		(size 0.5588)
		(drill 0.3048)
		(layers "F.Cu" "B.Cu")
		(net "GND")
	)
	(via
		(at 28.498038 -95.353124)
		(size 0.7112)
		(drill 0.4064)
		(layers "F.Cu" "B.Cu")
		(net "GND")
	)
	(via
		(at 183.4261 -44.2722)
		(size 0.508)
		(drill 0.254)
		(layers "F.Cu" "B.Cu")
		(net "GND")
	)
	(via
		(at 2.159 -172.282866)
		(size 0.7112)
		(drill 0.4064)
		(layers "F.Cu" "B.Cu")
		(net "GND")
	)
	(via
		(at 232.841038 -159.943292)
		(size 0.7112)
		(drill 0.4064)
		(layers "F.Cu" "B.Cu")
		(net "GND")
	)
	(via
		(at 64.530478 -191.84112)
		(size 0.7112)
		(drill 0.4064)
		(layers "F.Cu" "B.Cu")
		(net "GND")
	)
	(via
		(at 232.841038 -145.973292)
		(size 0.7112)
		(drill 0.4064)
		(layers "F.Cu" "B.Cu")
		(net "GND")
	)
	(via
		(at 232.841038 -43.103292)
		(size 0.7112)
		(drill 0.4064)
		(layers "F.Cu" "B.Cu")
		(net "GND")
	)
	(via
		(at 86.435438 -29.857192)
		(size 0.508)
		(drill 0.254)
		(layers "F.Cu" "B.Cu")
		(net "GND")
	)
	(via
		(at 7.1374 -191.9224)
		(size 0.7112)
		(drill 0.4064)
		(layers "F.Cu" "B.Cu")
		(net "GND")
	)
	(via
		(at 200.000108 -56.300116)
		(size 0.508)
		(drill 0.254)
		(layers "F.Cu" "B.Cu")
		(net "GND")
	)
	(via
		(at 192.800224 -61.100208)
		(size 0.508)
		(drill 0.254)
		(layers "F.Cu" "B.Cu")
		(net "GND")
	)
	(via
		(at 2.159 -174.822866)
		(size 0.7112)
		(drill 0.4064)
		(layers "F.Cu" "B.Cu")
		(net "GND")
	)
	(via
		(at 203.054204 -95.111824)
		(size 0.508)
		(drill 0.254)
		(layers "F.Cu" "B.Cu")
		(net "GND")
	)
	(via
		(at 196.000116 -53.100224)
		(size 0.508)
		(drill 0.254)
		(layers "F.Cu" "B.Cu")
		(net "GND")
	)
	(via
		(at 91.251532 -151.59228)
		(size 0.508)
		(drill 0.254)
		(layers "F.Cu" "B.Cu")
		(net "GND")
	)
	(via
		(at 5.1562 -189.5348)
		(size 0.7112)
		(drill 0.4064)
		(layers "F.Cu" "B.Cu")
		(net "GND")
	)
	(via
		(at 2.159 -21.152866)
		(size 0.7112)
		(drill 0.4064)
		(layers "F.Cu" "B.Cu")
		(net "GND")
	)
	(via
		(at 212.0646 -127.381)
		(size 0.7112)
		(drill 0.4064)
		(layers "F.Cu" "B.Cu")
		(net "GND")
	)
	(via
		(at 28.498038 -62.333124)
		(size 0.7112)
		(drill 0.4064)
		(layers "F.Cu" "B.Cu")
		(net "GND")
	)
	(via
		(at 34.04362 -157.67304)
		(size 0.508)
		(drill 0.254)
		(layers "F.Cu" "B.Cu")
		(net "GND")
	)
	(via
		(at 197.600062 -69.900292)
		(size 0.508)
		(drill 0.254)
		(layers "F.Cu" "B.Cu")
		(net "GND")
	)
	(via
		(at 2.159 -134.182866)
		(size 0.7112)
		(drill 0.4064)
		(layers "F.Cu" "B.Cu")
		(net "GND")
	)
	(via
		(at 232.841038 -118.033292)
		(size 0.7112)
		(drill 0.4064)
		(layers "F.Cu" "B.Cu")
		(net "GND")
	)
	(via
		(at 203.765658 -52.939696)
		(size 0.508)
		(drill 0.254)
		(layers "F.Cu" "B.Cu")
		(net "GND")
	)
	(via
		(at 190.399924 -57.900316)
		(size 0.508)
		(drill 0.254)
		(layers "F.Cu" "B.Cu")
		(net "GND")
	)
	(via
		(at 2.159 -162.122866)
		(size 0.7112)
		(drill 0.4064)
		(layers "F.Cu" "B.Cu")
		(net "GND")
	)
	(via
		(at 232.841038 -11.353292)
		(size 0.7112)
		(drill 0.4064)
		(layers "F.Cu" "B.Cu")
		(net "GND")
	)
	(via
		(at 28.498038 -89.003124)
		(size 0.7112)
		(drill 0.4064)
		(layers "F.Cu" "B.Cu")
		(net "GND")
	)
	(via
		(at 95.210376 -19.4818)
		(size 0.508)
		(drill 0.254)
		(layers "F.Cu" "B.Cu")
		(net "GND")
	)
	(via
		(at 21.6916 -169.4434)
		(size 0.7112)
		(drill 0.4064)
		(layers "F.Cu" "B.Cu")
		(net "GND")
	)
	(via
		(at 95.3008 -16.1036)
		(size 0.508)
		(drill 0.254)
		(layers "F.Cu" "B.Cu")
		(net "GND")
	)
	(via
		(at 51.5112 -167.8686)
		(size 0.508)
		(drill 0.254)
		(layers "F.Cu" "B.Cu")
		(net "GND")
	)
	(via
		(at 184.799986 -56.300116)
		(size 0.508)
		(drill 0.254)
		(layers "F.Cu" "B.Cu")
		(net "GND")
	)
	(via
		(at 232.841038 -140.893292)
		(size 0.7112)
		(drill 0.4064)
		(layers "F.Cu" "B.Cu")
		(net "GND")
	)
	(via
		(at 202.392788 -65.097406)
		(size 0.508)
		(drill 0.254)
		(layers "F.Cu" "B.Cu")
		(net "GND")
	)
	(via
		(at 53.100478 -191.84112)
		(size 0.7112)
		(drill 0.4064)
		(layers "F.Cu" "B.Cu")
		(net "GND")
	)
	(via
		(at 232.841038 -163.753292)
		(size 0.7112)
		(drill 0.4064)
		(layers "F.Cu" "B.Cu")
		(net "GND")
	)
	(via
		(at 187.200032 -65.099946)
		(size 0.508)
		(drill 0.254)
		(layers "F.Cu" "B.Cu")
		(net "GND")
	)
	(via
		(at 34.79546 -135.94969)
		(size 0.508)
		(drill 0.254)
		(layers "F.Cu" "B.Cu")
		(net "GND")
	)
	(via
		(at 200.7997 -73.09993)
		(size 0.508)
		(drill 0.254)
		(layers "F.Cu" "B.Cu")
		(net "GND")
	)
	(via
		(at 81.781904 -128.4605)
		(size 0.508)
		(drill 0.254)
		(layers "F.Cu" "B.Cu")
		(net "GND")
	)
	(via
		(at 208.5467 -135.4709)
		(size 0.508)
		(drill 0.254)
		(layers "F.Cu" "B.Cu")
		(net "GND")
	)
	(via
		(at 2.159 -160.852866)
		(size 0.7112)
		(drill 0.4064)
		(layers "F.Cu" "B.Cu")
		(net "GND")
	)
	(via
		(at 179.018184 -146.710146)
		(size 0.5588)
		(drill 0.3048)
		(layers "F.Cu" "B.Cu")
		(net "GND")
	)
	(via
		(at 22.9108 -169.4434)
		(size 0.7112)
		(drill 0.4064)
		(layers "F.Cu" "B.Cu")
		(net "GND")
	)
	(via
		(at 157.3276 -144.894554)
		(size 0.508)
		(drill 0.254)
		(layers "F.Cu" "B.Cu")
		(net "GND")
	)
	(via
		(at 200.589388 -191.84112)
		(size 0.7112)
		(drill 0.4064)
		(layers "F.Cu" "B.Cu")
		(net "GND")
	)
	(via
		(at 177.417984 -145.440146)
		(size 0.5588)
		(drill 0.3048)
		(layers "F.Cu" "B.Cu")
		(net "GND")
	)
	(via
		(at 28.498038 -30.583124)
		(size 0.7112)
		(drill 0.4064)
		(layers "F.Cu" "B.Cu")
		(net "GND")
	)
	(via
		(at 146.45894 -171.047664)
		(size 0.7112)
		(drill 0.4064)
		(layers "F.Cu" "B.Cu")
		(net "GND")
	)
	(via
		(at 176.9364 -61.341)
		(size 0.508)
		(drill 0.254)
		(layers "F.Cu" "B.Cu")
		(net "GND")
	)
	(via
		(at 53.721 -134.4676)
		(size 0.508)
		(drill 0.254)
		(layers "F.Cu" "B.Cu")
		(net "GND")
	)
	(via
		(at 2.159 -51.632866)
		(size 0.7112)
		(drill 0.4064)
		(layers "F.Cu" "B.Cu")
		(net "GND")
	)
	(via
		(at 70.9676 -174.3456)
		(size 0.508)
		(drill 0.254)
		(layers "F.Cu" "B.Cu")
		(net "GND")
	)
	(via
		(at 100.013262 -186.545728)
		(size 0.7112)
		(drill 0.4064)
		(layers "F.Cu" "B.Cu")
		(net "GND")
	)
	(via
		(at 2.159 -140.532866)
		(size 0.7112)
		(drill 0.4064)
		(layers "F.Cu" "B.Cu")
		(net "GND")
	)
	(via
		(at 201.8538 -128.3208)
		(size 0.508)
		(drill 0.254)
		(layers "F.Cu" "B.Cu")
		(net "GND")
	)
	(via
		(at 75.3872 -168.930574)
		(size 0.508)
		(drill 0.254)
		(layers "F.Cu" "B.Cu")
		(net "GND")
	)
	(via
		(at 51.639978 -128.6256)
		(size 0.508)
		(drill 0.254)
		(layers "F.Cu" "B.Cu")
		(net "GND")
	)
	(via
		(at 191.200024 -59.500262)
		(size 0.508)
		(drill 0.254)
		(layers "F.Cu" "B.Cu")
		(net "GND")
	)
	(via
		(at 161.26714 -43.01744)
		(size 0.508)
		(drill 0.254)
		(layers "F.Cu" "B.Cu")
		(net "GND")
	)
	(via
		(at 24.873204 -127.5842)
		(size 0.508)
		(drill 0.254)
		(layers "F.Cu" "B.Cu")
		(net "GND")
	)
	(via
		(at 187.993528 -61.102748)
		(size 0.508)
		(drill 0.254)
		(layers "F.Cu" "B.Cu")
		(net "GND")
	)
	(via
		(at 182.0291 -46.8757)
		(size 0.508)
		(drill 0.254)
		(layers "F.Cu" "B.Cu")
		(net "GND")
	)
	(via
		(at 2.159 -30.042866)
		(size 0.7112)
		(drill 0.4064)
		(layers "F.Cu" "B.Cu")
		(net "GND")
	)
	(via
		(at 27.700478 -191.84112)
		(size 0.7112)
		(drill 0.4064)
		(layers "F.Cu" "B.Cu")
		(net "GND")
	)
	(via
		(at 173.630082 -123.403614)
		(size 0.508)
		(drill 0.254)
		(layers "F.Cu" "B.Cu")
		(net "GND")
	)
	(via
		(at 198.400162 -60.300108)
		(size 0.508)
		(drill 0.254)
		(layers "F.Cu" "B.Cu")
		(net "GND")
	)
	(via
		(at 99.3521 -155.810966)
		(size 0.508)
		(drill 0.254)
		(layers "F.Cu" "B.Cu")
		(net "GND")
	)
	(via
		(at 232.841038 -139.623292)
		(size 0.7112)
		(drill 0.4064)
		(layers "F.Cu" "B.Cu")
		(net "GND")
	)
	(via
		(at 196.779388 -191.84112)
		(size 0.7112)
		(drill 0.4064)
		(layers "F.Cu" "B.Cu")
		(net "GND")
	)
	(via
		(at 11.05154 -14.68374)
		(size 0.508)
		(drill 0.254)
		(layers "F.Cu" "B.Cu")
		(net "GND")
	)
	(via
		(at 173.0248 -79.9846)
		(size 0.508)
		(drill 0.254)
		(layers "F.Cu" "B.Cu")
		(net "GND")
	)
	(via
		(at 35.320478 -191.84112)
		(size 0.7112)
		(drill 0.4064)
		(layers "F.Cu" "B.Cu")
		(net "GND")
	)
	(via
		(at 66.5226 -150.1902)
		(size 0.508)
		(drill 0.254)
		(layers "F.Cu" "B.Cu")
		(net "GND")
	)
	(via
		(at 232.841038 -10.083292)
		(size 0.7112)
		(drill 0.4064)
		(layers "F.Cu" "B.Cu")
		(net "GND")
	)
	(via
		(at 170.2816 -139.9794)
		(size 0.7112)
		(drill 0.4064)
		(layers "F.Cu" "B.Cu")
		(net "GND")
	)
	(via
		(at 39.699946 -148.999956)
		(size 0.4572)
		(drill 0.2032)
		(layers "F.Cu" "B.Cu")
		(net "GND")
	)
	(via
		(at 28.498038 -25.503124)
		(size 0.7112)
		(drill 0.4064)
		(layers "F.Cu" "B.Cu")
		(net "GND")
	)
	(via
		(at 232.841038 -123.113292)
		(size 0.7112)
		(drill 0.4064)
		(layers "F.Cu" "B.Cu")
		(net "GND")
	)
	(via
		(at 75.091036 -180.35778)
		(size 0.5588)
		(drill 0.3048)
		(layers "F.Cu" "B.Cu")
		(net "GND")
	)
	(via
		(at 232.841038 -31.673292)
		(size 0.7112)
		(drill 0.4064)
		(layers "F.Cu" "B.Cu")
		(net "GND")
	)
	(via
		(at 19.75612 -15.69466)
		(size 0.508)
		(drill 0.254)
		(layers "F.Cu" "B.Cu")
		(net "GND")
	)
	(via
		(at 165.029388 -191.84112)
		(size 0.7112)
		(drill 0.4064)
		(layers "F.Cu" "B.Cu")
		(net "GND")
	)
	(via
		(at 75.18908 -3.66268)
		(size 0.7112)
		(drill 0.4064)
		(layers "F.Cu" "B.Cu")
		(net "GND")
	)
	(via
		(at 232.841038 -30.403292)
		(size 0.7112)
		(drill 0.4064)
		(layers "F.Cu" "B.Cu")
		(net "GND")
	)
	(via
		(at 206.939388 -191.84112)
		(size 0.7112)
		(drill 0.4064)
		(layers "F.Cu" "B.Cu")
		(net "GND")
	)
	(via
		(at 188.024262 -122.908822)
		(size 0.508)
		(drill 0.254)
		(layers "F.Cu" "B.Cu")
		(net "GND")
	)
	(via
		(at 183.20004 -69.899784)
		(size 0.508)
		(drill 0.254)
		(layers "F.Cu" "B.Cu")
		(net "GND")
	)
	(via
		(at 87.756238 -134.021576)
		(size 0.508)
		(drill 0.254)
		(layers "F.Cu" "B.Cu")
		(net "GND")
	)
	(via
		(at 188.799724 -73.899776)
		(size 0.508)
		(drill 0.254)
		(layers "F.Cu" "B.Cu")
		(net "GND")
	)
	(via
		(at 35.538664 -182.021988)
		(size 0.5588)
		(drill 0.3048)
		(layers "F.Cu" "B.Cu")
		(net "GND")
	)
	(via
		(at 91.195144 -161.5186)
		(size 0.508)
		(drill 0.254)
		(layers "F.Cu" "B.Cu")
		(net "GND")
	)
	(via
		(at 39.130478 -191.84112)
		(size 0.7112)
		(drill 0.4064)
		(layers "F.Cu" "B.Cu")
		(net "GND")
	)
	(via
		(at 26.289 -165.23589)
		(size 0.7112)
		(drill 0.4064)
		(layers "F.Cu" "B.Cu")
		(net "GND")
	)
	(via
		(at 35.538664 -181.107588)
		(size 0.5588)
		(drill 0.3048)
		(layers "F.Cu" "B.Cu")
		(net "GND")
	)
	(via
		(at 202.692 -116.6622)
		(size 0.7112)
		(drill 0.4064)
		(layers "F.Cu" "B.Cu")
		(net "GND")
	)
	(via
		(at 222.180658 -101.208332)
		(size 0.7112)
		(drill 0.4064)
		(layers "F.Cu" "B.Cu")
		(net "GND")
	)
	(via
		(at 217.90533 -2.159)
		(size 0.7112)
		(drill 0.4064)
		(layers "F.Cu" "B.Cu")
		(net "GND")
	)
	(via
		(at 2.159 -151.962866)
		(size 0.7112)
		(drill 0.4064)
		(layers "F.Cu" "B.Cu")
		(net "GND")
	)
	(via
		(at 189.600078 -58.700162)
		(size 0.508)
		(drill 0.254)
		(layers "F.Cu" "B.Cu")
		(net "GND")
	)
	(via
		(at 232.841038 -35.483292)
		(size 0.7112)
		(drill 0.4064)
		(layers "F.Cu" "B.Cu")
		(net "GND")
	)
	(via
		(at 232.841038 -151.053292)
		(size 0.7112)
		(drill 0.4064)
		(layers "F.Cu" "B.Cu")
		(net "GND")
	)
	(via
		(at 76.38288 -179.04968)
		(size 0.5588)
		(drill 0.3048)
		(layers "F.Cu" "B.Cu")
		(net "GND")
	)
	(via
		(at 47.69993 -145.800064)
		(size 0.4572)
		(drill 0.2032)
		(layers "F.Cu" "B.Cu")
		(net "GND")
	)
	(via
		(at 194.399916 -58.699908)
		(size 0.508)
		(drill 0.254)
		(layers "F.Cu" "B.Cu")
		(net "GND")
	)
	(via
		(at 232.841038 -147.243292)
		(size 0.7112)
		(drill 0.4064)
		(layers "F.Cu" "B.Cu")
		(net "GND")
	)
	(via
		(at 2.159 -176.092866)
		(size 0.7112)
		(drill 0.4064)
		(layers "F.Cu" "B.Cu")
		(net "GND")
	)
	(via
		(at 146.45894 -117.707664)
		(size 0.7112)
		(drill 0.4064)
		(layers "F.Cu" "B.Cu")
		(net "GND")
	)
	(via
		(at 232.841038 -128.193292)
		(size 0.7112)
		(drill 0.4064)
		(layers "F.Cu" "B.Cu")
		(net "GND")
	)
	(via
		(at 88.664288 -49.167796)
		(size 0.508)
		(drill 0.254)
		(layers "F.Cu" "B.Cu")
		(net "GND")
	)
	(via
		(at 2.159 -112.592866)
		(size 0.7112)
		(drill 0.4064)
		(layers "F.Cu" "B.Cu")
		(net "GND")
	)
	(via
		(at 201.592688 -61.902086)
		(size 0.508)
		(drill 0.254)
		(layers "F.Cu" "B.Cu")
		(net "GND")
	)
	(via
		(at 2.159 -70.682866)
		(size 0.7112)
		(drill 0.4064)
		(layers "F.Cu" "B.Cu")
		(net "GND")
	)
	(via
		(at 42.940478 -191.84112)
		(size 0.7112)
		(drill 0.4064)
		(layers "F.Cu" "B.Cu")
		(net "GND")
	)
	(via
		(at 188.000132 -62.699646)
		(size 0.508)
		(drill 0.254)
		(layers "F.Cu" "B.Cu")
		(net "GND")
	)
	(via
		(at 186.399932 -68.299838)
		(size 0.508)
		(drill 0.254)
		(layers "F.Cu" "B.Cu")
		(net "GND")
	)
	(via
		(at 194.40017 -67.500246)
		(size 0.508)
		(drill 0.254)
		(layers "F.Cu" "B.Cu")
		(net "GND")
	)
	(via
		(at 209.1055 -81.1149)
		(size 0.508)
		(drill 0.254)
		(layers "F.Cu" "B.Cu")
		(net "GND")
	)
	(via
		(at 176.503584 -145.440146)
		(size 0.5588)
		(drill 0.3048)
		(layers "F.Cu" "B.Cu")
		(net "GND")
	)
	(via
		(at 196.000116 -53.90007)
		(size 0.508)
		(drill 0.254)
		(layers "F.Cu" "B.Cu")
		(net "GND")
	)
	(via
		(at 146.45894 -124.057664)
		(size 0.7112)
		(drill 0.4064)
		(layers "F.Cu" "B.Cu")
		(net "GND")
	)
	(via
		(at 26.9494 -189.1792)
		(size 0.7112)
		(drill 0.4064)
		(layers "F.Cu" "B.Cu")
		(net "GND")
	)
	(via
		(at 64.158622 -139.1031)
		(size 0.508)
		(drill 0.254)
		(layers "F.Cu" "B.Cu")
		(net "GND")
	)
	(via
		(at 146.45894 -148.187664)
		(size 0.7112)
		(drill 0.4064)
		(layers "F.Cu" "B.Cu")
		(net "GND")
	)
	(via
		(at 232.841038 -162.483292)
		(size 0.7112)
		(drill 0.4064)
		(layers "F.Cu" "B.Cu")
		(net "GND")
	)
	(via
		(at 58.3692 -150.6728)
		(size 0.508)
		(drill 0.254)
		(layers "F.Cu" "B.Cu")
		(net "GND")
	)
	(via
		(at 186.812936 -115.158012)
		(size 0.7112)
		(drill 0.4064)
		(layers "F.Cu" "B.Cu")
		(net "GND")
	)
	(via
		(at 86.321138 -157.551374)
		(size 0.508)
		(drill 0.254)
		(layers "F.Cu" "B.Cu")
		(net "GND")
	)
	(via
		(at 232.841038 -44.373292)
		(size 0.7112)
		(drill 0.4064)
		(layers "F.Cu" "B.Cu")
		(net "GND")
	)
	(via
		(at 191.19088 -64.299846)
		(size 0.508)
		(drill 0.254)
		(layers "F.Cu" "B.Cu")
		(net "GND")
	)
	(via
		(at 30.3276 -129.921)
		(size 0.508)
		(drill 0.254)
		(layers "F.Cu" "B.Cu")
		(net "GND")
	)
	(via
		(at 68.6816 -158.20898)
		(size 0.508)
		(drill 0.254)
		(layers "F.Cu" "B.Cu")
		(net "GND")
	)
	(via
		(at 230.521256 -187.895738)
		(size 0.7112)
		(drill 0.4064)
		(layers "F.Cu" "B.Cu")
		(net "GND")
	)
	(via
		(at 82.310478 -191.84112)
		(size 0.7112)
		(drill 0.4064)
		(layers "F.Cu" "B.Cu")
		(net "GND")
	)
	(via
		(at 205.466442 -62.478666)
		(size 0.508)
		(drill 0.254)
		(layers "F.Cu" "B.Cu")
		(net "GND")
	)
	(via
		(at 232.841038 -175.183292)
		(size 0.7112)
		(drill 0.4064)
		(layers "F.Cu" "B.Cu")
		(net "GND")
	)
	(via
		(at 232.841038 -165.023292)
		(size 0.7112)
		(drill 0.4064)
		(layers "F.Cu" "B.Cu")
		(net "GND")
	)
	(via
		(at 161.219388 -191.84112)
		(size 0.7112)
		(drill 0.4064)
		(layers "F.Cu" "B.Cu")
		(net "GND")
	)
	(via
		(at 195.196206 -71.494396)
		(size 0.508)
		(drill 0.254)
		(layers "F.Cu" "B.Cu")
		(net "GND")
	)
	(via
		(at 70.750684 -160.8963)
		(size 0.508)
		(drill 0.254)
		(layers "F.Cu" "B.Cu")
		(net "GND")
	)
	(via
		(at 152.781 -92.3544)
		(size 0.5588)
		(drill 0.3048)
		(layers "F.Cu" "B.Cu")
		(net "GND")
	)
	(via
		(at 203.199746 -70.69963)
		(size 0.508)
		(drill 0.254)
		(layers "F.Cu" "B.Cu")
		(net "GND")
	)
	(via
		(at 25.7302 -189.1792)
		(size 0.7112)
		(drill 0.4064)
		(layers "F.Cu" "B.Cu")
		(net "GND")
	)
	(via
		(at 146.45894 -150.727664)
		(size 0.7112)
		(drill 0.4064)
		(layers "F.Cu" "B.Cu")
		(net "GND")
	)
	(via
		(at 184.079388 -191.84112)
		(size 0.7112)
		(drill 0.4064)
		(layers "F.Cu" "B.Cu")
		(net "GND")
	)
	(via
		(at 232.841038 -41.833292)
		(size 0.7112)
		(drill 0.4064)
		(layers "F.Cu" "B.Cu")
		(net "GND")
	)
	(via
		(at 172.649388 -191.84112)
		(size 0.7112)
		(drill 0.4064)
		(layers "F.Cu" "B.Cu")
		(net "GND")
	)
	(via
		(at 47.69993 -146.59991)
		(size 0.4572)
		(drill 0.2032)
		(layers "F.Cu" "B.Cu")
		(net "GND")
	)
	(via
		(at 204.969872 -64.379856)
		(size 0.508)
		(drill 0.254)
		(layers "F.Cu" "B.Cu")
		(net "GND")
	)
	(via
		(at 77.567028 -57.778396)
		(size 0.508)
		(drill 0.254)
		(layers "F.Cu" "B.Cu")
		(net "GND")
	)
	(via
		(at 2.159 -165.932866)
		(size 0.7112)
		(drill 0.4064)
		(layers "F.Cu" "B.Cu")
		(net "GND")
	)
	(via
		(at 76.35748 -181.66588)
		(size 0.5588)
		(drill 0.3048)
		(layers "F.Cu" "B.Cu")
		(net "GND")
	)
	(via
		(at 72.5932 -139.546076)
		(size 0.508)
		(drill 0.254)
		(layers "F.Cu" "B.Cu")
		(net "GND")
	)
	(via
		(at 26.3144 -162.0012)
		(size 0.7112)
		(drill 0.4064)
		(layers "F.Cu" "B.Cu")
		(net "GND")
	)
	(via
		(at 43.40098 -125.03658)
		(size 0.508)
		(drill 0.254)
		(layers "F.Cu" "B.Cu")
		(net "GND")
	)
	(via
		(at 194.239388 -191.84112)
		(size 0.7112)
		(drill 0.4064)
		(layers "F.Cu" "B.Cu")
		(net "GND")
	)
	(via
		(at 192.800224 -62.700154)
		(size 0.508)
		(drill 0.254)
		(layers "F.Cu" "B.Cu")
		(net "GND")
	)
	(via
		(at 75.83678 -188.89218)
		(size 0.508)
		(drill 0.254)
		(layers "F.Cu" "B.Cu")
		(net "GND")
	)
	(via
		(at 56.5404 -127.889)
		(size 0.508)
		(drill 0.254)
		(layers "F.Cu" "B.Cu")
		(net "GND")
	)
	(via
		(at 40.400478 -191.84112)
		(size 0.7112)
		(drill 0.4064)
		(layers "F.Cu" "B.Cu")
		(net "GND")
	)
	(via
		(at 163.9062 -163.9824)
		(size 0.7112)
		(drill 0.4064)
		(layers "F.Cu" "B.Cu")
		(net "GND")
	)
	(via
		(at 2.159 -130.372866)
		(size 0.7112)
		(drill 0.4064)
		(layers "F.Cu" "B.Cu")
		(net "GND")
	)
	(via
		(at 146.45894 -155.807664)
		(size 0.7112)
		(drill 0.4064)
		(layers "F.Cu" "B.Cu")
		(net "GND")
	)
	(via
		(at 2.159 -35.122866)
		(size 0.7112)
		(drill 0.4064)
		(layers "F.Cu" "B.Cu")
		(net "GND")
	)
	(via
		(at 2.159 -157.042866)
		(size 0.7112)
		(drill 0.4064)
		(layers "F.Cu" "B.Cu")
		(net "GND")
	)
	(via
		(at 232.841038 -129.463292)
		(size 0.7112)
		(drill 0.4064)
		(layers "F.Cu" "B.Cu")
		(net "GND")
	)
	(via
		(at 187.200032 -56.300116)
		(size 0.508)
		(drill 0.254)
		(layers "F.Cu" "B.Cu")
		(net "GND")
	)
	(via
		(at 7.59206 -13.73378)
		(size 0.508)
		(drill 0.254)
		(layers "F.Cu" "B.Cu")
		(net "GND")
	)
	(via
		(at 199.206358 -62.703202)
		(size 0.508)
		(drill 0.254)
		(layers "F.Cu" "B.Cu")
		(net "GND")
	)
	(via
		(at 34.050478 -191.84112)
		(size 0.7112)
		(drill 0.4064)
		(layers "F.Cu" "B.Cu")
		(net "GND")
	)
	(via
		(at 178.332384 -145.440146)
		(size 0.5588)
		(drill 0.3048)
		(layers "F.Cu" "B.Cu")
		(net "GND")
	)
	(via
		(at 205.794356 -126.9619)
		(size 0.5588)
		(drill 0.3048)
		(layers "F.Cu" "B.Cu")
		(net "GND")
	)
	(via
		(at 81.605374 -67.687444)
		(size 0.508)
		(drill 0.254)
		(layers "F.Cu" "B.Cu")
		(net "GND")
	)
	(via
		(at 25.7556 -154.0002)
		(size 0.508)
		(drill 0.254)
		(layers "F.Cu" "B.Cu")
		(net "GND")
	)
	(via
		(at 214.09533 -2.159)
		(size 0.7112)
		(drill 0.4064)
		(layers "F.Cu" "B.Cu")
		(net "GND")
	)
	(via
		(at 167.132 -105.156)
		(size 0.7112)
		(drill 0.4064)
		(layers "F.Cu" "B.Cu")
		(net "GND")
	)
	(via
		(at 28.498038 -73.763124)
		(size 0.7112)
		(drill 0.4064)
		(layers "F.Cu" "B.Cu")
		(net "GND")
	)
	(via
		(at 28.498038 -43.283124)
		(size 0.7112)
		(drill 0.4064)
		(layers "F.Cu" "B.Cu")
		(net "GND")
	)
	(via
		(at 196.3928 -24.7904)
		(size 0.508)
		(drill 0.254)
		(layers "F.Cu" "B.Cu")
		(net "GND")
	)
	(via
		(at 91.1606 -155.6512)
		(size 0.5588)
		(drill 0.3048)
		(layers "F.Cu" "B.Cu")
		(net "GND")
	)
	(via
		(at 31.510478 -191.84112)
		(size 0.7112)
		(drill 0.4064)
		(layers "F.Cu" "B.Cu")
		(net "GND")
	)
	(via
		(at 204.399388 -191.84112)
		(size 0.7112)
		(drill 0.4064)
		(layers "F.Cu" "B.Cu")
		(net "GND")
	)
	(via
		(at 28.498038 -15.343124)
		(size 0.7112)
		(drill 0.4064)
		(layers "F.Cu" "B.Cu")
		(net "GND")
	)
	(via
		(at 82.7278 -180.7464)
		(size 0.7112)
		(drill 0.4064)
		(layers "F.Cu" "B.Cu")
		(net "GND")
	)
	(via
		(at 232.841038 -138.353292)
		(size 0.7112)
		(drill 0.4064)
		(layers "F.Cu" "B.Cu")
		(net "GND")
	)
	(via
		(at 94.3102 -157.1752)
		(size 0.5588)
		(drill 0.3048)
		(layers "F.Cu" "B.Cu")
		(net "GND")
	)
	(via
		(at 18.2499 -177.5206)
		(size 0.508)
		(drill 0.254)
		(layers "F.Cu" "B.Cu")
		(net "GND")
	)
	(via
		(at 232.841038 -137.083292)
		(size 0.7112)
		(drill 0.4064)
		(layers "F.Cu" "B.Cu")
		(net "GND")
	)
	(via
		(at 193.5353 -32.1183)
		(size 0.508)
		(drill 0.254)
		(layers "F.Cu" "B.Cu")
		(net "GND")
	)
	(via
		(at 232.841038 -12.623292)
		(size 0.7112)
		(drill 0.4064)
		(layers "F.Cu" "B.Cu")
		(net "GND")
	)
	(via
		(at 39.699438 -141.799818)
		(size 0.4572)
		(drill 0.2032)
		(layers "F.Cu" "B.Cu")
		(net "GND")
	)
	(via
		(at 146.45894 -112.627664)
		(size 0.7112)
		(drill 0.4064)
		(layers "F.Cu" "B.Cu")
		(net "GND")
	)
	(via
		(at 83.580478 -191.84112)
		(size 0.7112)
		(drill 0.4064)
		(layers "F.Cu" "B.Cu")
		(net "GND")
	)
	(via
		(at 2.159 -60.522866)
		(size 0.7112)
		(drill 0.4064)
		(layers "F.Cu" "B.Cu")
		(net "GND")
	)
	(via
		(at 2.159 -9.722866)
		(size 0.7112)
		(drill 0.4064)
		(layers "F.Cu" "B.Cu")
		(net "GND")
	)
	(via
		(at 201.936604 -95.137224)
		(size 0.508)
		(drill 0.254)
		(layers "F.Cu" "B.Cu")
		(net "GND")
	)
	(via
		(at 185.60034 -59.500516)
		(size 0.508)
		(drill 0.254)
		(layers "F.Cu" "B.Cu")
		(net "GND")
	)
	(via
		(at 228.06533 -2.159)
		(size 0.7112)
		(drill 0.4064)
		(layers "F.Cu" "B.Cu")
		(net "GND")
	)
	(via
		(at 2.159 -101.162866)
		(size 0.7112)
		(drill 0.4064)
		(layers "F.Cu" "B.Cu")
		(net "GND")
	)
	(via
		(at 186.812936 -113.938812)
		(size 0.7112)
		(drill 0.4064)
		(layers "F.Cu" "B.Cu")
		(net "GND")
	)
	(via
		(at 94.3356 -155.6258)
		(size 0.5588)
		(drill 0.3048)
		(layers "F.Cu" "B.Cu")
		(net "GND")
	)
	(via
		(at 45.466 -126.9492)
		(size 0.508)
		(drill 0.254)
		(layers "F.Cu" "B.Cu")
		(net "GND")
	)
	(via
		(at 10.238486 -167.8178)
		(size 0.508)
		(drill 0.254)
		(layers "F.Cu" "B.Cu")
		(net "GND")
	)
	(via
		(at 232.841038 -67.233292)
		(size 0.7112)
		(drill 0.4064)
		(layers "F.Cu" "B.Cu")
		(net "GND")
	)
	(via
		(at 232.841038 -114.223292)
		(size 0.7112)
		(drill 0.4064)
		(layers "F.Cu" "B.Cu")
		(net "GND")
	)
	(via
		(at 210.03895 -14.58595)
		(size 0.508)
		(drill 0.254)
		(layers "F.Cu" "B.Cu")
		(net "GND")
	)
	(via
		(at 175.189388 -191.84112)
		(size 0.7112)
		(drill 0.4064)
		(layers "F.Cu" "B.Cu")
		(net "GND")
	)
	(via
		(at 203.199746 -73.899776)
		(size 0.508)
		(drill 0.254)
		(layers "F.Cu" "B.Cu")
		(net "GND")
	)
	(via
		(at 17.755616 -127.527558)
		(size 0.508)
		(drill 0.254)
		(layers "F.Cu" "B.Cu")
		(net "GND")
	)
	(via
		(at 232.841038 -49.453292)
		(size 0.7112)
		(drill 0.4064)
		(layers "F.Cu" "B.Cu")
		(net "GND")
	)
	(via
		(at 83.08594 -148.24964)
		(size 0.508)
		(drill 0.254)
		(layers "F.Cu" "B.Cu")
		(net "GND")
	)
	(via
		(at 187.889388 -191.84112)
		(size 0.7112)
		(drill 0.4064)
		(layers "F.Cu" "B.Cu")
		(net "GND")
	)
	(via
		(at 42.900092 -142.599918)
		(size 0.4572)
		(drill 0.2032)
		(layers "F.Cu" "B.Cu")
		(net "GND")
	)
	(via
		(at 86.126574 -159.555942)
		(size 0.508)
		(drill 0.254)
		(layers "F.Cu" "B.Cu")
		(net "GND")
	)
	(via
		(at 28.498038 -36.933124)
		(size 0.7112)
		(drill 0.4064)
		(layers "F.Cu" "B.Cu")
		(net "GND")
	)
	(via
		(at 58.182002 -162.19424)
		(size 0.508)
		(drill 0.254)
		(layers "F.Cu" "B.Cu")
		(net "GND")
	)
	(via
		(at 75.08748 -179.10048)
		(size 0.5588)
		(drill 0.3048)
		(layers "F.Cu" "B.Cu")
		(net "GND")
	)
	(via
		(at 28.498038 -78.843124)
		(size 0.7112)
		(drill 0.4064)
		(layers "F.Cu" "B.Cu")
		(net "GND")
	)
	(via
		(at 232.841038 -152.323292)
		(size 0.7112)
		(drill 0.4064)
		(layers "F.Cu" "B.Cu")
		(net "GND")
	)
	(via
		(at 199.20966 -69.099938)
		(size 0.508)
		(drill 0.254)
		(layers "F.Cu" "B.Cu")
		(net "GND")
	)
	(via
		(at 203.93533 -2.159)
		(size 0.7112)
		(drill 0.4064)
		(layers "F.Cu" "B.Cu")
		(net "GND")
	)
	(via
		(at 2.159 -92.272866)
		(size 0.7112)
		(drill 0.4064)
		(layers "F.Cu" "B.Cu")
		(net "GND")
	)
	(via
		(at 7.295134 -2.159)
		(size 0.7112)
		(drill 0.4064)
		(layers "F.Cu" "B.Cu")
		(net "GND")
	)
	(via
		(at 47.699676 -148.999956)
		(size 0.4572)
		(drill 0.2032)
		(layers "F.Cu" "B.Cu")
		(net "GND")
	)
	(via
		(at 188.0362 -110.9218)
		(size 0.7112)
		(drill 0.4064)
		(layers "F.Cu" "B.Cu")
		(net "GND")
	)
	(via
		(at 33.024826 -183.00573)
		(size 0.5588)
		(drill 0.3048)
		(layers "F.Cu" "B.Cu")
		(net "GND")
	)
	(via
		(at 30.240478 -191.84112)
		(size 0.7112)
		(drill 0.4064)
		(layers "F.Cu" "B.Cu")
		(net "GND")
	)
	(via
		(at 146.45894 -122.787664)
		(size 0.7112)
		(drill 0.4064)
		(layers "F.Cu" "B.Cu")
		(net "GND")
	)
	(via
		(at 77.648562 -51.34991)
		(size 0.508)
		(drill 0.254)
		(layers "F.Cu" "B.Cu")
		(net "GND")
	)
	(via
		(at 42.099992 -148.199856)
		(size 0.4572)
		(drill 0.2032)
		(layers "F.Cu" "B.Cu")
		(net "GND")
	)
	(via
		(at 50.4698 -179.06619)
		(size 0.7112)
		(drill 0.4064)
		(layers "F.Cu" "B.Cu")
		(net "GND")
	)
	(via
		(at 204.3684 -53.5432)
		(size 0.508)
		(drill 0.254)
		(layers "F.Cu" "B.Cu")
		(net "GND")
	)
	(via
		(at 33.18002 -157.7086)
		(size 0.508)
		(drill 0.254)
		(layers "F.Cu" "B.Cu")
		(net "GND")
	)
	(via
		(at 204.4954 -128.2446)
		(size 0.5588)
		(drill 0.3048)
		(layers "F.Cu" "B.Cu")
		(net "GND")
	)
	(via
		(at 184.799986 -69.099938)
		(size 0.508)
		(drill 0.254)
		(layers "F.Cu" "B.Cu")
		(net "GND")
	)
	(via
		(at 80.6704 -153.2382)
		(size 0.508)
		(drill 0.254)
		(layers "F.Cu" "B.Cu")
		(net "GND")
	)
	(via
		(at 3.429 -186.0296)
		(size 0.7112)
		(drill 0.4064)
		(layers "F.Cu" "B.Cu")
		(net "GND")
	)
	(via
		(at 99.874324 -19.713956)
		(size 0.508)
		(drill 0.254)
		(layers "F.Cu" "B.Cu")
		(net "GND")
	)
	(via
		(at 156.64434 -135.763)
		(size 0.7112)
		(drill 0.4064)
		(layers "F.Cu" "B.Cu")
		(net "GND")
	)
	(via
		(at 2.159 -79.572866)
		(size 0.7112)
		(drill 0.4064)
		(layers "F.Cu" "B.Cu")
		(net "GND")
	)
	(via
		(at 3.485134 -2.159)
		(size 0.7112)
		(drill 0.4064)
		(layers "F.Cu" "B.Cu")
		(net "GND")
	)
	(via
		(at 232.841038 -81.203292)
		(size 0.7112)
		(drill 0.4064)
		(layers "F.Cu" "B.Cu")
		(net "GND")
	)
	(via
		(at 195.6054 -2.159)
		(size 0.7112)
		(drill 0.4064)
		(layers "F.Cu" "B.Cu")
		(net "GND")
	)
	(via
		(at 28.498038 -94.083124)
		(size 0.7112)
		(drill 0.4064)
		(layers "F.Cu" "B.Cu")
		(net "GND")
	)
	(via
		(at 21.717 -159.639)
		(size 0.508)
		(drill 0.254)
		(layers "F.Cu" "B.Cu")
		(net "GND")
	)
	(via
		(at 86.314788 -154.88539)
		(size 0.508)
		(drill 0.254)
		(layers "F.Cu" "B.Cu")
		(net "GND")
	)
	(via
		(at 6.025134 -2.159)
		(size 0.7112)
		(drill 0.4064)
		(layers "F.Cu" "B.Cu")
		(net "GND")
	)
	(via
		(at 44.500038 -149.800056)
		(size 0.4572)
		(drill 0.2032)
		(layers "F.Cu" "B.Cu")
		(net "GND")
	)
	(via
		(at 97.9424 -134.393178)
		(size 0.508)
		(drill 0.254)
		(layers "F.Cu" "B.Cu")
		(net "GND")
	)
	(via
		(at 59.436 -159.912304)
		(size 0.508)
		(drill 0.254)
		(layers "F.Cu" "B.Cu")
		(net "GND")
	)
	(via
		(at 185.349388 -191.84112)
		(size 0.7112)
		(drill 0.4064)
		(layers "F.Cu" "B.Cu")
		(net "GND")
	)
	(via
		(at 155.5242 -87.4522)
		(size 0.508)
		(drill 0.254)
		(layers "F.Cu" "B.Cu")
		(net "GND")
	)
	(via
		(at 40.500046 -144.200118)
		(size 0.4572)
		(drill 0.2032)
		(layers "F.Cu" "B.Cu")
		(net "GND")
	)
	(via
		(at 206.022448 -100.00869)
		(size 0.508)
		(drill 0.254)
		(layers "F.Cu" "B.Cu")
		(net "GND")
	)
	(via
		(at 232.841038 -144.703292)
		(size 0.7112)
		(drill 0.4064)
		(layers "F.Cu" "B.Cu")
		(net "GND")
	)
	(via
		(at 28.498038 -72.493124)
		(size 0.7112)
		(drill 0.4064)
		(layers "F.Cu" "B.Cu")
		(net "GND")
	)
	(via
		(at 194.007486 -136.446514)
		(size 0.508)
		(drill 0.254)
		(layers "F.Cu" "B.Cu")
		(net "GND")
	)
	(via
		(at 28.498038 -80.113124)
		(size 0.7112)
		(drill 0.4064)
		(layers "F.Cu" "B.Cu")
		(net "GND")
	)
	(via
		(at 25.08758 -15.45844)
		(size 0.508)
		(drill 0.254)
		(layers "F.Cu" "B.Cu")
		(net "GND")
	)
	(via
		(at 185.60034 -69.100192)
		(size 0.508)
		(drill 0.254)
		(layers "F.Cu" "B.Cu")
		(net "GND")
	)
	(via
		(at 146.45894 -159.617664)
		(size 0.7112)
		(drill 0.4064)
		(layers "F.Cu" "B.Cu")
		(net "GND")
	)
	(via
		(at 2.159 -28.772866)
		(size 0.7112)
		(drill 0.4064)
		(layers "F.Cu" "B.Cu")
		(net "GND")
	)
	(via
		(at 232.841038 -20.243292)
		(size 0.7112)
		(drill 0.4064)
		(layers "F.Cu" "B.Cu")
		(net "GND")
	)
	(via
		(at 4.0132 -187.1726)
		(size 0.7112)
		(drill 0.4064)
		(layers "F.Cu" "B.Cu")
		(net "GND")
	)
	(via
		(at 28.498038 -90.273124)
		(size 0.7112)
		(drill 0.4064)
		(layers "F.Cu" "B.Cu")
		(net "GND")
	)
	(via
		(at 64.566546 -153.274522)
		(size 0.508)
		(drill 0.254)
		(layers "F.Cu" "B.Cu")
		(net "GND")
	)
	(via
		(at 34.294826 -179.34813)
		(size 0.5588)
		(drill 0.3048)
		(layers "F.Cu" "B.Cu")
		(net "GND")
	)
	(via
		(at 89.3064 -137.3124)
		(size 0.508)
		(drill 0.254)
		(layers "F.Cu" "B.Cu")
		(net "GND")
	)
	(via
		(at 229.33533 -2.159)
		(size 0.7112)
		(drill 0.4064)
		(layers "F.Cu" "B.Cu")
		(net "GND")
	)
	(via
		(at 74.623422 -132.475224)
		(size 0.508)
		(drill 0.254)
		(layers "F.Cu" "B.Cu")
		(net "GND")
	)
	(via
		(at 232.841038 -178.993292)
		(size 0.7112)
		(drill 0.4064)
		(layers "F.Cu" "B.Cu")
		(net "GND")
	)
	(via
		(at 147.141946 -184.856374)
		(size 0.7112)
		(drill 0.4064)
		(layers "F.Cu" "B.Cu")
		(net "GND")
	)
	(via
		(at 55.6768 -164.3888)
		(size 0.508)
		(drill 0.254)
		(layers "F.Cu" "B.Cu")
		(net "GND")
	)
	(via
		(at 81.586832 -131.930394)
		(size 0.508)
		(drill 0.254)
		(layers "F.Cu" "B.Cu")
		(net "GND")
	)
	(via
		(at 24.5872 -168.148)
		(size 0.7112)
		(drill 0.4064)
		(layers "F.Cu" "B.Cu")
		(net "GND")
	)
	(via
		(at 146.45894 -145.647664)
		(size 0.7112)
		(drill 0.4064)
		(layers "F.Cu" "B.Cu")
		(net "GND")
	)
	(via
		(at 197.1548 -116.332)
		(size 0.7112)
		(drill 0.4064)
		(layers "F.Cu" "B.Cu")
		(net "GND")
	)
	(via
		(at 2.159 -87.192866)
		(size 0.7112)
		(drill 0.4064)
		(layers "F.Cu" "B.Cu")
		(net "GND")
	)
	(via
		(at 28.498038 -87.733124)
		(size 0.7112)
		(drill 0.4064)
		(layers "F.Cu" "B.Cu")
		(net "GND")
	)
	(via
		(at 76.9874 -149.098)
		(size 0.508)
		(drill 0.254)
		(layers "F.Cu" "B.Cu")
		(net "GND")
	)
	(via
		(at 200.000108 -75.499722)
		(size 0.508)
		(drill 0.254)
		(layers "F.Cu" "B.Cu")
		(net "GND")
	)
	(via
		(at 232.841038 -32.943292)
		(size 0.7112)
		(drill 0.4064)
		(layers "F.Cu" "B.Cu")
		(net "GND")
	)
	(via
		(at 232.841038 -25.323292)
		(size 0.7112)
		(drill 0.4064)
		(layers "F.Cu" "B.Cu")
		(net "GND")
	)
	(via
		(at 95.210376 -22.3266)
		(size 0.508)
		(drill 0.254)
		(layers "F.Cu" "B.Cu")
		(net "GND")
	)
	(via
		(at 156.572712 -96.401382)
		(size 0.508)
		(drill 0.254)
		(layers "F.Cu" "B.Cu")
		(net "GND")
	)
	(via
		(at 34.5694 -166.7002)
		(size 0.508)
		(drill 0.254)
		(layers "F.Cu" "B.Cu")
		(net "GND")
	)
	(via
		(at 73.7362 -161.7726)
		(size 0.508)
		(drill 0.254)
		(layers "F.Cu" "B.Cu")
		(net "GND")
	)
	(via
		(at 22.834346 -141.76121)
		(size 0.508)
		(drill 0.254)
		(layers "F.Cu" "B.Cu")
		(net "GND")
	)
	(via
		(at 2.159 -171.012866)
		(size 0.7112)
		(drill 0.4064)
		(layers "F.Cu" "B.Cu")
		(net "GND")
	)
	(via
		(at 176.459388 -191.84112)
		(size 0.7112)
		(drill 0.4064)
		(layers "F.Cu" "B.Cu")
		(net "GND")
	)
	(via
		(at 222.98533 -2.159)
		(size 0.7112)
		(drill 0.4064)
		(layers "F.Cu" "B.Cu")
		(net "GND")
	)
	(via
		(at 192.793874 -65.903094)
		(size 0.508)
		(drill 0.254)
		(layers "F.Cu" "B.Cu")
		(net "GND")
	)
	(via
		(at 2.159 -59.252866)
		(size 0.7112)
		(drill 0.4064)
		(layers "F.Cu" "B.Cu")
		(net "GND")
	)
	(via
		(at 155.82392 -84.76234)
		(size 0.508)
		(drill 0.254)
		(layers "F.Cu" "B.Cu")
		(net "GND")
	)
	(via
		(at 49.299876 -136.99998)
		(size 0.4572)
		(drill 0.2032)
		(layers "F.Cu" "B.Cu")
		(net "GND")
	)
	(via
		(at 146.45894 -106.277664)
		(size 0.7112)
		(drill 0.4064)
		(layers "F.Cu" "B.Cu")
		(net "GND")
	)
	(via
		(at 30.607 -189.1792)
		(size 0.7112)
		(drill 0.4064)
		(layers "F.Cu" "B.Cu")
		(net "GND")
	)
	(via
		(at 121.2596 -17.6022)
		(size 0.508)
		(drill 0.254)
		(layers "F.Cu" "B.Cu")
		(net "GND")
	)
	(via
		(at 194.400424 -69.900038)
		(size 0.508)
		(drill 0.254)
		(layers "F.Cu" "B.Cu")
		(net "GND")
	)
	(via
		(at 19.151346 -127.553466)
		(size 0.508)
		(drill 0.254)
		(layers "F.Cu" "B.Cu")
		(net "GND")
	)
	(via
		(at 62.94755 -170.27525)
		(size 0.508)
		(drill 0.254)
		(layers "F.Cu" "B.Cu")
		(net "GND")
	)
	(via
		(at 163.8808 -132.5626)
		(size 0.7112)
		(drill 0.4064)
		(layers "F.Cu" "B.Cu")
		(net "GND")
	)
	(via
		(at 146.45894 -153.267664)
		(size 0.7112)
		(drill 0.4064)
		(layers "F.Cu" "B.Cu")
		(net "GND")
	)
	(via
		(at 184.799986 -59.500008)
		(size 0.508)
		(drill 0.254)
		(layers "F.Cu" "B.Cu")
		(net "GND")
	)
	(via
		(at 96.647 -8.509)
		(size 0.508)
		(drill 0.254)
		(layers "F.Cu" "B.Cu")
		(net "GND")
	)
	(via
		(at 2.159 -13.532866)
		(size 0.7112)
		(drill 0.4064)
		(layers "F.Cu" "B.Cu")
		(net "GND")
	)
	(via
		(at 81.36128 -180.77688)
		(size 0.7112)
		(drill 0.4064)
		(layers "F.Cu" "B.Cu")
		(net "GND")
	)
	(via
		(at 53.773324 -163.918646)
		(size 0.508)
		(drill 0.254)
		(layers "F.Cu" "B.Cu")
		(net "GND")
	)
	(via
		(at 28.498038 -77.573124)
		(size 0.7112)
		(drill 0.4064)
		(layers "F.Cu" "B.Cu")
		(net "GND")
	)
	(via
		(at 197.605904 -65.903094)
		(size 0.508)
		(drill 0.254)
		(layers "F.Cu" "B.Cu")
		(net "GND")
	)
	(via
		(at 147.70989 -185.992262)
		(size 0.7112)
		(drill 0.4064)
		(layers "F.Cu" "B.Cu")
		(net "GND")
	)
	(via
		(at 46.900084 -146.59991)
		(size 0.4572)
		(drill 0.2032)
		(layers "F.Cu" "B.Cu")
		(net "GND")
	)
	(via
		(at 64.827912 -160.292034)
		(size 0.508)
		(drill 0.254)
		(layers "F.Cu" "B.Cu")
		(net "GND")
	)
	(via
		(at 2.159 -177.362866)
		(size 0.7112)
		(drill 0.4064)
		(layers "F.Cu" "B.Cu")
		(net "GND")
	)
	(via
		(at 89.941908 -167.809164)
		(size 0.508)
		(drill 0.254)
		(layers "F.Cu" "B.Cu")
		(net "GND")
	)
	(via
		(at 2.159 -36.392866)
		(size 0.7112)
		(drill 0.4064)
		(layers "F.Cu" "B.Cu")
		(net "GND")
	)
	(via
		(at 232.841038 -48.183292)
		(size 0.7112)
		(drill 0.4064)
		(layers "F.Cu" "B.Cu")
		(net "GND")
	)
	(via
		(at 207.8736 -116.6622)
		(size 0.7112)
		(drill 0.4064)
		(layers "F.Cu" "B.Cu")
		(net "GND")
	)
	(via
		(at 28.498038 -22.963124)
		(size 0.7112)
		(drill 0.4064)
		(layers "F.Cu" "B.Cu")
		(net "GND")
	)
	(via
		(at 232.3338 -184.4294)
		(size 0.7112)
		(drill 0.4064)
		(layers "F.Cu" "B.Cu")
		(net "GND")
	)
	(via
		(at 187.200032 -62.699646)
		(size 0.508)
		(drill 0.254)
		(layers "F.Cu" "B.Cu")
		(net "GND")
	)
	(via
		(at 26.7589 -130.0099)
		(size 0.508)
		(drill 0.254)
		(layers "F.Cu" "B.Cu")
		(net "GND")
	)
	(via
		(at 69.1007 -180.79974)
		(size 0.508)
		(drill 0.254)
		(layers "F.Cu" "B.Cu")
		(net "GND")
	)
	(via
		(at 184.799986 -64.3001)
		(size 0.508)
		(drill 0.254)
		(layers "F.Cu" "B.Cu")
		(net "GND")
	)
	(via
		(at 22.834346 -145.761456)
		(size 0.508)
		(drill 0.254)
		(layers "F.Cu" "B.Cu")
		(net "GND")
	)
	(via
		(at 92.9132 -126.5682)
		(size 0.508)
		(drill 0.254)
		(layers "F.Cu" "B.Cu")
		(net "GND")
	)
	(via
		(at 176.859184 -146.710146)
		(size 0.5588)
		(drill 0.3048)
		(layers "F.Cu" "B.Cu")
		(net "GND")
	)
	(via
		(at 28.498038 -86.463124)
		(size 0.7112)
		(drill 0.4064)
		(layers "F.Cu" "B.Cu")
		(net "GND")
	)
	(via
		(at 88.471756 -148.745956)
		(size 0.508)
		(drill 0.254)
		(layers "F.Cu" "B.Cu")
		(net "GND")
	)
	(via
		(at 210.749388 -191.84112)
		(size 0.7112)
		(drill 0.4064)
		(layers "F.Cu" "B.Cu")
		(net "GND")
	)
	(via
		(at 62.606936 -136.433306)
		(size 0.508)
		(drill 0.254)
		(layers "F.Cu" "B.Cu")
		(net "GND")
	)
	(via
		(at 73.81748 -180.37048)
		(size 0.5588)
		(drill 0.3048)
		(layers "F.Cu" "B.Cu")
		(net "GND")
	)
	(via
		(at 65.800478 -191.84112)
		(size 0.7112)
		(drill 0.4064)
		(layers "F.Cu" "B.Cu")
		(net "GND")
	)
	(via
		(at 2.159 -108.782866)
		(size 0.7112)
		(drill 0.4064)
		(layers "F.Cu" "B.Cu")
		(net "GND")
	)
	(via
		(at 202.520042 -130.089148)
		(size 0.508)
		(drill 0.254)
		(layers "F.Cu" "B.Cu")
		(net "GND")
	)
	(via
		(at 42.926 -162.6362)
		(size 0.508)
		(drill 0.254)
		(layers "F.Cu" "B.Cu")
		(net "GND")
	)
	(via
		(at 90.2462 -129.5654)
		(size 0.508)
		(drill 0.254)
		(layers "F.Cu" "B.Cu")
		(net "GND")
	)
	(via
		(at 77.58938 -158.428436)
		(size 0.508)
		(drill 0.254)
		(layers "F.Cu" "B.Cu")
		(net "GND")
	)
	(via
		(at 82.7024 -162.5854)
		(size 0.7112)
		(drill 0.4064)
		(layers "F.Cu" "B.Cu")
		(net "GND")
	)
	(via
		(at 189.600078 -61.100208)
		(size 0.508)
		(drill 0.254)
		(layers "F.Cu" "B.Cu")
		(net "GND")
	)
	(via
		(at 232.841038 -22.783292)
		(size 0.7112)
		(drill 0.4064)
		(layers "F.Cu" "B.Cu")
		(net "GND")
	)
	(via
		(at 179.8574 -84.17814)
		(size 0.508)
		(drill 0.254)
		(layers "F.Cu" "B.Cu")
		(net "GND")
	)
	(via
		(at 67.06616 -164.68598)
		(size 0.508)
		(drill 0.254)
		(layers "F.Cu" "B.Cu")
		(net "GND")
	)
	(via
		(at 191.4652 -46.101)
		(size 0.508)
		(drill 0.254)
		(layers "F.Cu" "B.Cu")
		(net "GND")
	)
	(via
		(at 188.0362 -108.4834)
		(size 0.7112)
		(drill 0.4064)
		(layers "F.Cu" "B.Cu")
		(net "GND")
	)
	(via
		(at 2.159 -89.732866)
		(size 0.7112)
		(drill 0.4064)
		(layers "F.Cu" "B.Cu")
		(net "GND")
	)
	(via
		(at 152.399492 -99.38258)
		(size 0.508)
		(drill 0.254)
		(layers "F.Cu" "B.Cu")
		(net "GND")
	)
	(via
		(at 192.000124 -59.500262)
		(size 0.508)
		(drill 0.254)
		(layers "F.Cu" "B.Cu")
		(net "GND")
	)
	(via
		(at 43.700192 -141.00048)
		(size 0.4572)
		(drill 0.2032)
		(layers "F.Cu" "B.Cu")
		(net "GND")
	)
	(via
		(at 85.1408 -162.5854)
		(size 0.7112)
		(drill 0.4064)
		(layers "F.Cu" "B.Cu")
		(net "GND")
	)
	(via
		(at 28.498038 -85.193124)
		(size 0.7112)
		(drill 0.4064)
		(layers "F.Cu" "B.Cu")
		(net "GND")
	)
	(via
		(at 187.200286 -59.500262)
		(size 0.508)
		(drill 0.254)
		(layers "F.Cu" "B.Cu")
		(net "GND")
	)
	(via
		(at 59.7154 -172.699934)
		(size 0.508)
		(drill 0.254)
		(layers "F.Cu" "B.Cu")
		(net "GND")
	)
	(via
		(at 232.841038 -168.833292)
		(size 0.7112)
		(drill 0.4064)
		(layers "F.Cu" "B.Cu")
		(net "GND")
	)
	(via
		(at 136.345676 -19.652742)
		(size 0.7112)
		(drill 0.4064)
		(layers "F.Cu" "B.Cu")
		(net "GND")
	)
	(via
		(at 28.498038 -102.973124)
		(size 0.7112)
		(drill 0.4064)
		(layers "F.Cu" "B.Cu")
		(net "GND")
	)
	(via
		(at 35.538664 -179.278788)
		(size 0.5588)
		(drill 0.3048)
		(layers "F.Cu" "B.Cu")
		(net "GND")
	)
	(via
		(at 182.45836 -80.2132)
		(size 0.508)
		(drill 0.254)
		(layers "F.Cu" "B.Cu")
		(net "GND")
	)
	(via
		(at 198.049388 -191.84112)
		(size 0.7112)
		(drill 0.4064)
		(layers "F.Cu" "B.Cu")
		(net "GND")
	)
	(via
		(at 2.159 -129.102866)
		(size 0.7112)
		(drill 0.4064)
		(layers "F.Cu" "B.Cu")
		(net "GND")
	)
	(via
		(at 183.20004 -64.3001)
		(size 0.508)
		(drill 0.254)
		(layers "F.Cu" "B.Cu")
		(net "GND")
	)
	(via
		(at 192.793874 -69.10324)
		(size 0.508)
		(drill 0.254)
		(layers "F.Cu" "B.Cu")
		(net "GND")
	)
	(via
		(at 224.249234 -61.917834)
		(size 0.508)
		(drill 0.254)
		(layers "F.Cu" "B.Cu")
		(net "GND")
	)
	(via
		(at 2.159 -155.772866)
		(size 0.7112)
		(drill 0.4064)
		(layers "F.Cu" "B.Cu")
		(net "GND")
	)
	(via
		(at 186.812936 -118.815612)
		(size 0.7112)
		(drill 0.4064)
		(layers "F.Cu" "B.Cu")
		(net "GND")
	)
	(via
		(at 180.6321 -44.2722)
		(size 0.508)
		(drill 0.254)
		(layers "F.Cu" "B.Cu")
		(net "GND")
	)
	(via
		(at 26.345134 -2.159)
		(size 0.7112)
		(drill 0.4064)
		(layers "F.Cu" "B.Cu")
		(net "GND")
	)
	(via
		(at 75.18908 -7.47268)
		(size 0.7112)
		(drill 0.4064)
		(layers "F.Cu" "B.Cu")
		(net "GND")
	)
	(via
		(at 199.206358 -64.303148)
		(size 0.508)
		(drill 0.254)
		(layers "F.Cu" "B.Cu")
		(net "GND")
	)
	(via
		(at 194.59194 -31.81858)
		(size 0.508)
		(drill 0.254)
		(layers "F.Cu" "B.Cu")
		(net "GND")
	)
	(via
		(at 146.45894 -182.477664)
		(size 0.7112)
		(drill 0.4064)
		(layers "F.Cu" "B.Cu")
		(net "GND")
	)
	(via
		(at 2.159 -137.992866)
		(size 0.7112)
		(drill 0.4064)
		(layers "F.Cu" "B.Cu")
		(net "GND")
	)
	(via
		(at 28.498038 -53.443124)
		(size 0.7112)
		(drill 0.4064)
		(layers "F.Cu" "B.Cu")
		(net "GND")
	)
	(via
		(at 186.812936 -109.062012)
		(size 0.7112)
		(drill 0.4064)
		(layers "F.Cu" "B.Cu")
		(net "GND")
	)
	(via
		(at 15.3924 -170.4086)
		(size 0.5588)
		(drill 0.3048)
		(layers "F.Cu" "B.Cu")
		(net "GND")
	)
	(via
		(at 232.841038 -157.403292)
		(size 0.7112)
		(drill 0.4064)
		(layers "F.Cu" "B.Cu")
		(net "GND")
	)
	(via
		(at 95.070168 -147.3962)
		(size 0.508)
		(drill 0.254)
		(layers "F.Cu" "B.Cu")
		(net "GND")
	)
	(via
		(at 38.899846 -153.800302)
		(size 0.4572)
		(drill 0.2032)
		(layers "F.Cu" "B.Cu")
		(net "GND")
	)
	(via
		(at 183.999886 -73.899776)
		(size 0.508)
		(drill 0.254)
		(layers "F.Cu" "B.Cu")
		(net "GND")
	)
	(via
		(at 194.40017 -64.3001)
		(size 0.508)
		(drill 0.254)
		(layers "F.Cu" "B.Cu")
		(net "GND")
	)
	(via
		(at 122.604022 -10.7188)
		(size 0.508)
		(drill 0.254)
		(layers "F.Cu" "B.Cu")
		(net "GND")
	)
	(via
		(at 28.498038 -97.893124)
		(size 0.7112)
		(drill 0.4064)
		(layers "F.Cu" "B.Cu")
		(net "GND")
	)
	(via
		(at 67.31 -168.293796)
		(size 0.508)
		(drill 0.254)
		(layers "F.Cu" "B.Cu")
		(net "GND")
	)
	(via
		(at 170.2816 -136.3218)
		(size 0.7112)
		(drill 0.4064)
		(layers "F.Cu" "B.Cu")
		(net "GND")
	)
	(via
		(at 232.841038 -53.263292)
		(size 0.7112)
		(drill 0.4064)
		(layers "F.Cu" "B.Cu")
		(net "GND")
	)
	(via
		(at 87.5538 -129.286)
		(size 0.508)
		(drill 0.254)
		(layers "F.Cu" "B.Cu")
		(net "GND")
	)
	(via
		(at 2.159 -47.822866)
		(size 0.7112)
		(drill 0.4064)
		(layers "F.Cu" "B.Cu")
		(net "GND")
	)
	(via
		(at 164.442902 -177.163476)
		(size 0.6604)
		(drill 0.3302)
		(layers "F.Cu" "B.Cu")
		(net "GND")
	)
	(via
		(at 25.2984 -172.339)
		(size 0.7112)
		(drill 0.4064)
		(layers "F.Cu" "B.Cu")
		(net "GND")
	)
	(via
		(at 170.2816 -138.7602)
		(size 0.7112)
		(drill 0.4064)
		(layers "F.Cu" "B.Cu")
		(net "GND")
	)
	(via
		(at 232.841038 -105.333292)
		(size 0.7112)
		(drill 0.4064)
		(layers "F.Cu" "B.Cu")
		(net "GND")
	)
	(via
		(at 232.841038 -62.153292)
		(size 0.7112)
		(drill 0.4064)
		(layers "F.Cu" "B.Cu")
		(net "GND")
	)
	(via
		(at 2.159 -61.792866)
		(size 0.7112)
		(drill 0.4064)
		(layers "F.Cu" "B.Cu")
		(net "GND")
	)
	(via
		(at 196.799708 -73.099676)
		(size 0.508)
		(drill 0.254)
		(layers "F.Cu" "B.Cu")
		(net "GND")
	)
	(via
		(at 50.00117 -177.38217)
		(size 0.508)
		(drill 0.254)
		(layers "F.Cu" "B.Cu")
		(net "GND")
	)
	(via
		(at 53.299868 -148.199856)
		(size 0.4572)
		(drill 0.2032)
		(layers "F.Cu" "B.Cu")
		(net "GND")
	)
	(via
		(at 183.20004 -65.900046)
		(size 0.508)
		(drill 0.254)
		(layers "F.Cu" "B.Cu")
		(net "GND")
	)
	(via
		(at 56.49976 -153.800048)
		(size 0.4572)
		(drill 0.2032)
		(layers "F.Cu" "B.Cu")
		(net "GND")
	)
	(via
		(at 131.04241 -20.466304)
		(size 0.7112)
		(drill 0.4064)
		(layers "F.Cu" "B.Cu")
		(net "GND")
	)
	(via
		(at 198.390256 -69.099938)
		(size 0.508)
		(drill 0.254)
		(layers "F.Cu" "B.Cu")
		(net "GND")
	)
	(via
		(at 8.4074 -191.9224)
		(size 0.7112)
		(drill 0.4064)
		(layers "F.Cu" "B.Cu")
		(net "GND")
	)
	(via
		(at 8.565134 -2.159)
		(size 0.7112)
		(drill 0.4064)
		(layers "F.Cu" "B.Cu")
		(net "GND")
	)
	(via
		(at 28.498038 -47.093124)
		(size 0.7112)
		(drill 0.4064)
		(layers "F.Cu" "B.Cu")
		(net "GND")
	)
	(via
		(at 46.900084 -144.199864)
		(size 0.4572)
		(drill 0.2032)
		(layers "F.Cu" "B.Cu")
		(net "GND")
	)
	(via
		(at 232.841038 -120.573292)
		(size 0.7112)
		(drill 0.4064)
		(layers "F.Cu" "B.Cu")
		(net "GND")
	)
	(via
		(at 16.434054 -144.961864)
		(size 0.508)
		(drill 0.254)
		(layers "F.Cu" "B.Cu")
		(net "GND")
	)
	(via
		(at 214.559388 -191.84112)
		(size 0.7112)
		(drill 0.4064)
		(layers "F.Cu" "B.Cu")
		(net "GND")
	)
	(via
		(at 49.290478 -191.84112)
		(size 0.7112)
		(drill 0.4064)
		(layers "F.Cu" "B.Cu")
		(net "GND")
	)
	(via
		(at 39.699946 -147.40001)
		(size 0.4572)
		(drill 0.2032)
		(layers "F.Cu" "B.Cu")
		(net "GND")
	)
	(via
		(at 163.6014 -50.7619)
		(size 0.508)
		(drill 0.254)
		(layers "F.Cu" "B.Cu")
		(net "GND")
	)
	(via
		(at 56.28005 -176.6316)
		(size 0.508)
		(drill 0.254)
		(layers "F.Cu" "B.Cu")
		(net "GND")
	)
	(via
		(at 74.690478 -191.84112)
		(size 0.7112)
		(drill 0.4064)
		(layers "F.Cu" "B.Cu")
		(net "GND")
	)
	(via
		(at 159.9946 -86.1822)
		(size 0.508)
		(drill 0.254)
		(layers "F.Cu" "B.Cu")
		(net "GND")
	)
	(via
		(at 179.316126 -147.953984)
		(size 0.5588)
		(drill 0.3048)
		(layers "F.Cu" "B.Cu")
		(net "GND")
	)
	(via
		(at 43.41876 -156.0576)
		(size 0.508)
		(drill 0.254)
		(layers "F.Cu" "B.Cu")
		(net "GND")
	)
	(via
		(at 22.0345 -144.16151)
		(size 0.508)
		(drill 0.254)
		(layers "F.Cu" "B.Cu")
		(net "GND")
	)
	(via
		(at 196.000116 -75.499722)
		(size 0.508)
		(drill 0.254)
		(layers "F.Cu" "B.Cu")
		(net "GND")
	)
	(via
		(at 232.841038 -86.283292)
		(size 0.7112)
		(drill 0.4064)
		(layers "F.Cu" "B.Cu")
		(net "GND")
	)
	(via
		(at 93.655134 -133.418834)
		(size 0.508)
		(drill 0.254)
		(layers "F.Cu" "B.Cu")
		(net "GND")
	)
	(via
		(at 101.14915 -184.273952)
		(size 0.7112)
		(drill 0.4064)
		(layers "F.Cu" "B.Cu")
		(net "GND")
	)
	(via
		(at 62.92215 -166.71925)
		(size 0.508)
		(drill 0.254)
		(layers "F.Cu" "B.Cu")
		(net "GND")
	)
	(via
		(at 202.392788 -66.697352)
		(size 0.508)
		(drill 0.254)
		(layers "F.Cu" "B.Cu")
		(net "GND")
	)
	(via
		(at 92.131388 -60.369196)
		(size 0.508)
		(drill 0.254)
		(layers "F.Cu" "B.Cu")
		(net "GND")
	)
	(via
		(at 198.3994 -73.1012)
		(size 0.508)
		(drill 0.254)
		(layers "F.Cu" "B.Cu")
		(net "GND")
	)
	(via
		(at 146.45894 -98.657664)
		(size 0.7112)
		(drill 0.4064)
		(layers "F.Cu" "B.Cu")
		(net "GND")
	)
	(via
		(at 2.159 -82.112866)
		(size 0.7112)
		(drill 0.4064)
		(layers "F.Cu" "B.Cu")
		(net "GND")
	)
	(via
		(at 199.200262 -58.700162)
		(size 0.508)
		(drill 0.254)
		(layers "F.Cu" "B.Cu")
		(net "GND")
	)
	(via
		(at 213.2838 -127.381)
		(size 0.7112)
		(drill 0.4064)
		(layers "F.Cu" "B.Cu")
		(net "GND")
	)
	(via
		(at 62.3062 -161.4678)
		(size 0.508)
		(drill 0.254)
		(layers "F.Cu" "B.Cu")
		(net "GND")
	)
	(via
		(at 188.000386 -71.499984)
		(size 0.508)
		(drill 0.254)
		(layers "F.Cu" "B.Cu")
		(net "GND")
	)
	(via
		(at 7.40791 -135.283448)
		(size 0.508)
		(drill 0.254)
		(layers "F.Cu" "B.Cu")
		(net "GND")
	)
	(via
		(at 196.000116 -65.900046)
		(size 0.508)
		(drill 0.254)
		(layers "F.Cu" "B.Cu")
		(net "GND")
	)
	(via
		(at 86.120478 -191.84112)
		(size 0.7112)
		(drill 0.4064)
		(layers "F.Cu" "B.Cu")
		(net "GND")
	)
	(via
		(at 167.1066 -112.5728)
		(size 0.508)
		(drill 0.254)
		(layers "F.Cu" "B.Cu")
		(net "GND")
	)
	(via
		(at 209.479388 -191.84112)
		(size 0.7112)
		(drill 0.4064)
		(layers "F.Cu" "B.Cu")
		(net "GND")
	)
	(via
		(at 2.159 -69.412866)
		(size 0.7112)
		(drill 0.4064)
		(layers "F.Cu" "B.Cu")
		(net "GND")
	)
	(via
		(at 146.45894 -178.667664)
		(size 0.7112)
		(drill 0.4064)
		(layers "F.Cu" "B.Cu")
		(net "GND")
	)
	(via
		(at 82.7786 -172.339)
		(size 0.508)
		(drill 0.254)
		(layers "F.Cu" "B.Cu")
		(net "GND")
	)
	(via
		(at 2.159 -179.902866)
		(size 0.7112)
		(drill 0.4064)
		(layers "F.Cu" "B.Cu")
		(net "GND")
	)
	(via
		(at 2.159 -42.742866)
		(size 0.7112)
		(drill 0.4064)
		(layers "F.Cu" "B.Cu")
		(net "GND")
	)
	(via
		(at 232.841038 -130.733292)
		(size 0.7112)
		(drill 0.4064)
		(layers "F.Cu" "B.Cu")
		(net "GND")
	)
	(via
		(at 229.410768 -190.192914)
		(size 0.7112)
		(drill 0.4064)
		(layers "F.Cu" "B.Cu")
		(net "GND")
	)
	(via
		(at 189.593982 -67.503294)
		(size 0.508)
		(drill 0.254)
		(layers "F.Cu" "B.Cu")
		(net "GND")
	)
	(via
		(at 187.200286 -71.499984)
		(size 0.508)
		(drill 0.254)
		(layers "F.Cu" "B.Cu")
		(net "GND")
	)
	(via
		(at 49.299622 -141.00048)
		(size 0.4572)
		(drill 0.2032)
		(layers "F.Cu" "B.Cu")
		(net "GND")
	)
	(via
		(at 180.230526 -147.953984)
		(size 0.5588)
		(drill 0.3048)
		(layers "F.Cu" "B.Cu")
		(net "GND")
	)
	(via
		(at 196.000116 -67.500246)
		(size 0.508)
		(drill 0.254)
		(layers "F.Cu" "B.Cu")
		(net "GND")
	)
	(via
		(at 28.498038 -14.073124)
		(size 0.7112)
		(drill 0.4064)
		(layers "F.Cu" "B.Cu")
		(net "GND")
	)
	(via
		(at 81.732628 -54.857396)
		(size 0.508)
		(drill 0.254)
		(layers "F.Cu" "B.Cu")
		(net "GND")
	)
	(via
		(at 48.620172 -129.535174)
		(size 0.508)
		(drill 0.254)
		(layers "F.Cu" "B.Cu")
		(net "GND")
	)
	(via
		(at 146.45894 -131.677664)
		(size 0.7112)
		(drill 0.4064)
		(layers "F.Cu" "B.Cu")
		(net "GND")
	)
	(via
		(at 186.619388 -191.84112)
		(size 0.7112)
		(drill 0.4064)
		(layers "F.Cu" "B.Cu")
		(net "GND")
	)
	(via
		(at 28.970478 -191.84112)
		(size 0.7112)
		(drill 0.4064)
		(layers "F.Cu" "B.Cu")
		(net "GND")
	)
	(via
		(at 190.5254 -2.159)
		(size 0.7112)
		(drill 0.4064)
		(layers "F.Cu" "B.Cu")
		(net "GND")
	)
	(via
		(at 232.841038 -109.143292)
		(size 0.7112)
		(drill 0.4064)
		(layers "F.Cu" "B.Cu")
		(net "GND")
	)
	(via
		(at 2.159 -17.342866)
		(size 0.7112)
		(drill 0.4064)
		(layers "F.Cu" "B.Cu")
		(net "GND")
	)
	(via
		(at 74.4982 -172.6438)
		(size 0.508)
		(drill 0.254)
		(layers "F.Cu" "B.Cu")
		(net "GND")
	)
	(via
		(at 2.159 -99.892866)
		(size 0.7112)
		(drill 0.4064)
		(layers "F.Cu" "B.Cu")
		(net "GND")
	)
	(via
		(at 232.841038 -124.383292)
		(size 0.7112)
		(drill 0.4064)
		(layers "F.Cu" "B.Cu")
		(net "GND")
	)
	(via
		(at 25.2984 -173.609)
		(size 0.7112)
		(drill 0.4064)
		(layers "F.Cu" "B.Cu")
		(net "GND")
	)
	(via
		(at 46.900084 -144.999964)
		(size 0.4572)
		(drill 0.2032)
		(layers "F.Cu" "B.Cu")
		(net "GND")
	)
	(via
		(at 232.841038 -82.473292)
		(size 0.7112)
		(drill 0.4064)
		(layers "F.Cu" "B.Cu")
		(net "GND")
	)
	(via
		(at 91.1606 -157.1752)
		(size 0.5588)
		(drill 0.3048)
		(layers "F.Cu" "B.Cu")
		(net "GND")
	)
	(via
		(at 27.526234 -146.623532)
		(size 0.508)
		(drill 0.254)
		(layers "F.Cu" "B.Cu")
		(net "GND")
	)
	(via
		(at 35.538664 -182.936388)
		(size 0.5588)
		(drill 0.3048)
		(layers "F.Cu" "B.Cu")
		(net "GND")
	)
	(via
		(at 5.7404 -190.7032)
		(size 0.7112)
		(drill 0.4064)
		(layers "F.Cu" "B.Cu")
		(net "GND")
	)
	(via
		(at 196.00037 -60.300108)
		(size 0.508)
		(drill 0.254)
		(layers "F.Cu" "B.Cu")
		(net "GND")
	)
	(via
		(at 189.600078 -57.100216)
		(size 0.508)
		(drill 0.254)
		(layers "F.Cu" "B.Cu")
		(net "GND")
	)
	(via
		(at 2.159 -135.452866)
		(size 0.7112)
		(drill 0.4064)
		(layers "F.Cu" "B.Cu")
		(net "GND")
	)
	(via
		(at 199.98944 -9.0551)
		(size 0.508)
		(drill 0.254)
		(layers "F.Cu" "B.Cu")
		(net "GND")
	)
	(via
		(at 193.600324 -70.700138)
		(size 0.508)
		(drill 0.254)
		(layers "F.Cu" "B.Cu")
		(net "GND")
	)
	(via
		(at 178.999388 -191.84112)
		(size 0.7112)
		(drill 0.4064)
		(layers "F.Cu" "B.Cu")
		(net "GND")
	)
	(via
		(at 187.200032 -67.499738)
		(size 0.508)
		(drill 0.254)
		(layers "F.Cu" "B.Cu")
		(net "GND")
	)
	(via
		(at 183.20004 -69.099938)
		(size 0.508)
		(drill 0.254)
		(layers "F.Cu" "B.Cu")
		(net "GND")
	)
	(via
		(at 195.199 -121.92)
		(size 0.508)
		(drill 0.254)
		(layers "F.Cu" "B.Cu")
		(net "GND")
	)
	(via
		(at 2.159 -37.662866)
		(size 0.7112)
		(drill 0.4064)
		(layers "F.Cu" "B.Cu")
		(net "GND")
	)
	(via
		(at 190.3476 -49.6824)
		(size 0.508)
		(drill 0.254)
		(layers "F.Cu" "B.Cu")
		(net "GND")
	)
	(via
		(at 86.173564 -167.235886)
		(size 0.508)
		(drill 0.254)
		(layers "F.Cu" "B.Cu")
		(net "GND")
	)
	(via
		(at 189.600078 -62.6999)
		(size 0.508)
		(drill 0.254)
		(layers "F.Cu" "B.Cu")
		(net "GND")
	)
	(via
		(at 183.20004 -67.499992)
		(size 0.508)
		(drill 0.254)
		(layers "F.Cu" "B.Cu")
		(net "GND")
	)
	(via
		(at 155.0162 -90.1192)
		(size 0.508)
		(drill 0.254)
		(layers "F.Cu" "B.Cu")
		(net "GND")
	)
	(via
		(at 210.28533 -2.159)
		(size 0.7112)
		(drill 0.4064)
		(layers "F.Cu" "B.Cu")
		(net "GND")
	)
	(via
		(at 178.401726 -147.953984)
		(size 0.5588)
		(drill 0.3048)
		(layers "F.Cu" "B.Cu")
		(net "GND")
	)
	(via
		(at 224.25533 -2.159)
		(size 0.7112)
		(drill 0.4064)
		(layers "F.Cu" "B.Cu")
		(net "GND")
	)
	(via
		(at 73.84288 -179.10048)
		(size 0.5588)
		(drill 0.3048)
		(layers "F.Cu" "B.Cu")
		(net "GND")
	)
	(via
		(at 188.000132 -68.299838)
		(size 0.508)
		(drill 0.254)
		(layers "F.Cu" "B.Cu")
		(net "GND")
	)
	(via
		(at 232.841038 -107.873292)
		(size 0.7112)
		(drill 0.4064)
		(layers "F.Cu" "B.Cu")
		(net "GND")
	)
	(via
		(at 2.159 -68.142866)
		(size 0.7112)
		(drill 0.4064)
		(layers "F.Cu" "B.Cu")
		(net "GND")
	)
	(via
		(at 48.006 -167.6146)
		(size 0.508)
		(drill 0.254)
		(layers "F.Cu" "B.Cu")
		(net "GND")
	)
	(via
		(at 126.1618 -8.1534)
		(size 0.508)
		(drill 0.254)
		(layers "F.Cu" "B.Cu")
		(net "GND")
	)
	(via
		(at 186.399932 -65.099946)
		(size 0.508)
		(drill 0.254)
		(layers "F.Cu" "B.Cu")
		(net "GND")
	)
	(via
		(at 2.159 -167.202866)
		(size 0.7112)
		(drill 0.4064)
		(layers "F.Cu" "B.Cu")
		(net "GND")
	)
	(via
		(at 82.663538 -136.171686)
		(size 0.508)
		(drill 0.254)
		(layers "F.Cu" "B.Cu")
		(net "GND")
	)
	(via
		(at 2.159 -41.472866)
		(size 0.7112)
		(drill 0.4064)
		(layers "F.Cu" "B.Cu")
		(net "GND")
	)
	(via
		(at 2.159 -85.922866)
		(size 0.7112)
		(drill 0.4064)
		(layers "F.Cu" "B.Cu")
		(net "GND")
	)
	(via
		(at 230.60533 -2.159)
		(size 0.7112)
		(drill 0.4064)
		(layers "F.Cu" "B.Cu")
		(net "GND")
	)
	(via
		(at 95.25 -27.2542)
		(size 0.508)
		(drill 0.254)
		(layers "F.Cu" "B.Cu")
		(net "GND")
	)
	(via
		(at 67.709034 -154.589226)
		(size 0.508)
		(drill 0.254)
		(layers "F.Cu" "B.Cu")
		(net "GND")
	)
	(via
		(at 52.499768 -150.599902)
		(size 0.4572)
		(drill 0.2032)
		(layers "F.Cu" "B.Cu")
		(net "GND")
	)
	(via
		(at 166.299388 -191.84112)
		(size 0.7112)
		(drill 0.4064)
		(layers "F.Cu" "B.Cu")
		(net "GND")
	)
	(via
		(at 195.6562 -102.9716)
		(size 0.7112)
		(drill 0.4064)
		(layers "F.Cu" "B.Cu")
		(net "GND")
	)
	(via
		(at 58.180478 -191.84112)
		(size 0.7112)
		(drill 0.4064)
		(layers "F.Cu" "B.Cu")
		(net "GND")
	)
	(via
		(at 231.1908 -186.7662)
		(size 0.7112)
		(drill 0.4064)
		(layers "F.Cu" "B.Cu")
		(net "GND")
	)
	(via
		(at 25.075134 -2.159)
		(size 0.7112)
		(drill 0.4064)
		(layers "F.Cu" "B.Cu")
		(net "GND")
	)
	(via
		(at 166.37 -177.8508)
		(size 0.7112)
		(drill 0.4064)
		(layers "F.Cu" "B.Cu")
		(net "GND")
	)
	(via
		(at 48.50003 -144.999964)
		(size 0.4572)
		(drill 0.2032)
		(layers "F.Cu" "B.Cu")
		(net "GND")
	)
	(via
		(at 58.6486 -147.7264)
		(size 0.508)
		(drill 0.254)
		(layers "F.Cu" "B.Cu")
		(net "GND")
	)
	(via
		(at 2.159 -124.022866)
		(size 0.7112)
		(drill 0.4064)
		(layers "F.Cu" "B.Cu")
		(net "GND")
	)
	(via
		(at 185.60034 -61.900308)
		(size 0.508)
		(drill 0.254)
		(layers "F.Cu" "B.Cu")
		(net "GND")
	)
	(via
		(at 7.310628 -141.000226)
		(size 0.508)
		(drill 0.254)
		(layers "F.Cu" "B.Cu")
		(net "GND")
	)
	(via
		(at 154.686 -121.539)
		(size 0.7112)
		(drill 0.4064)
		(layers "F.Cu" "B.Cu")
		(net "GND")
	)
	(via
		(at 198.808086 -136.573514)
		(size 0.508)
		(drill 0.254)
		(layers "F.Cu" "B.Cu")
		(net "GND")
	)
	(via
		(at 77.596492 -54.311296)
		(size 0.508)
		(drill 0.254)
		(layers "F.Cu" "B.Cu")
		(net "GND")
	)
	(via
		(at 15.5194 -138.8618)
		(size 0.508)
		(drill 0.254)
		(layers "F.Cu" "B.Cu")
		(net "GND")
	)
	(via
		(at 198.1962 -78.5622)
		(size 0.508)
		(drill 0.254)
		(layers "F.Cu" "B.Cu")
		(net "GND")
	)
	(via
		(at 28.498038 -108.053124)
		(size 0.7112)
		(drill 0.4064)
		(layers "F.Cu" "B.Cu")
		(net "GND")
	)
	(via
		(at 232.841038 -96.443292)
		(size 0.7112)
		(drill 0.4064)
		(layers "F.Cu" "B.Cu")
		(net "GND")
	)
	(via
		(at 70.752462 -187.96508)
		(size 0.508)
		(drill 0.254)
		(layers "F.Cu" "B.Cu")
		(net "GND")
	)
	(via
		(at 2.159 -78.302866)
		(size 0.7112)
		(drill 0.4064)
		(layers "F.Cu" "B.Cu")
		(net "GND")
	)
	(via
		(at 2.159 -117.672866)
		(size 0.7112)
		(drill 0.4064)
		(layers "F.Cu" "B.Cu")
		(net "GND")
	)
	(via
		(at 88.412828 -47.300896)
		(size 0.508)
		(drill 0.254)
		(layers "F.Cu" "B.Cu")
		(net "GND")
	)
	(via
		(at 225.52533 -2.159)
		(size 0.7112)
		(drill 0.4064)
		(layers "F.Cu" "B.Cu")
		(net "GND")
	)
	(via
		(at 232.841038 -177.723292)
		(size 0.7112)
		(drill 0.4064)
		(layers "F.Cu" "B.Cu")
		(net "GND")
	)
	(via
		(at 232.841038 -77.393292)
		(size 0.7112)
		(drill 0.4064)
		(layers "F.Cu" "B.Cu")
		(net "GND")
	)
	(via
		(at 55.9054 -130.4036)
		(size 0.508)
		(drill 0.254)
		(layers "F.Cu" "B.Cu")
		(net "GND")
	)
	(via
		(at 2.159 -56.712866)
		(size 0.7112)
		(drill 0.4064)
		(layers "F.Cu" "B.Cu")
		(net "GND")
	)
	(via
		(at 17.9832 -167.8178)
		(size 0.5588)
		(drill 0.3048)
		(layers "F.Cu" "B.Cu")
		(net "GND")
	)
	(via
		(at 190.399924 -59.500262)
		(size 0.508)
		(drill 0.254)
		(layers "F.Cu" "B.Cu")
		(net "GND")
	)
	(via
		(at 184.80024 -62.700154)
		(size 0.508)
		(drill 0.254)
		(layers "F.Cu" "B.Cu")
		(net "GND")
	)
	(via
		(at 25.160478 -191.84112)
		(size 0.7112)
		(drill 0.4064)
		(layers "F.Cu" "B.Cu")
		(net "GND")
	)
	(via
		(at 74.490834 -141.540992)
		(size 0.508)
		(drill 0.254)
		(layers "F.Cu" "B.Cu")
		(net "GND")
	)
	(via
		(at 2.159 -73.222866)
		(size 0.7112)
		(drill 0.4064)
		(layers "F.Cu" "B.Cu")
		(net "GND")
	)
	(via
		(at 28.498038 -64.873124)
		(size 0.7112)
		(drill 0.4064)
		(layers "F.Cu" "B.Cu")
		(net "GND")
	)
	(via
		(at 2.159 -131.642866)
		(size 0.7112)
		(drill 0.4064)
		(layers "F.Cu" "B.Cu")
		(net "GND")
	)
	(via
		(at 96.936052 -191.84112)
		(size 0.7112)
		(drill 0.4064)
		(layers "F.Cu" "B.Cu")
		(net "GND")
	)
	(via
		(at 232.841038 -55.803292)
		(size 0.7112)
		(drill 0.4064)
		(layers "F.Cu" "B.Cu")
		(net "GND")
	)
	(via
		(at 232.841038 -45.643292)
		(size 0.7112)
		(drill 0.4064)
		(layers "F.Cu" "B.Cu")
		(net "GND")
	)
	(via
		(at 69.977 -118.4148)
		(size 0.508)
		(drill 0.254)
		(layers "F.Cu" "B.Cu")
		(net "GND")
	)
	(via
		(at 28.498038 -52.173124)
		(size 0.7112)
		(drill 0.4064)
		(layers "F.Cu" "B.Cu")
		(net "GND")
	)
	(via
		(at 44.210478 -191.84112)
		(size 0.7112)
		(drill 0.4064)
		(layers "F.Cu" "B.Cu")
		(net "GND")
	)
	(via
		(at 232.841038 -126.923292)
		(size 0.7112)
		(drill 0.4064)
		(layers "F.Cu" "B.Cu")
		(net "GND")
	)
	(via
		(at 178.67376 -139.40028)
		(size 0.508)
		(drill 0.254)
		(layers "F.Cu" "B.Cu")
		(net "GND")
	)
	(via
		(at 232.841038 -64.693292)
		(size 0.7112)
		(drill 0.4064)
		(layers "F.Cu" "B.Cu")
		(net "GND")
	)
	(via
		(at 91.007184 -170.80484)
		(size 0.508)
		(drill 0.254)
		(layers "F.Cu" "B.Cu")
		(net "GND")
	)
	(via
		(at 38.38702 -178.67376)
		(size 0.508)
		(drill 0.254)
		(layers "F.Cu" "B.Cu")
		(net "GND")
	)
	(via
		(at 17.234662 -145.76171)
		(size 0.508)
		(drill 0.254)
		(layers "F.Cu" "B.Cu")
		(net "GND")
	)
	(via
		(at 163.9062 -167.64)
		(size 0.7112)
		(drill 0.4064)
		(layers "F.Cu" "B.Cu")
		(net "GND")
	)
	(via
		(at 146.45894 -174.857664)
		(size 0.7112)
		(drill 0.4064)
		(layers "F.Cu" "B.Cu")
		(net "GND")
	)
	(via
		(at 2.159 -57.982866)
		(size 0.7112)
		(drill 0.4064)
		(layers "F.Cu" "B.Cu")
		(net "GND")
	)
	(via
		(at 232.841038 -38.023292)
		(size 0.7112)
		(drill 0.4064)
		(layers "F.Cu" "B.Cu")
		(net "GND")
	)
	(via
		(at 215.36533 -2.159)
		(size 0.7112)
		(drill 0.4064)
		(layers "F.Cu" "B.Cu")
		(net "GND")
	)
	(via
		(at 186.400186 -59.500262)
		(size 0.508)
		(drill 0.254)
		(layers "F.Cu" "B.Cu")
		(net "GND")
	)
	(via
		(at 23.805134 -2.159)
		(size 0.7112)
		(drill 0.4064)
		(layers "F.Cu" "B.Cu")
		(net "GND")
	)
	(via
		(at 146.45894 -157.077664)
		(size 0.7112)
		(drill 0.4064)
		(layers "F.Cu" "B.Cu")
		(net "GND")
	)
	(via
		(at 198.0946 -102.9716)
		(size 0.7112)
		(drill 0.4064)
		(layers "F.Cu" "B.Cu")
		(net "GND")
	)
	(via
		(at 207.0354 -126.9492)
		(size 0.5588)
		(drill 0.3048)
		(layers "F.Cu" "B.Cu")
		(net "GND")
	)
	(via
		(at 98.30943 -189.953646)
		(size 0.7112)
		(drill 0.4064)
		(layers "F.Cu" "B.Cu")
		(net "GND")
	)
	(via
		(at 71.4756 -179.8828)
		(size 0.508)
		(drill 0.254)
		(layers "F.Cu" "B.Cu")
		(net "GND")
	)
	(via
		(at 194.399916 -56.300116)
		(size 0.508)
		(drill 0.254)
		(layers "F.Cu" "B.Cu")
		(net "GND")
	)
	(via
		(at 194.40017 -57.100216)
		(size 0.508)
		(drill 0.254)
		(layers "F.Cu" "B.Cu")
		(net "GND")
	)
	(via
		(at 205.1304 -116.6622)
		(size 0.7112)
		(drill 0.4064)
		(layers "F.Cu" "B.Cu")
		(net "GND")
	)
	(via
		(at 124.4727 -11.6586)
		(size 0.508)
		(drill 0.254)
		(layers "F.Cu" "B.Cu")
		(net "GND")
	)
	(via
		(at 146.45894 -105.007664)
		(size 0.7112)
		(drill 0.4064)
		(layers "F.Cu" "B.Cu")
		(net "GND")
	)
	(via
		(at 207.74533 -2.159)
		(size 0.7112)
		(drill 0.4064)
		(layers "F.Cu" "B.Cu")
		(net "GND")
	)
	(via
		(at 81.896204 -57.792874)
		(size 0.508)
		(drill 0.254)
		(layers "F.Cu" "B.Cu")
		(net "GND")
	)
	(via
		(at 186.812936 -110.281212)
		(size 0.7112)
		(drill 0.4064)
		(layers "F.Cu" "B.Cu")
		(net "GND")
	)
	(via
		(at 232.841038 -88.823292)
		(size 0.7112)
		(drill 0.4064)
		(layers "F.Cu" "B.Cu")
		(net "GND")
	)
	(via
		(at 187.200286 -60.2996)
		(size 0.508)
		(drill 0.254)
		(layers "F.Cu" "B.Cu")
		(net "GND")
	)
	(via
		(at 80.8736 -172.3136)
		(size 0.508)
		(drill 0.254)
		(layers "F.Cu" "B.Cu")
		(net "GND")
	)
	(via
		(at 16.3576 -136.906)
		(size 0.508)
		(drill 0.254)
		(layers "F.Cu" "B.Cu")
		(net "GND")
	)
	(via
		(at 72.150478 -191.84112)
		(size 0.7112)
		(drill 0.4064)
		(layers "F.Cu" "B.Cu")
		(net "GND")
	)
	(via
		(at 232.841038 -101.523292)
		(size 0.7112)
		(drill 0.4064)
		(layers "F.Cu" "B.Cu")
		(net "GND")
	)
	(via
		(at 63.1063 -154.9146)
		(size 0.508)
		(drill 0.254)
		(layers "F.Cu" "B.Cu")
		(net "GND")
	)
	(via
		(at 179.246784 -145.440146)
		(size 0.5588)
		(drill 0.3048)
		(layers "F.Cu" "B.Cu")
		(net "GND")
	)
	(via
		(at 205.7908 -125.7046)
		(size 0.5588)
		(drill 0.3048)
		(layers "F.Cu" "B.Cu")
		(net "GND")
	)
	(via
		(at 66.356992 -177.821844)
		(size 0.508)
		(drill 0.254)
		(layers "F.Cu" "B.Cu")
		(net "GND")
	)
	(via
		(at 191.200278 -61.100208)
		(size 0.508)
		(drill 0.254)
		(layers "F.Cu" "B.Cu")
		(net "GND")
	)
	(via
		(at 177.938684 -146.710146)
		(size 0.5588)
		(drill 0.3048)
		(layers "F.Cu" "B.Cu")
		(net "GND")
	)
	(via
		(at 232.841038 -59.613292)
		(size 0.7112)
		(drill 0.4064)
		(layers "F.Cu" "B.Cu")
		(net "GND")
	)
	(via
		(at 232.841038 -149.783292)
		(size 0.7112)
		(drill 0.4064)
		(layers "F.Cu" "B.Cu")
		(net "GND")
	)
	(via
		(at 2.159 -104.972866)
		(size 0.7112)
		(drill 0.4064)
		(layers "F.Cu" "B.Cu")
		(net "GND")
	)
	(via
		(at 146.45894 -127.867664)
		(size 0.7112)
		(drill 0.4064)
		(layers "F.Cu" "B.Cu")
		(net "GND")
	)
	(via
		(at 186.399932 -63.499746)
		(size 0.508)
		(drill 0.254)
		(layers "F.Cu" "B.Cu")
		(net "GND")
	)
	(via
		(at 148.845778 -188.264292)
		(size 0.7112)
		(drill 0.4064)
		(layers "F.Cu" "B.Cu")
		(net "GND")
	)
	(via
		(at 28.498038 -28.043124)
		(size 0.7112)
		(drill 0.4064)
		(layers "F.Cu" "B.Cu")
		(net "GND")
	)
	(via
		(at 77.837284 -62.959996)
		(size 0.508)
		(drill 0.254)
		(layers "F.Cu" "B.Cu")
		(net "GND")
	)
	(via
		(at 9.56564 -143.8656)
		(size 0.508)
		(drill 0.254)
		(layers "F.Cu" "B.Cu")
		(net "GND")
	)
	(via
		(at 71.6026 -162.7886)
		(size 0.508)
		(drill 0.254)
		(layers "F.Cu" "B.Cu")
		(net "GND")
	)
	(via
		(at 210.8454 -127.381)
		(size 0.7112)
		(drill 0.4064)
		(layers "F.Cu" "B.Cu")
		(net "GND")
	)
	(via
		(at 43.700192 -149.800056)
		(size 0.4572)
		(drill 0.2032)
		(layers "F.Cu" "B.Cu")
		(net "GND")
	)
	(via
		(at 48.499776 -145.800064)
		(size 0.4572)
		(drill 0.2032)
		(layers "F.Cu" "B.Cu")
		(net "GND")
	)
	(via
		(at 31.7754 -166.8018)
		(size 0.508)
		(drill 0.254)
		(layers "F.Cu" "B.Cu")
		(net "GND")
	)
	(via
		(at 28.498038 -55.983124)
		(size 0.7112)
		(drill 0.4064)
		(layers "F.Cu" "B.Cu")
		(net "GND")
	)
	(via
		(at 127.71882 -4.748022)
		(size 0.508)
		(drill 0.254)
		(layers "F.Cu" "B.Cu")
		(net "GND")
	)
	(via
		(at 146.45894 -164.697664)
		(size 0.7112)
		(drill 0.4064)
		(layers "F.Cu" "B.Cu")
		(net "GND")
	)
	(via
		(at 67.781678 -161.123122)
		(size 0.508)
		(drill 0.254)
		(layers "F.Cu" "B.Cu")
		(net "GND")
	)
	(via
		(at 2.159 -102.432866)
		(size 0.7112)
		(drill 0.4064)
		(layers "F.Cu" "B.Cu")
		(net "GND")
	)
	(via
		(at 232.841038 -171.373292)
		(size 0.7112)
		(drill 0.4064)
		(layers "F.Cu" "B.Cu")
		(net "GND")
	)
	(via
		(at 28.498038 -19.153124)
		(size 0.7112)
		(drill 0.4064)
		(layers "F.Cu" "B.Cu")
		(net "GND")
	)
	(via
		(at 189.600078 -69.900038)
		(size 0.508)
		(drill 0.254)
		(layers "F.Cu" "B.Cu")
		(net "GND")
	)
	(via
		(at 67.779138 -159.068262)
		(size 0.508)
		(drill 0.254)
		(layers "F.Cu" "B.Cu")
		(net "GND")
	)
	(via
		(at 13.645134 -2.159)
		(size 0.7112)
		(drill 0.4064)
		(layers "F.Cu" "B.Cu")
		(net "GND")
	)
	(via
		(at 210.312 -116.6622)
		(size 0.7112)
		(drill 0.4064)
		(layers "F.Cu" "B.Cu")
		(net "GND")
	)
	(via
		(at 162.17138 -41.77538)
		(size 0.508)
		(drill 0.254)
		(layers "F.Cu" "B.Cu")
		(net "GND")
	)
	(via
		(at 2.159 -18.612866)
		(size 0.7112)
		(drill 0.4064)
		(layers "F.Cu" "B.Cu")
		(net "GND")
	)
	(via
		(at 197.600062 -70.700138)
		(size 0.508)
		(drill 0.254)
		(layers "F.Cu" "B.Cu")
		(net "GND")
	)
	(via
		(at 178.963066 -65.573656)
		(size 0.508)
		(drill 0.254)
		(layers "F.Cu" "B.Cu")
		(net "GND")
	)
	(via
		(at 35.538664 -180.193188)
		(size 0.5588)
		(drill 0.3048)
		(layers "F.Cu" "B.Cu")
		(net "GND")
	)
	(via
		(at 219.640658 -101.208332)
		(size 0.7112)
		(drill 0.4064)
		(layers "F.Cu" "B.Cu")
		(net "GND")
	)
	(via
		(at 146.45894 -136.757664)
		(size 0.7112)
		(drill 0.4064)
		(layers "F.Cu" "B.Cu")
		(net "GND")
	)
	(via
		(at 200.004426 -70.701916)
		(size 0.508)
		(drill 0.254)
		(layers "F.Cu" "B.Cu")
		(net "GND")
	)
	(via
		(at 232.841038 -69.773292)
		(size 0.7112)
		(drill 0.4064)
		(layers "F.Cu" "B.Cu")
		(net "GND")
	)
	(via
		(at 232.841038 -158.673292)
		(size 0.7112)
		(drill 0.4064)
		(layers "F.Cu" "B.Cu")
		(net "GND")
	)
	(via
		(at 22.620478 -191.84112)
		(size 0.7112)
		(drill 0.4064)
		(layers "F.Cu" "B.Cu")
		(net "GND")
	)
	(via
		(at 180.161184 -145.440146)
		(size 0.5588)
		(drill 0.3048)
		(layers "F.Cu" "B.Cu")
		(net "GND")
	)
	(via
		(at 208.209388 -191.84112)
		(size 0.7112)
		(drill 0.4064)
		(layers "F.Cu" "B.Cu")
		(net "GND")
	)
	(via
		(at 206.3496 -116.6622)
		(size 0.7112)
		(drill 0.4064)
		(layers "F.Cu" "B.Cu")
		(net "GND")
	)
	(via
		(at 18.725134 -2.159)
		(size 0.7112)
		(drill 0.4064)
		(layers "F.Cu" "B.Cu")
		(net "GND")
	)
	(via
		(at 88.5444 -163.449)
		(size 0.508)
		(drill 0.254)
		(layers "F.Cu" "B.Cu")
		(net "GND")
	)
	(via
		(at 232.841038 -27.863292)
		(size 0.7112)
		(drill 0.4064)
		(layers "F.Cu" "B.Cu")
		(net "GND")
	)
	(via
		(at 203.199746 -72.29983)
		(size 0.508)
		(drill 0.254)
		(layers "F.Cu" "B.Cu")
		(net "GND")
	)
	(via
		(at 33.024826 -183.92013)
		(size 0.5588)
		(drill 0.3048)
		(layers "F.Cu" "B.Cu")
		(net "GND")
	)
	(via
		(at 193.600324 -69.900038)
		(size 0.508)
		(drill 0.254)
		(layers "F.Cu" "B.Cu")
		(net "GND")
	)
	(via
		(at 232.841038 -132.003292)
		(size 0.7112)
		(drill 0.4064)
		(layers "F.Cu" "B.Cu")
		(net "GND")
	)
	(via
		(at 225.1202 -56.1721)
		(size 0.508)
		(drill 0.254)
		(layers "F.Cu" "B.Cu")
		(net "GND")
	)
	(via
		(at 232.841038 -7.543292)
		(size 0.7112)
		(drill 0.4064)
		(layers "F.Cu" "B.Cu")
		(net "GND")
	)
	(via
		(at 77.796644 -160.9471)
		(size 0.5588)
		(drill 0.3048)
		(layers "F.Cu" "B.Cu")
		(net "GND")
	)
	(via
		(at 205.583536 -123.185936)
		(size 0.508)
		(drill 0.254)
		(layers "F.Cu" "B.Cu")
		(net "GND")
	)
	(via
		(at 2.159 -52.902866)
		(size 0.7112)
		(drill 0.4064)
		(layers "F.Cu" "B.Cu")
		(net "GND")
	)
	(via
		(at 194.40017 -57.900062)
		(size 0.508)
		(drill 0.254)
		(layers "F.Cu" "B.Cu")
		(net "GND")
	)
	(via
		(at 53.7718 -130.429)
		(size 0.508)
		(drill 0.254)
		(layers "F.Cu" "B.Cu")
		(net "GND")
	)
	(via
		(at 232.841038 -74.853292)
		(size 0.7112)
		(drill 0.4064)
		(layers "F.Cu" "B.Cu")
		(net "GND")
	)
	(via
		(at 97.536 -7.62)
		(size 0.508)
		(drill 0.254)
		(layers "F.Cu" "B.Cu")
		(net "GND")
	)
	(via
		(at 2.159 -38.932866)
		(size 0.7112)
		(drill 0.4064)
		(layers "F.Cu" "B.Cu")
		(net "GND")
	)
	(via
		(at 65.024254 -155.536138)
		(size 0.508)
		(drill 0.254)
		(layers "F.Cu" "B.Cu")
		(net "GND")
	)
	(via
		(at 232.841038 -36.753292)
		(size 0.7112)
		(drill 0.4064)
		(layers "F.Cu" "B.Cu")
		(net "GND")
	)
	(via
		(at 232.841038 -161.213292)
		(size 0.7112)
		(drill 0.4064)
		(layers "F.Cu" "B.Cu")
		(net "GND")
	)
	(via
		(at 2.159 -149.422866)
		(size 0.7112)
		(drill 0.4064)
		(layers "F.Cu" "B.Cu")
		(net "GND")
	)
	(via
		(at 50.899822 -149.800056)
		(size 0.4572)
		(drill 0.2032)
		(layers "F.Cu" "B.Cu")
		(net "GND")
	)
	(via
		(at 2.159 -103.702866)
		(size 0.7112)
		(drill 0.4064)
		(layers "F.Cu" "B.Cu")
		(net "GND")
	)
	(via
		(at 178.181 -63.643256)
		(size 0.508)
		(drill 0.254)
		(layers "F.Cu" "B.Cu")
		(net "GND")
	)
	(via
		(at 166.7256 -131.445)
		(size 0.7112)
		(drill 0.4064)
		(layers "F.Cu" "B.Cu")
		(net "GND")
	)
	(via
		(at 49.2506 -179.06619)
		(size 0.7112)
		(drill 0.4064)
		(layers "F.Cu" "B.Cu")
		(net "GND")
	)
	(via
		(at 83.8708 -180.1622)
		(size 0.7112)
		(drill 0.4064)
		(layers "F.Cu" "B.Cu")
		(net "GND")
	)
	(via
		(at 189.600078 -65.900046)
		(size 0.508)
		(drill 0.254)
		(layers "F.Cu" "B.Cu")
		(net "GND")
	)
	(via
		(at 2.159 -71.952866)
		(size 0.7112)
		(drill 0.4064)
		(layers "F.Cu" "B.Cu")
		(net "GND")
	)
	(via
		(at 28.498038 -26.773124)
		(size 0.7112)
		(drill 0.4064)
		(layers "F.Cu" "B.Cu")
		(net "GND")
	)
	(via
		(at 196.8754 -102.9716)
		(size 0.7112)
		(drill 0.4064)
		(layers "F.Cu" "B.Cu")
		(net "GND")
	)
	(via
		(at 78.77048 -2.159)
		(size 0.7112)
		(drill 0.4064)
		(layers "F.Cu" "B.Cu")
		(net "GND")
	)
	(via
		(at 101.653848 -39.301928)
		(size 0.508)
		(drill 0.254)
		(layers "F.Cu" "B.Cu")
		(net "GND")
	)
	(via
		(at 23.2918 -189.1792)
		(size 0.7112)
		(drill 0.4064)
		(layers "F.Cu" "B.Cu")
		(net "GND")
	)
	(via
		(at 184.799986 -67.499992)
		(size 0.508)
		(drill 0.254)
		(layers "F.Cu" "B.Cu")
		(net "GND")
	)
	(via
		(at 183.200294 -61.099954)
		(size 0.508)
		(drill 0.254)
		(layers "F.Cu" "B.Cu")
		(net "GND")
	)
	(via
		(at 99.75088 -177.165)
		(size 0.508)
		(drill 0.254)
		(layers "F.Cu" "B.Cu")
		(net "GND")
	)
	(via
		(at 81.1784 -170.2943)
		(size 0.508)
		(drill 0.254)
		(layers "F.Cu" "B.Cu")
		(net "GND")
	)
	(via
		(at 205.3336 -53.5432)
		(size 0.508)
		(drill 0.254)
		(layers "F.Cu" "B.Cu")
		(net "GND")
	)
	(via
		(at 71.501 -180.8988)
		(size 0.508)
		(drill 0.254)
		(layers "F.Cu" "B.Cu")
		(net "GND")
	)
	(via
		(at 166.28618 -99.439476)
		(size 0.508)
		(drill 0.254)
		(layers "F.Cu" "B.Cu")
		(net "GND")
	)
	(via
		(at 232.841038 -90.093292)
		(size 0.7112)
		(drill 0.4064)
		(layers "F.Cu" "B.Cu")
		(net "GND")
	)
	(via
		(at 194.437 -102.9716)
		(size 0.7112)
		(drill 0.4064)
		(layers "F.Cu" "B.Cu")
		(net "GND")
	)
	(via
		(at 42.900092 -144.999964)
		(size 0.4572)
		(drill 0.2032)
		(layers "F.Cu" "B.Cu")
		(net "GND")
	)
	(via
		(at 190.39967 -73.899776)
		(size 0.508)
		(drill 0.254)
		(layers "F.Cu" "B.Cu")
		(net "GND")
	)
	(via
		(at 190.399924 -58.700162)
		(size 0.508)
		(drill 0.254)
		(layers "F.Cu" "B.Cu")
		(net "GND")
	)
	(via
		(at 79.092044 -160.8963)
		(size 0.5588)
		(drill 0.3048)
		(layers "F.Cu" "B.Cu")
		(net "GND")
	)
	(via
		(at 232.841038 -125.653292)
		(size 0.7112)
		(drill 0.4064)
		(layers "F.Cu" "B.Cu")
		(net "GND")
	)
	(via
		(at 76.33208 -180.34508)
		(size 0.5588)
		(drill 0.3048)
		(layers "F.Cu" "B.Cu")
		(net "GND")
	)
	(via
		(at 195.509388 -191.84112)
		(size 0.7112)
		(drill 0.4064)
		(layers "F.Cu" "B.Cu")
		(net "GND")
	)
	(via
		(at 18.034508 -146.561302)
		(size 0.508)
		(drill 0.254)
		(layers "F.Cu" "B.Cu")
		(net "GND")
	)
	(via
		(at 232.841038 -8.813292)
		(size 0.7112)
		(drill 0.4064)
		(layers "F.Cu" "B.Cu")
		(net "GND")
	)
	(via
		(at 12.56284 -16.17726)
		(size 0.508)
		(drill 0.254)
		(layers "F.Cu" "B.Cu")
		(net "GND")
	)
	(via
		(at 232.841038 -115.493292)
		(size 0.7112)
		(drill 0.4064)
		(layers "F.Cu" "B.Cu")
		(net "GND")
	)
	(via
		(at 7.380732 -136.709912)
		(size 0.508)
		(drill 0.254)
		(layers "F.Cu" "B.Cu")
		(net "GND")
	)
	(via
		(at 34.293048 -129.5908)
		(size 0.508)
		(drill 0.254)
		(layers "F.Cu" "B.Cu")
		(net "GND")
	)
	(via
		(at 97.3582 -152.5524)
		(size 0.508)
		(drill 0.254)
		(layers "F.Cu" "B.Cu")
		(net "GND")
	)
	(via
		(at 80.43672 -148.215858)
		(size 0.508)
		(drill 0.254)
		(layers "F.Cu" "B.Cu")
		(net "GND")
	)
	(via
		(at 232.841038 -76.123292)
		(size 0.7112)
		(drill 0.4064)
		(layers "F.Cu" "B.Cu")
		(net "GND")
	)
	(via
		(at 2.159 -159.582866)
		(size 0.7112)
		(drill 0.4064)
		(layers "F.Cu" "B.Cu")
		(net "GND")
	)
	(via
		(at 226.682046 -61.277246)
		(size 0.508)
		(drill 0.254)
		(layers "F.Cu" "B.Cu")
		(net "GND")
	)
	(via
		(at 81.896204 -56.827674)
		(size 0.508)
		(drill 0.254)
		(layers "F.Cu" "B.Cu")
		(net "GND")
	)
	(via
		(at 28.498038 -63.603124)
		(size 0.7112)
		(drill 0.4064)
		(layers "F.Cu" "B.Cu")
		(net "GND")
	)
	(via
		(at 91.998038 -56.405272)
		(size 0.508)
		(drill 0.254)
		(layers "F.Cu" "B.Cu")
		(net "GND")
	)
	(via
		(at 2.159 -55.442866)
		(size 0.7112)
		(drill 0.4064)
		(layers "F.Cu" "B.Cu")
		(net "GND")
	)
	(via
		(at 2.159 -126.562866)
		(size 0.7112)
		(drill 0.4064)
		(layers "F.Cu" "B.Cu")
		(net "GND")
	)
	(via
		(at 229.997 -189.0776)
		(size 0.7112)
		(drill 0.4064)
		(layers "F.Cu" "B.Cu")
		(net "GND")
	)
	(via
		(at 232.841038 -167.563292)
		(size 0.7112)
		(drill 0.4064)
		(layers "F.Cu" "B.Cu")
		(net "GND")
	)
	(via
		(at 28.498038 -69.953124)
		(size 0.7112)
		(drill 0.4064)
		(layers "F.Cu" "B.Cu")
		(net "GND")
	)
	(via
		(at 101.689154 -42.06367)
		(size 0.508)
		(drill 0.254)
		(layers "F.Cu" "B.Cu")
		(net "GND")
	)
	(via
		(at 168.839388 -191.84112)
		(size 0.7112)
		(drill 0.4064)
		(layers "F.Cu" "B.Cu")
		(net "GND")
	)
	(via
		(at 186.399932 -61.8998)
		(size 0.508)
		(drill 0.254)
		(layers "F.Cu" "B.Cu")
		(net "GND")
	)
	(via
		(at 17.234408 -148.961602)
		(size 0.508)
		(drill 0.254)
		(layers "F.Cu" "B.Cu")
		(net "GND")
	)
	(via
		(at 146.45894 -132.947664)
		(size 0.7112)
		(drill 0.4064)
		(layers "F.Cu" "B.Cu")
		(net "GND")
	)
	(via
		(at 189.600078 -59.500262)
		(size 0.508)
		(drill 0.254)
		(layers "F.Cu" "B.Cu")
		(net "GND")
	)
	(via
		(at 138.5062 -19.2024)
		(size 0.508)
		(drill 0.254)
		(layers "F.Cu" "B.Cu")
		(net "GND")
	)
	(via
		(at 146.45894 -134.217664)
		(size 0.7112)
		(drill 0.4064)
		(layers "F.Cu" "B.Cu")
		(net "GND")
	)
	(via
		(at 2.159 -65.602866)
		(size 0.7112)
		(drill 0.4064)
		(layers "F.Cu" "B.Cu")
		(net "GND")
	)
	(via
		(at 18.810478 -191.84112)
		(size 0.7112)
		(drill 0.4064)
		(layers "F.Cu" "B.Cu")
		(net "GND")
	)
	(via
		(at 189.76975 -122.916696)
		(size 0.508)
		(drill 0.254)
		(layers "F.Cu" "B.Cu")
		(net "GND")
	)
	(via
		(at 17.9578 -170.434)
		(size 0.5588)
		(drill 0.3048)
		(layers "F.Cu" "B.Cu")
		(net "GND")
	)
	(via
		(at 69.7992 -161.29)
		(size 0.508)
		(drill 0.254)
		(layers "F.Cu" "B.Cu")
		(net "GND")
	)
	(via
		(at 187.200286 -57.900062)
		(size 0.508)
		(drill 0.254)
		(layers "F.Cu" "B.Cu")
		(net "GND")
	)
	(via
		(at 232.841038 -26.593292)
		(size 0.7112)
		(drill 0.4064)
		(layers "F.Cu" "B.Cu")
		(net "GND")
	)
	(via
		(at 91.1352 -154.0002)
		(size 0.5588)
		(drill 0.3048)
		(layers "F.Cu" "B.Cu")
		(net "GND")
	)
	(via
		(at 73.79208 -181.64048)
		(size 0.5588)
		(drill 0.3048)
		(layers "F.Cu" "B.Cu")
		(net "GND")
	)
	(via
		(at 194.400424 -70.700138)
		(size 0.508)
		(drill 0.254)
		(layers "F.Cu" "B.Cu")
		(net "GND")
	)
	(via
		(at 232.841038 -50.723292)
		(size 0.7112)
		(drill 0.4064)
		(layers "F.Cu" "B.Cu")
		(net "GND")
	)
	(via
		(at 232.841038 -5.003292)
		(size 0.7112)
		(drill 0.4064)
		(layers "F.Cu" "B.Cu")
		(net "GND")
	)
	(via
		(at 193.0654 -2.159)
		(size 0.7112)
		(drill 0.4064)
		(layers "F.Cu" "B.Cu")
		(net "GND")
	)
	(via
		(at 175.6664 -52.7304)
		(size 0.508)
		(drill 0.254)
		(layers "F.Cu" "B.Cu")
		(net "GND")
	)
	(via
		(at 2.159 -40.202866)
		(size 0.7112)
		(drill 0.4064)
		(layers "F.Cu" "B.Cu")
		(net "GND")
	)
	(via
		(at 2.258568 -183.689498)
		(size 0.7112)
		(drill 0.4064)
		(layers "F.Cu" "B.Cu")
		(net "GND")
	)
	(via
		(at 232.841038 -100.253292)
		(size 0.7112)
		(drill 0.4064)
		(layers "F.Cu" "B.Cu")
		(net "GND")
	)
	(via
		(at 16.480536 -165.349936)
		(size 0.508)
		(drill 0.254)
		(layers "F.Cu" "B.Cu")
		(net "GND")
	)
	(via
		(at 28.498038 -91.543124)
		(size 0.7112)
		(drill 0.4064)
		(layers "F.Cu" "B.Cu")
		(net "GND")
	)
	(via
		(at 27.615134 -2.159)
		(size 0.7112)
		(drill 0.4064)
		(layers "F.Cu" "B.Cu")
		(net "GND")
	)
	(via
		(at 64.934592 -159.036258)
		(size 0.508)
		(drill 0.254)
		(layers "F.Cu" "B.Cu")
		(net "GND")
	)
	(via
		(at 92.837 -157.226)
		(size 0.5588)
		(drill 0.3048)
		(layers "F.Cu" "B.Cu")
		(net "GND")
	)
	(via
		(at 232.841038 -34.213292)
		(size 0.7112)
		(drill 0.4064)
		(layers "F.Cu" "B.Cu")
		(net "GND")
	)
	(via
		(at 192.804542 -73.10374)
		(size 0.508)
		(drill 0.254)
		(layers "F.Cu" "B.Cu")
		(net "GND")
	)
	(via
		(at 9.835134 -2.159)
		(size 0.7112)
		(drill 0.4064)
		(layers "F.Cu" "B.Cu")
		(net "GND")
	)
	(via
		(at 180.269388 -191.84112)
		(size 0.7112)
		(drill 0.4064)
		(layers "F.Cu" "B.Cu")
		(net "GND")
	)
	(via
		(at 94.869 -137.23747)
		(size 0.508)
		(drill 0.254)
		(layers "F.Cu" "B.Cu")
		(net "GND")
	)
	(via
		(at 232.841038 -166.293292)
		(size 0.7112)
		(drill 0.4064)
		(layers "F.Cu" "B.Cu")
		(net "GND")
	)
	(via
		(at 190.7794 -102.9716)
		(size 0.7112)
		(drill 0.4064)
		(layers "F.Cu" "B.Cu")
		(net "GND")
	)
	(via
		(at 8.68045 -133.850126)
		(size 0.508)
		(drill 0.254)
		(layers "F.Cu" "B.Cu")
		(net "GND")
	)
	(via
		(at 231.758744 -185.573162)
		(size 0.7112)
		(drill 0.4064)
		(layers "F.Cu" "B.Cu")
		(net "GND")
	)
	(via
		(at 232.841038 -57.073292)
		(size 0.7112)
		(drill 0.4064)
		(layers "F.Cu" "B.Cu")
		(net "GND")
	)
	(via
		(at 12.8778 -168.656)
		(size 0.508)
		(drill 0.254)
		(layers "F.Cu" "B.Cu")
		(net "GND")
	)
	(via
		(at 94.0308 -161.6456)
		(size 0.508)
		(drill 0.254)
		(layers "F.Cu" "B.Cu")
		(net "GND")
	)
	(via
		(at 200.12533 -2.159)
		(size 0.7112)
		(drill 0.4064)
		(layers "F.Cu" "B.Cu")
		(net "GND")
	)
	(via
		(at 21.265134 -2.159)
		(size 0.7112)
		(drill 0.4064)
		(layers "F.Cu" "B.Cu")
		(net "GND")
	)
	(via
		(at 146.45894 -177.397664)
		(size 0.7112)
		(drill 0.4064)
		(layers "F.Cu" "B.Cu")
		(net "GND")
	)
	(via
		(at 179.2351 -46.8757)
		(size 0.508)
		(drill 0.254)
		(layers "F.Cu" "B.Cu")
		(net "GND")
	)
	(via
		(at 205.096872 -59.553856)
		(size 0.508)
		(drill 0.254)
		(layers "F.Cu" "B.Cu")
		(net "GND")
	)
	(via
		(at 181.539388 -191.84112)
		(size 0.7112)
		(drill 0.4064)
		(layers "F.Cu" "B.Cu")
		(net "GND")
	)
	(via
		(at 47.69993 -143.400018)
		(size 0.4572)
		(drill 0.2032)
		(layers "F.Cu" "B.Cu")
		(net "GND")
	)
	(via
		(at 2.159 -49.092866)
		(size 0.7112)
		(drill 0.4064)
		(layers "F.Cu" "B.Cu")
		(net "GND")
	)
	(via
		(at 159.78632 -137.13968)
		(size 0.5588)
		(drill 0.3048)
		(layers "F.Cu" "B.Cu")
		(net "GND")
	)
	(via
		(at 225.691954 -57.568846)
		(size 0.508)
		(drill 0.254)
		(layers "F.Cu" "B.Cu")
		(net "GND")
	)
	(via
		(at 191.200278 -65.900046)
		(size 0.508)
		(drill 0.254)
		(layers "F.Cu" "B.Cu")
		(net "GND")
	)
	(via
		(at 61.990478 -191.84112)
		(size 0.7112)
		(drill 0.4064)
		(layers "F.Cu" "B.Cu")
		(net "GND")
	)
	(via
		(at 193.593974 -69.10324)
		(size 0.508)
		(drill 0.254)
		(layers "F.Cu" "B.Cu")
		(net "GND")
	)
	(via
		(at 62.639194 -140.083794)
		(size 0.508)
		(drill 0.254)
		(layers "F.Cu" "B.Cu")
		(net "GND")
	)
	(segment
		(start 89.8525 -132.3213)
		(end 89.7382 -132.4356)
		(width 0.508)
		(layer "B.Cu")
		(net "GND")
	)
	(segment
		(start 61.95187 -139.8016)
		(end 62.234064 -140.083794)
		(width 0.508)
		(layer "B.Cu")
		(net "GND")
	)
	(segment
		(start 49.376584 -134.696962)
		(end 49.376838 -134.696962)
		(width 0.508)
		(layer "B.Cu")
		(net "GND")
	)
	(segment
		(start 57.5691 -150.6728)
		(end 58.3692 -150.6728)
		(width 0.508)
		(layer "B.Cu")
		(net "GND")
	)
	(segment
		(start 93.4339 -129.9337)
		(end 93.726 -130.2258)
		(width 0.254)
		(layer "B.Cu")
		(net "GND")
	)
	(segment
		(start 94.6404 -146.356578)
		(end 94.816422 -146.356578)
		(width 0.508)
		(layer "B.Cu")
		(net "GND")
	)
	(segment
		(start 55.4228 -165.4556)
		(end 54.941724 -165.936676)
		(width 0.508)
		(layer "B.Cu")
		(net "GND")
	)
	(segment
		(start 49.0347 -135.038846)
		(end 49.376584 -134.696962)
		(width 0.508)
		(layer "B.Cu")
		(net "GND")
	)
	(segment
		(start 187.199778 -73.899776)
		(end 187.199778 -74.060304)
		(width 0.508)
		(layer "B.Cu")
		(net "GND")
	)
	(segment
		(start 81.781904 -128.4605)
		(end 81.4451 -128.797304)
		(width 0.254)
		(layer "B.Cu")
		(net "GND")
	)
	(segment
		(start 90.4367 -137.5156)
		(end 89.5096 -137.5156)
		(width 0.508)
		(layer "B.Cu")
		(net "GND")
	)
	(segment
		(start 117.3226 -14.2367)
		(end 119.93245 -14.2367)
		(width 0.508)
		(layer "B.Cu")
		(net "GND")
	)
	(segment
		(start 57.460896 -162.19424)
		(end 58.182002 -162.19424)
		(width 0.254)
		(layer "B.Cu")
		(net "GND")
	)
	(segment
		(start 178.963066 -65.573656)
		(end 179.013866 -65.522856)
		(width 0.508)
		(layer "B.Cu")
		(net "GND")
	)
	(segment
		(start 54.9402 -164.973)
		(end 55.4228 -165.4556)
		(width 0.508)
		(layer "B.Cu")
		(net "GND")
	)
	(segment
		(start 201.855324 -60.300108)
		(end 202.463146 -60.90793)
		(width 0.508)
		(layer "B.Cu")
		(net "GND")
	)
	(segment
		(start 92.338906 -139.016486)
		(end 92.846906 -139.524486)
		(width 0.508)
		(layer "B.Cu")
		(net "GND")
	)
	(segment
		(start 57.291732 -162.025076)
		(end 57.460896 -162.19424)
		(width 0.254)
		(layer "B.Cu")
		(net "GND")
	)
	(segment
		(start 199.9996 -71.247)
		(end 199.9996 -70.706742)
		(width 0.254)
		(layer "B.Cu")
		(net "GND")
	)
	(segment
		(start 152.781 -93.4847)
		(end 152.781 -92.3544)
		(width 0.254)
		(layer "B.Cu")
		(net "GND")
	)
	(segment
		(start 89.5096 -137.5156)
		(end 89.3064 -137.3124)
		(width 0.508)
		(layer "B.Cu")
		(net "GND")
	)
	(segment
		(start 50.95494 -162.461194)
		(end 51.068986 -162.461194)
		(width 0.254)
		(layer "B.Cu")
		(net "GND")
	)
	(segment
		(start 57.809892 -147.743164)
		(end 58.631836 -147.743164)
		(width 0.508)
		(layer "B.Cu")
		(net "GND")
	)
	(segment
		(start 62.134242 -136.906)
		(end 62.606936 -136.433306)
		(width 0.508)
		(layer "B.Cu")
		(net "GND")
	)
	(segment
		(start 47.43069 -118.12651)
		(end 46.656498 -118.900702)
		(width 0.3302)
		(layer "B.Cu")
		(net "GND")
	)
	(segment
		(start 159.9946 -55.0672)
		(end 159.9946 -53.6575)
		(width 0.254)
		(layer "B.Cu")
		(net "GND")
	)
	(segment
		(start 34.293048 -129.5908)
		(end 34.722308 -129.16154)
		(width 0.508)
		(layer "B.Cu")
		(net "GND")
	)
	(segment
		(start 94.816422 -146.356578)
		(end 95.1865 -145.9865)
		(width 0.508)
		(layer "B.Cu")
		(net "GND")
	)
	(segment
		(start 89.1794 -180.8734)
		(end 90.06078 -179.99202)
		(width 0.254)
		(layer "B.Cu")
		(net "GND")
	)
	(segment
		(start 52.07508 -154.60726)
		(end 52.07508 -154.14371)
		(width 0.254)
		(layer "B.Cu")
		(net "GND")
	)
	(segment
		(start 47.0789 -163.4744)
		(end 46.981618 -163.571682)
		(width 0.508)
		(layer "B.Cu")
		(net "GND")
	)
	(segment
		(start 56.5404 -127.889)
		(end 56.35498 -128.07442)
		(width 0.254)
		(layer "B.Cu")
		(net "GND")
	)
	(segment
		(start 199.197722 -70.692772)
		(end 198.775574 -71.11492)
		(width 0.3048)
		(layer "B.Cu")
		(net "GND")
	)
	(segment
		(start 51.74488 -161.86658)
		(end 51.74996 -161.8615)
		(width 0.254)
		(layer "B.Cu")
		(net "GND")
	)
	(segment
		(start 193.599816 -72.966072)
		(end 193.599816 -73.099676)
		(width 0.3048)
		(layer "B.Cu")
		(net "GND")
	)
	(segment
		(start 190.428372 -74.793856)
		(end 190.428372 -73.928478)
		(width 0.508)
		(layer "B.Cu")
		(net "GND")
	)
	(segment
		(start 207.182212 -63.71971)
		(end 207.284066 -63.617856)
		(width 0.508)
		(layer "B.Cu")
		(net "GND")
	)
	(segment
		(start 169.4942 -52.3748)
		(end 169.4942 -53.6575)
		(width 0.3048)
		(layer "B.Cu")
		(net "GND")
	)
	(segment
		(start 97.0407 -152.8699)
		(end 97.3582 -152.5524)
		(width 0.254)
		(layer "B.Cu")
		(net "GND")
	)
	(segment
		(start 202.260454 -58.700162)
		(end 201.600054 -58.700162)
		(width 0.508)
		(layer "B.Cu")
		(net "GND")
	)
	(segment
		(start 141.5415 -16.4338)
		(end 140.38834 -16.4338)
		(width 0.508)
		(layer "B.Cu")
		(net "GND")
	)
	(segment
		(start 34.722308 -129.16154)
		(end 34.722308 -125.123194)
		(width 0.508)
		(layer "B.Cu")
		(net "GND")
	)
	(segment
		(start 80.08366 -173.20768)
		(end 80.58912 -173.20768)
		(width 0.254)
		(layer "B.Cu")
		(net "GND")
	)
	(segment
		(start 204.182472 -70.729856)
		(end 203.229972 -70.729856)
		(width 0.3048)
		(layer "B.Cu")
		(net "GND")
	)
	(segment
		(start 27.2034 -126.3142)
		(end 28.0289 -126.3142)
		(width 0.508)
		(layer "B.Cu")
		(net "GND")
	)
	(segment
		(start 93.853 -146.3421)
		(end 93.867478 -146.356578)
		(width 0.508)
		(layer "B.Cu")
		(net "GND")
	)
	(segment
		(start 144.89049 -17.78)
		(end 144.272 -17.78)
		(width 0.4064)
		(layer "B.Cu")
		(net "GND")
	)
	(segment
		(start 192.635632 -72.93483)
		(end 192.804542 -73.10374)
		(width 0.254)
		(layer "B.Cu")
		(net "GND")
	)
	(segment
		(start 81.4451 -128.797304)
		(end 81.4451 -129.39776)
		(width 0.254)
		(layer "B.Cu")
		(net "GND")
	)
	(segment
		(start 203.6064 -77.978)
		(end 203.6064 -77.5716)
		(width 0.254)
		(layer "B.Cu")
		(net "GND")
	)
	(segment
		(start 38.00729 -119.014748)
		(end 37.150802 -119.014748)
		(width 0.508)
		(layer "B.Cu")
		(net "GND")
	)
	(segment
		(start 188.87694 -73.82256)
		(end 188.799724 -73.899776)
		(width 0.381)
		(layer "B.Cu")
		(net "GND")
	)
	(segment
		(start 89.52992 -148.872956)
		(end 89.46642 -148.809456)
		(width 0.508)
		(layer "B.Cu")
		(net "GND")
	)
	(segment
		(start 63.3095 -154.516836)
		(end 63.3095 -153.99004)
		(width 0.508)
		(layer "B.Cu")
		(net "GND")
	)
	(segment
		(start 61.08192 -152.94864)
		(end 60.67044 -152.94864)
		(width 0.508)
		(layer "B.Cu")
		(net "GND")
	)
	(segment
		(start 24.45766 -146.418808)
		(end 24.456898 -146.418046)
		(width 0.508)
		(layer "B.Cu")
		(net "GND")
	)
	(segment
		(start 51.068986 -162.461194)
		(end 51.6636 -161.86658)
		(width 0.254)
		(layer "B.Cu")
		(net "GND")
	)
	(segment
		(start 178.67376 -139.40028)
		(end 179.063904 -139.790424)
		(width 0.508)
		(layer "B.Cu")
		(net "GND")
	)
	(segment
		(start 200.1774 -71.6788)
		(end 199.9996 -71.501)
		(width 0.254)
		(layer "B.Cu")
		(net "GND")
	)
	(segment
		(start 95.1865 -145.9865)
		(end 96.139 -145.9865)
		(width 0.508)
		(layer "B.Cu")
		(net "GND")
	)
	(segment
		(start 140.0175 -19.06524)
		(end 138.64336 -19.06524)
		(width 0.4064)
		(layer "B.Cu")
		(net "GND")
	)
	(segment
		(start 47.0789 -161.3662)
		(end 47.0789 -163.4744)
		(width 0.508)
		(layer "B.Cu")
		(net "GND")
	)
	(segment
		(start 147.2819 -19.9644)
		(end 146.5834 -19.9644)
		(width 0.508)
		(layer "B.Cu")
		(net "GND")
	)
	(segment
		(start 64.480186 -139.956286)
		(end 66.50736 -139.956286)
		(width 0.508)
		(layer "B.Cu")
		(net "GND")
	)
	(segment
		(start 49.0347 -135.0391)
		(end 49.0347 -135.038846)
		(width 0.508)
		(layer "B.Cu")
		(net "GND")
	)
	(segment
		(start 48.495966 -135.285734)
		(end 48.514 -135.2677)
		(width 0.508)
		(layer "B.Cu")
		(net "GND")
	)
	(segment
		(start 56.35498 -128.07442)
		(end 55.66664 -128.07442)
		(width 0.254)
		(layer "B.Cu")
		(net "GND")
	)
	(segment
		(start 183.935624 -71.5645)
		(end 184.00014 -71.499984)
		(width 0.254)
		(layer "B.Cu")
		(net "GND")
	)
	(segment
		(start 193.999866 -72.566022)
		(end 193.599816 -72.966072)
		(width 0.3048)
		(layer "B.Cu")
		(net "GND")
	)
	(segment
		(start 199.9996 -70.706742)
		(end 200.004426 -70.701916)
		(width 0.254)
		(layer "B.Cu")
		(net "GND")
	)
	(segment
		(start 63.1063 -154.720036)
		(end 63.3095 -154.516836)
		(width 0.508)
		(layer "B.Cu")
		(net "GND")
	)
	(segment
		(start 99.4029 -177.9778)
		(end 99.4029 -177.51298)
		(width 0.508)
		(layer "B.Cu")
		(net "GND")
	)
	(segment
		(start 89.916 -163.2966)
		(end 89.916 -162.0266)
		(width 0.254)
		(layer "B.Cu")
		(net "GND")
	)
	(segment
		(start 88.519 -167.74668)
		(end 89.879424 -167.74668)
		(width 0.254)
		(layer "B.Cu")
		(net "GND")
	)
	(segment
		(start 61.8871 -136.906)
		(end 62.134242 -136.906)
		(width 0.508)
		(layer "B.Cu")
		(net "GND")
	)
	(segment
		(start 204.724 -69.469)
		(end 204.131672 -68.876672)
		(width 0.254)
		(layer "B.Cu")
		(net "GND")
	)
	(segment
		(start 200.75144 -61.7093)
		(end 201.399902 -61.7093)
		(width 0.508)
		(layer "B.Cu")
		(net "GND")
	)
	(segment
		(start 88.040972 -149.17674)
		(end 87.691976 -149.17674)
		(width 0.508)
		(layer "B.Cu")
		(net "GND")
	)
	(segment
		(start 204.3049 -62.6872)
		(end 205.257908 -62.6872)
		(width 0.508)
		(layer "B.Cu")
		(net "GND")
	)
	(segment
		(start 54.864 -162.1536)
		(end 55.5752 -161.4424)
		(width 0.508)
		(layer "B.Cu")
		(net "GND")
	)
	(segment
		(start 37.97681 -122.188478)
		(end 37.120322 -122.188478)
		(width 0.508)
		(layer "B.Cu")
		(net "GND")
	)
	(segment
		(start 53.5686 -134.62)
		(end 53.721 -134.4676)
		(width 0.508)
		(layer "B.Cu")
		(net "GND")
	)
	(segment
		(start 200.723754 -67.56654)
		(end 200.796652 -67.493642)
		(width 0.3048)
		(layer "B.Cu")
		(net "GND")
	)
	(segment
		(start 48.8061 -135.2677)
		(end 49.0347 -135.0391)
		(width 0.508)
		(layer "B.Cu")
		(net "GND")
	)
	(segment
		(start 51.99888 -140.335)
		(end 51.99888 -140.499592)
		(width 0.4572)
		(layer "B.Cu")
		(net "GND")
	)
	(segment
		(start 93.0529 -144.072102)
		(end 94.194376 -144.072102)
		(width 0.508)
		(layer "B.Cu")
		(net "GND")
	)
	(segment
		(start 193.999866 -72.380856)
		(end 193.999866 -72.566022)
		(width 0.3048)
		(layer "B.Cu")
		(net "GND")
	)
	(segment
		(start 92.8116 -129.9337)
		(end 93.4339 -129.9337)
		(width 0.254)
		(layer "B.Cu")
		(net "GND")
	)
	(segment
		(start 198.775574 -71.11492)
		(end 198.7042 -71.11492)
		(width 0.3048)
		(layer "B.Cu")
		(net "GND")
	)
	(segment
		(start 190.734442 -72.644)
		(end 190.396622 -72.30618)
		(width 0.254)
		(layer "B.Cu")
		(net "GND")
	)
	(segment
		(start 93.8149 -130.3147)
		(end 93.726 -130.2258)
		(width 0.254)
		(layer "B.Cu")
		(net "GND")
	)
	(segment
		(start 86.131654 -100.074222)
		(end 86.399878 -100.074222)
		(width 0.254)
		(layer "B.Cu")
		(net "GND")
	)
	(segment
		(start 199.9996 -71.501)
		(end 199.9996 -71.247)
		(width 0.254)
		(layer "B.Cu")
		(net "GND")
	)
	(segment
		(start 164.465 -50.7619)
		(end 163.6014 -50.7619)
		(width 0.508)
		(layer "B.Cu")
		(net "GND")
	)
	(segment
		(start 194.2846 -53.4035)
		(end 194.09664 -53.4035)
		(width 0.508)
		(layer "B.Cu")
		(net "GND")
	)
	(segment
		(start 206.8703 -78.8416)
		(end 206.8703 -77.9653)
		(width 0.508)
		(layer "B.Cu")
		(net "GND")
	)
	(segment
		(start 93.3704 -180.2638)
		(end 92.5068 -181.1274)
		(width 0.508)
		(layer "B.Cu")
		(net "GND")
	)
	(segment
		(start 200.04786 -67.56654)
		(end 200.723754 -67.56654)
		(width 0.3048)
		(layer "B.Cu")
		(net "GND")
	)
	(segment
		(start 121.539 -6.477)
		(end 121.539 -5.02285)
		(width 0.508)
		(layer "B.Cu")
		(net "GND")
	)
	(segment
		(start 54.941724 -165.936676)
		(end 54.497732 -165.936676)
		(width 0.508)
		(layer "B.Cu")
		(net "GND")
	)
	(segment
		(start 52.07508 -154.14371)
		(end 51.71567 -153.7843)
		(width 0.254)
		(layer "B.Cu")
		(net "GND")
	)
	(segment
		(start 62.2808 -175.7299)
		(end 61.8617 -175.7299)
		(width 0.254)
		(layer "B.Cu")
		(net "GND")
	)
	(segment
		(start 197.63486 -72.34428)
		(end 197.59041 -72.29983)
		(width 0.254)
		(layer "B.Cu")
		(net "GND")
	)
	(segment
		(start 88.471756 -148.745956)
		(end 88.040972 -149.17674)
		(width 0.508)
		(layer "B.Cu")
		(net "GND")
	)
	(segment
		(start 138.64336 -19.06524)
		(end 138.5062 -19.2024)
		(width 0.4064)
		(layer "B.Cu")
		(net "GND")
	)
	(segment
		(start 82.7786 -172.3644)
		(end 82.6135 -172.5295)
		(width 0.254)
		(layer "B.Cu")
		(net "GND")
	)
	(segment
		(start 204.724 -69.5452)
		(end 204.724 -69.469)
		(width 0.254)
		(layer "B.Cu")
		(net "GND")
	)
	(segment
		(start 57.470548 -161.259774)
		(end 58.200798 -161.259774)
		(width 0.254)
		(layer "B.Cu")
		(net "GND")
	)
	(segment
		(start 187.199778 -74.060304)
		(end 187.634372 -74.494898)
		(width 0.508)
		(layer "B.Cu")
		(net "GND")
	)
	(segment
		(start 63.1063 -154.9146)
		(end 63.1063 -154.720036)
		(width 0.508)
		(layer "B.Cu")
		(net "GND")
	)
	(segment
		(start 93.655134 -133.418834)
		(end 93.655134 -133.421882)
		(width 0.254)
		(layer "B.Cu")
		(net "GND")
	)
	(segment
		(start 200.7108 -69.020436)
		(end 200.791826 -69.101462)
		(width 0.254)
		(layer "B.Cu")
		(net "GND")
	)
	(segment
		(start 184.48274 -57.573164)
		(end 184.808876 -57.8993)
		(width 0.254)
		(layer "B.Cu")
		(net "GND")
	)
	(segment
		(start 92.107258 -138.919712)
		(end 92.107258 -137.546842)
		(width 0.254)
		(layer "B.Cu")
		(net "GND")
	)
	(segment
		(start 52.705 -126.77902)
		(end 52.705 -127.762)
		(width 0.3556)
		(layer "B.Cu")
		(net "GND")
	)
	(segment
		(start 96.52 -152.8699)
		(end 97.0407 -152.8699)
		(width 0.254)
		(layer "B.Cu")
		(net "GND")
	)
	(segment
		(start 39.699946 -144.999964)
		(end 39.557198 -144.857216)
		(width 0.254)
		(layer "B.Cu")
		(net "GND")
	)
	(segment
		(start 62.8396 -149.7584)
		(end 62.2554 -149.7584)
		(width 0.508)
		(layer "B.Cu")
		(net "GND")
	)
	(segment
		(start 51.7652 -160.8963)
		(end 51.36134 -160.8963)
		(width 0.254)
		(layer "B.Cu")
		(net "GND")
	)
	(segment
		(start 64.158622 -139.1031)
		(end 64.158622 -139.634722)
		(width 0.508)
		(layer "B.Cu")
		(net "GND")
	)
	(segment
		(start 198.78294 -70.10908)
		(end 198.78294 -70.27799)
		(width 0.3048)
		(layer "B.Cu")
		(net "GND")
	)
	(segment
		(start 94.4245 -175.133)
		(end 94.4245 -175.5775)
		(width 0.254)
		(layer "B.Cu")
		(net "GND")
	)
	(segment
		(start 49.376838 -134.696962)
		(end 49.6062 -134.4676)
		(width 0.508)
		(layer "B.Cu")
		(net "GND")
	)
	(segment
		(start 187.634372 -74.494898)
		(end 187.634372 -74.793856)
		(width 0.508)
		(layer "B.Cu")
		(net "GND")
	)
	(segment
		(start 207.182212 -64.430656)
		(end 207.182212 -63.71971)
		(width 0.508)
		(layer "B.Cu")
		(net "GND")
	)
	(segment
		(start 186.96178 -73.1901)
		(end 187.199778 -73.428098)
		(width 0.381)
		(layer "B.Cu")
		(net "GND")
	)
	(segment
		(start 89.027 -164.1856)
		(end 89.916 -163.2966)
		(width 0.254)
		(layer "B.Cu")
		(net "GND")
	)
	(segment
		(start 187.199778 -73.428098)
		(end 187.199778 -73.899776)
		(width 0.381)
		(layer "B.Cu")
		(net "GND")
	)
	(segment
		(start 92.69222 -134.384796)
		(end 92.69222 -134.57936)
		(width 0.254)
		(layer "B.Cu")
		(net "GND")
	)
	(segment
		(start 88.5444 -163.3728)
		(end 88.6968 -163.2204)
		(width 0.508)
		(layer "B.Cu")
		(net "GND")
	)
	(segment
		(start 94.194376 -144.072102)
		(end 94.291658 -143.97482)
		(width 0.508)
		(layer "B.Cu")
		(net "GND")
	)
	(segment
		(start 61.9633 -150.0505)
		(end 61.468 -150.0505)
		(width 0.508)
		(layer "B.Cu")
		(net "GND")
	)
	(segment
		(start 94.4245 -175.5775)
		(end 93.8784 -176.1236)
		(width 0.254)
		(layer "B.Cu")
		(net "GND")
	)
	(segment
		(start 38.0111 -116.8908)
		(end 37.160454 -116.8908)
		(width 0.508)
		(layer "B.Cu")
		(net "GND")
	)
	(segment
		(start 195.7832 -76.1746)
		(end 195.7832 -75.716638)
		(width 0.254)
		(layer "B.Cu")
		(net "GND")
	)
	(segment
		(start 202.394566 -58.56605)
		(end 202.260454 -58.700162)
		(width 0.508)
		(layer "B.Cu")
		(net "GND")
	)
	(segment
		(start 198.78294 -70.27799)
		(end 199.197722 -70.692772)
		(width 0.3048)
		(layer "B.Cu")
		(net "GND")
	)
	(segment
		(start 33.562544 -123.21286)
		(end 33.820608 -122.954796)
		(width 0.254)
		(layer "B.Cu")
		(net "GND")
	)
	(segment
		(start 169.3418 -52.2224)
		(end 169.4942 -52.3748)
		(width 0.3048)
		(layer "B.Cu")
		(net "GND")
	)
	(segment
		(start 197.59041 -72.29983)
		(end 197.59041 -71.499984)
		(width 0.254)
		(layer "B.Cu")
		(net "GND")
	)
	(segment
		(start 164.769292 -75.270106)
		(end 164.769292 -74.397108)
		(width 0.508)
		(layer "B.Cu")
		(net "GND")
	)
	(segment
		(start 62.4713 -148.0693)
		(end 61.4934 -148.0693)
		(width 0.508)
		(layer "B.Cu")
		(net "GND")
	)
	(segment
		(start 78.2066 -129.7305)
		(end 78.070456 -129.594356)
		(width 0.508)
		(layer "B.Cu")
		(net "GND")
	)
	(segment
		(start 62.611 -152.781)
		(end 62.39764 -152.56764)
		(width 0.508)
		(layer "B.Cu")
		(net "GND")
	)
	(segment
		(start 62.2554 -149.7584)
		(end 61.9633 -150.0505)
		(width 0.508)
		(layer "B.Cu")
		(net "GND")
	)
	(segment
		(start 183.824372 -74.07529)
		(end 183.999886 -73.899776)
		(width 0.508)
		(layer "B.Cu")
		(net "GND")
	)
	(segment
		(start 50.086514 -161.706052)
		(end 50.551588 -161.706052)
		(width 0.254)
		(layer "B.Cu")
		(net "GND")
	)
	(segment
		(start 88.00211 -178.60899)
		(end 88.19261 -178.60899)
		(width 0.254)
		(layer "B.Cu")
		(net "GND")
	)
	(segment
		(start 200.44283 -75.057)
		(end 200.000108 -75.499722)
		(width 0.254)
		(layer "B.Cu")
		(net "GND")
	)
	(segment
		(start 67.183 -150.1902)
		(end 67.528186 -149.845014)
		(width 0.254)
		(layer "B.Cu")
		(net "GND")
	)
	(segment
		(start 195.7832 -75.716638)
		(end 196.000116 -75.499722)
		(width 0.254)
		(layer "B.Cu")
		(net "GND")
	)
	(segment
		(start 205.257908 -62.6872)
		(end 205.466442 -62.478666)
		(width 0.508)
		(layer "B.Cu")
		(net "GND")
	)
	(segment
		(start 89.879424 -167.74668)
		(end 89.941908 -167.809164)
		(width 0.254)
		(layer "B.Cu")
		(net "GND")
	)
	(segment
		(start 179.013866 -65.522856)
		(end 180.067966 -65.522856)
		(width 0.508)
		(layer "B.Cu")
		(net "GND")
	)
	(segment
		(start 61.46292 -152.56764)
		(end 61.08192 -152.94864)
		(width 0.508)
		(layer "B.Cu")
		(net "GND")
	)
	(segment
		(start 214.1728 -122.301)
		(end 215.5444 -122.301)
		(width 0.508)
		(layer "B.Cu")
		(net "GND")
	)
	(segment
		(start 119.93245 -14.2367)
		(end 120.4087 -14.71295)
		(width 0.508)
		(layer "B.Cu")
		(net "GND")
	)
	(segment
		(start 92.204032 -139.016486)
		(end 92.338906 -139.016486)
		(width 0.508)
		(layer "B.Cu")
		(net "GND")
	)
	(segment
		(start 159.893 -48.4505)
		(end 159.893 -47.625)
		(width 0.508)
		(layer "B.Cu")
		(net "GND")
	)
	(segment
		(start 51.36134 -160.8963)
		(end 50.94224 -161.3154)
		(width 0.254)
		(layer "B.Cu")
		(net "GND")
	)
	(segment
		(start 159.8676 -55.1942)
		(end 159.9946 -55.0672)
		(width 0.254)
		(layer "B.Cu")
		(net "GND")
	)
	(segment
		(start 25.44572 -146.418808)
		(end 24.45766 -146.418808)
		(width 0.508)
		(layer "B.Cu")
		(net "GND")
	)
	(segment
		(start 203.229972 -70.729856)
		(end 203.199746 -70.69963)
		(width 0.3048)
		(layer "B.Cu")
		(net "GND")
	)
	(segment
		(start 145.7325 -17.79524)
		(end 144.90573 -17.79524)
		(width 0.4064)
		(layer "B.Cu")
		(net "GND")
	)
	(segment
		(start 97.742756 -159.78632)
		(end 97.742756 -160.814004)
		(width 0.254)
		(layer "B.Cu")
		(net "GND")
	)
	(segment
		(start 40.132 -122.0978)
		(end 40.401748 -122.367548)
		(width 0.508)
		(layer "B.Cu")
		(net "GND")
	)
	(segment
		(start 54.6735 -162.1536)
		(end 54.864 -162.1536)
		(width 0.508)
		(layer "B.Cu")
		(net "GND")
	)
	(segment
		(start 50.85334 -151.446484)
		(end 50.899822 -151.400002)
		(width 0.254)
		(layer "B.Cu")
		(net "GND")
	)
	(segment
		(start 185.6486 -72.18934)
		(end 185.6486 -71.548244)
		(width 0.254)
		(layer "B.Cu")
		(net "GND")
	)
	(segment
		(start 200.8632 -75.057)
		(end 200.44283 -75.057)
		(width 0.254)
		(layer "B.Cu")
		(net "GND")
	)
	(segment
		(start 197.5866 -78.5622)
		(end 198.1962 -78.5622)
		(width 0.254)
		(layer "B.Cu")
		(net "GND")
	)
	(segment
		(start 197.5358 -78.613)
		(end 197.5866 -78.5622)
		(width 0.254)
		(layer "B.Cu")
		(net "GND")
	)
	(segment
		(start 43.04538 -124.68098)
		(end 43.40098 -125.03658)
		(width 0.508)
		(layer "B.Cu")
		(net "GND")
	)
	(segment
		(start 88.535256 -148.809456)
		(end 88.471756 -148.745956)
		(width 0.508)
		(layer "B.Cu")
		(net "GND")
	)
	(segment
		(start 58.631836 -147.743164)
		(end 58.6486 -147.7264)
		(width 0.508)
		(layer "B.Cu")
		(net "GND")
	)
	(segment
		(start 62.39764 -152.56764)
		(end 61.46292 -152.56764)
		(width 0.508)
		(layer "B.Cu")
		(net "GND")
	)
	(segment
		(start 55.2958 -161.163)
		(end 54.6735 -161.163)
		(width 0.508)
		(layer "B.Cu")
		(net "GND")
	)
	(segment
		(start 116.8273 -15.7226)
		(end 116.8273 -14.732)
		(width 0.508)
		(layer "B.Cu")
		(net "GND")
	)
	(segment
		(start 184.4294 -58.278776)
		(end 184.808876 -57.8993)
		(width 0.254)
		(layer "B.Cu")
		(net "GND")
	)
	(segment
		(start 82.7786 -172.339)
		(end 82.7786 -172.3644)
		(width 0.254)
		(layer "B.Cu")
		(net "GND")
	)
	(segment
		(start 23.777702 -146.418046)
		(end 23.634192 -146.561556)
		(width 0.508)
		(layer "B.Cu")
		(net "GND")
	)
	(segment
		(start 92.846906 -139.524486)
		(end 92.846906 -140.716)
		(width 0.508)
		(layer "B.Cu")
		(net "GND")
	)
	(segment
		(start 93.867478 -146.356578)
		(end 94.6404 -146.356578)
		(width 0.508)
		(layer "B.Cu")
		(net "GND")
	)
	(segment
		(start 40.401748 -122.367548)
		(end 41.24579 -122.367548)
		(width 0.508)
		(layer "B.Cu")
		(net "GND")
	)
	(segment
		(start 54.5211 -164.973)
		(end 54.9402 -164.973)
		(width 0.508)
		(layer "B.Cu")
		(net "GND")
	)
	(segment
		(start 16.3449 -148.0058)
		(end 17.078706 -148.0058)
		(width 0.508)
		(layer "B.Cu")
		(net "GND")
	)
	(segment
		(start 50.85334 -152.23236)
		(end 50.85334 -151.446484)
		(width 0.254)
		(layer "B.Cu")
		(net "GND")
	)
	(segment
		(start 204.115416 -68.7324)
		(end 203.563728 -68.7324)
		(width 0.254)
		(layer "B.Cu")
		(net "GND")
	)
	(segment
		(start 155.2448 -90.1192)
		(end 155.0162 -90.1192)
		(width 0.508)
		(layer "B.Cu")
		(net "GND")
	)
	(segment
		(start 95.590868 -180.66004)
		(end 97.12198 -180.66004)
		(width 0.4064)
		(layer "B.Cu")
		(net "GND")
	)
	(segment
		(start 88.19261 -178.60899)
		(end 88.6714 -178.1302)
		(width 0.254)
		(layer "B.Cu")
		(net "GND")
	)
	(segment
		(start 89.46642 -148.809456)
		(end 88.535256 -148.809456)
		(width 0.508)
		(layer "B.Cu")
		(net "GND")
	)
	(segment
		(start 184.4294 -58.79084)
		(end 184.4294 -58.278776)
		(width 0.254)
		(layer "B.Cu")
		(net "GND")
	)
	(segment
		(start 191.008 -72.644)
		(end 190.734442 -72.644)
		(width 0.254)
		(layer "B.Cu")
		(net "GND")
	)
	(segment
		(start 53.5686 -135.2677)
		(end 53.5686 -134.62)
		(width 0.508)
		(layer "B.Cu")
		(net "GND")
	)
	(segment
		(start 201.600054 -60.300108)
		(end 201.855324 -60.300108)
		(width 0.508)
		(layer "B.Cu")
		(net "GND")
	)
	(segment
		(start 155.7655 -91.1606)
		(end 155.7655 -90.6399)
		(width 0.508)
		(layer "B.Cu")
		(net "GND")
	)
	(segment
		(start 55.5752 -161.4424)
		(end 55.2958 -161.163)
		(width 0.508)
		(layer "B.Cu")
		(net "GND")
	)
	(segment
		(start 185.729372 -74.029316)
		(end 185.599832 -73.899776)
		(width 0.508)
		(layer "B.Cu")
		(net "GND")
	)
	(segment
		(start 204.131672 -68.876672)
		(end 204.131672 -68.748656)
		(width 0.254)
		(layer "B.Cu")
		(net "GND")
	)
	(segment
		(start 183.2356 -71.5645)
		(end 183.935624 -71.5645)
		(width 0.254)
		(layer "B.Cu")
		(net "GND")
	)
	(segment
		(start 201.399902 -61.7093)
		(end 201.592688 -61.902086)
		(width 0.508)
		(layer "B.Cu")
		(net "GND")
	)
	(segment
		(start 89.027 -164.4904)
		(end 89.027 -164.1856)
		(width 0.254)
		(layer "B.Cu")
		(net "GND")
	)
	(segment
		(start 88.6714 -178.1302)
		(end 88.6714 -177.78222)
		(width 0.254)
		(layer "B.Cu")
		(net "GND")
	)
	(segment
		(start 62.86246 -155.15844)
		(end 63.1063 -154.9146)
		(width 0.508)
		(layer "B.Cu")
		(net "GND")
	)
	(segment
		(start 164.769292 -74.397108)
		(end 164.7698 -74.3966)
		(width 0.508)
		(layer "B.Cu")
		(net "GND")
	)
	(segment
		(start 179.063904 -139.790424)
		(end 179.063904 -140.824966)
		(width 0.508)
		(layer "B.Cu")
		(net "GND")
	)
	(segment
		(start 193.60007 -53.90007)
		(end 193.3321 -53.6321)
		(width 0.508)
		(layer "B.Cu")
		(net "GND")
	)
	(segment
		(start 64.158622 -139.634722)
		(end 64.480186 -139.956286)
		(width 0.508)
		(layer "B.Cu")
		(net "GND")
	)
	(segment
		(start 62.611 -147.9296)
		(end 62.4713 -148.0693)
		(width 0.508)
		(layer "B.Cu")
		(net "GND")
	)
	(segment
		(start 92.204032 -139.016486)
		(end 92.107258 -138.919712)
		(width 0.254)
		(layer "B.Cu")
		(net "GND")
	)
	(segment
		(start 67.528186 -149.845014)
		(end 67.528186 -149.304502)
		(width 0.254)
		(layer "B.Cu")
		(net "GND")
	)
	(segment
		(start 93.655134 -133.421882)
		(end 92.69222 -134.384796)
		(width 0.254)
		(layer "B.Cu")
		(net "GND")
	)
	(segment
		(start 122.493532 -10.60831)
		(end 122.604022 -10.7188)
		(width 0.508)
		(layer "B.Cu")
		(net "GND")
	)
	(segment
		(start 47.43069 -117.791992)
		(end 47.43069 -118.12651)
		(width 0.3302)
		(layer "B.Cu")
		(net "GND")
	)
	(segment
		(start 185.729372 -74.793856)
		(end 185.729372 -74.029316)
		(width 0.508)
		(layer "B.Cu")
		(net "GND")
	)
	(segment
		(start 198.00316 -68.33362)
		(end 198.00316 -68.712842)
		(width 0.3048)
		(layer "B.Cu")
		(net "GND")
	)
	(segment
		(start 66.5226 -150.1902)
		(end 67.183 -150.1902)
		(width 0.254)
		(layer "B.Cu")
		(net "GND")
	)
	(segment
		(start 50.551588 -161.706052)
		(end 50.94224 -161.3154)
		(width 0.254)
		(layer "B.Cu")
		(net "GND")
	)
	(segment
		(start 78.070456 -129.594356)
		(end 78.070456 -128.4605)
		(width 0.508)
		(layer "B.Cu")
		(net "GND")
	)
	(segment
		(start 39.557198 -144.857216)
		(end 38.675564 -144.857216)
		(width 0.254)
		(layer "B.Cu")
		(net "GND")
	)
	(segment
		(start 90.54592 -148.283168)
		(end 90.173048 -147.910296)
		(width 0.508)
		(layer "B.Cu")
		(net "GND")
	)
	(segment
		(start 203.287122 -73.8124)
		(end 203.199746 -73.899776)
		(width 0.254)
		(layer "B.Cu")
		(net "GND")
	)
	(segment
		(start 82.6135 -172.5295)
		(end 82.6135 -173.2026)
		(width 0.254)
		(layer "B.Cu")
		(net "GND")
	)
	(segment
		(start 190.428372 -73.928478)
		(end 190.39967 -73.899776)
		(width 0.508)
		(layer "B.Cu")
		(net "GND")
	)
	(segment
		(start 116.8273 -14.732)
		(end 117.3226 -14.2367)
		(width 0.508)
		(layer "B.Cu")
		(net "GND")
	)
	(segment
		(start 46.656498 -118.900702)
		(end 46.116748 -118.900702)
		(width 0.3302)
		(layer "B.Cu")
		(net "GND")
	)
	(segment
		(start 61.8617 -175.7299)
		(end 61.468 -176.1236)
		(width 0.254)
		(layer "B.Cu")
		(net "GND")
	)
	(segment
		(start 193.3321 -53.6321)
		(end 192.786 -53.6321)
		(width 0.508)
		(layer "B.Cu")
		(net "GND")
	)
	(segment
		(start 57.294526 -161.083752)
		(end 57.470548 -161.259774)
		(width 0.254)
		(layer "B.Cu")
		(net "GND")
	)
	(segment
		(start 61.3664 -155.15844)
		(end 62.86246 -155.15844)
		(width 0.508)
		(layer "B.Cu")
		(net "GND")
	)
	(segment
		(start 200.20788 -71.88962)
		(end 200.1774 -71.85914)
		(width 0.254)
		(layer "B.Cu")
		(net "GND")
	)
	(segment
		(start 200.1774 -71.85914)
		(end 200.1774 -71.6788)
		(width 0.254)
		(layer "B.Cu")
		(net "GND")
	)
	(segment
		(start 88.6714 -177.78222)
		(end 90.03538 -176.41824)
		(width 0.254)
		(layer "B.Cu")
		(net "GND")
	)
	(segment
		(start 184.48274 -57.16524)
		(end 184.48274 -57.573164)
		(width 0.254)
		(layer "B.Cu")
		(net "GND")
	)
	(segment
		(start 203.6064 -77.5716)
		(end 204.0382 -77.1398)
		(width 0.254)
		(layer "B.Cu")
		(net "GND")
	)
	(segment
		(start 85.339428 -99.281996)
		(end 86.131654 -100.074222)
		(width 0.254)
		(layer "B.Cu")
		(net "GND")
	)
	(segment
		(start 97.742756 -160.814004)
		(end 97.64014 -160.91662)
		(width 0.254)
		(layer "B.Cu")
		(net "GND")
	)
	(segment
		(start 58.894726 -161.259774)
		(end 58.200798 -161.259774)
		(width 0.254)
		(layer "B.Cu")
		(net "GND")
	)
	(segment
		(start 200.277222 -72.822308)
		(end 199.9996 -73.09993)
		(width 0.254)
		(layer "B.Cu")
		(net "GND")
	)
	(segment
		(start 59.1439 -161.0106)
		(end 58.894726 -161.259774)
		(width 0.254)
		(layer "B.Cu")
		(net "GND")
	)
	(segment
		(start 147.5867 -19.6596)
		(end 147.2819 -19.9644)
		(width 0.508)
		(layer "B.Cu")
		(net "GND")
	)
	(segment
		(start 200.277222 -72.5932)
		(end 200.277222 -72.822308)
		(width 0.254)
		(layer "B.Cu")
		(net "GND")
	)
	(segment
		(start 93.3704 -179.1843)
		(end 93.3704 -180.2638)
		(width 0.508)
		(layer "B.Cu")
		(net "GND")
	)
	(segment
		(start 155.7655 -90.6399)
		(end 155.2448 -90.1192)
		(width 0.508)
		(layer "B.Cu")
		(net "GND")
	)
	(segment
		(start 51.6636 -161.86658)
		(end 51.74488 -161.86658)
		(width 0.254)
		(layer "B.Cu")
		(net "GND")
	)
	(segment
		(start 121.397522 -10.60831)
		(end 122.493532 -10.60831)
		(width 0.508)
		(layer "B.Cu")
		(net "GND")
	)
	(segment
		(start 90.5764 -132.2959)
		(end 89.8525 -132.3213)
		(width 0.508)
		(layer "B.Cu")
		(net "GND")
	)
	(segment
		(start 144.90573 -17.79524)
		(end 144.89049 -17.78)
		(width 0.4064)
		(layer "B.Cu")
		(net "GND")
	)
	(segment
		(start 61.4553 -139.8016)
		(end 61.95187 -139.8016)
		(width 0.508)
		(layer "B.Cu")
		(net "GND")
	)
	(segment
		(start 62.234064 -140.083794)
		(end 62.639194 -140.083794)
		(width 0.508)
		(layer "B.Cu")
		(net "GND")
	)
	(segment
		(start 62.7634 -147.9296)
		(end 62.611 -147.9296)
		(width 0.508)
		(layer "B.Cu")
		(net "GND")
	)
	(segment
		(start 99.4029 -177.51298)
		(end 99.75088 -177.165)
		(width 0.508)
		(layer "B.Cu")
		(net "GND")
	)
	(segment
		(start 90.54592 -149.07006)
		(end 90.54592 -148.283168)
		(width 0.508)
		(layer "B.Cu")
		(net "GND")
	)
	(segment
		(start 15.6845 -138.6967)
		(end 15.5194 -138.8618)
		(width 0.508)
		(layer "B.Cu")
		(net "GND")
	)
	(segment
		(start 48.514 -135.2677)
		(end 48.8061 -135.2677)
		(width 0.508)
		(layer "B.Cu")
		(net "GND")
	)
	(segment
		(start 17.078706 -148.0058)
		(end 17.234408 -148.161502)
		(width 0.508)
		(layer "B.Cu")
		(net "GND")
	)
	(segment
		(start 185.6486 -71.548244)
		(end 185.60034 -71.499984)
		(width 0.254)
		(layer "B.Cu")
		(net "GND")
	)
	(segment
		(start 203.563728 -68.7324)
		(end 203.193396 -69.102732)
		(width 0.254)
		(layer "B.Cu")
		(net "GND")
	)
	(segment
		(start 24.456898 -146.418046)
		(end 23.777702 -146.418046)
		(width 0.508)
		(layer "B.Cu")
		(net "GND")
	)
	(segment
		(start 203.9874 -73.8124)
		(end 203.287122 -73.8124)
		(width 0.254)
		(layer "B.Cu")
		(net "GND")
	)
	(segment
		(start 51.99888 -140.499592)
		(end 52.499768 -141.00048)
		(width 0.4572)
		(layer "B.Cu")
		(net "GND")
	)
	(segment
		(start 90.06078 -179.99202)
		(end 90.06078 -179.61864)
		(width 0.254)
		(layer "B.Cu")
		(net "GND")
	)
	(segment
		(start 193.0146 -125.1204)
		(end 191.897 -125.1204)
		(width 0.508)
		(layer "B.Cu")
		(net "GND")
	)
	(segment
		(start 93.8149 -131.40436)
		(end 93.8149 -130.3147)
		(width 0.254)
		(layer "B.Cu")
		(net "GND")
	)
	(segment
		(start 66.50736 -139.956286)
		(end 66.86677 -139.596876)
		(width 0.508)
		(layer "B.Cu")
		(net "GND")
	)
	(segment
		(start 58.95086 -162.19424)
		(end 59.1185 -162.0266)
		(width 0.254)
		(layer "B.Cu")
		(net "GND")
	)
	(segment
		(start 80.8736 -172.9232)
		(end 80.8736 -172.3136)
		(width 0.254)
		(layer "B.Cu")
		(net "GND")
	)
	(segment
		(start 42.382694 -124.68098)
		(end 43.04538 -124.68098)
		(width 0.508)
		(layer "B.Cu")
		(net "GND")
	)
	(segment
		(start 16.6116 -138.6967)
		(end 15.6845 -138.6967)
		(width 0.508)
		(layer "B.Cu")
		(net "GND")
	)
	(segment
		(start 183.824372 -74.793856)
		(end 183.824372 -74.07529)
		(width 0.508)
		(layer "B.Cu")
		(net "GND")
	)
	(segment
		(start 80.58912 -173.20768)
		(end 80.8736 -172.9232)
		(width 0.254)
		(layer "B.Cu")
		(net "GND")
	)
	(segment
		(start 92.107258 -137.546842)
		(end 92.3417 -137.3124)
		(width 0.254)
		(layer "B.Cu")
		(net "GND")
	)
	(segment
		(start 88.5444 -163.449)
		(end 88.5444 -163.3728)
		(width 0.508)
		(layer "B.Cu")
		(net "GND")
	)
	(segment
		(start 200.7108 -68.326)
		(end 200.7108 -69.020436)
		(width 0.254)
		(layer "B.Cu")
		(net "GND")
	)
	(segment
		(start 58.182002 -162.19424)
		(end 58.95086 -162.19424)
		(width 0.254)
		(layer "B.Cu")
		(net "GND")
	)
	(segment
		(start 188.87694 -73.10374)
		(end 188.87694 -73.82256)
		(width 0.381)
		(layer "B.Cu")
		(net "GND")
	)
	(segment
		(start 88.6968 -163.2204)
		(end 88.6968 -162.0266)
		(width 0.508)
		(layer "B.Cu")
		(net "GND")
	)
	(segment
		(start 204.131672 -68.748656)
		(end 204.115416 -68.7324)
		(width 0.254)
		(layer "B.Cu")
		(net "GND")
	)
	(segment
		(start 192.635632 -72.380856)
		(end 192.635632 -72.93483)
		(width 0.254)
		(layer "B.Cu")
		(net "GND")
	)
	(segment
		(start 45.466 -127.7747)
		(end 45.466 -126.9492)
		(width 0.508)
		(layer "B.Cu")
		(net "GND")
	)
	(segment
		(start 47.479966 -135.285734)
		(end 48.495966 -135.285734)
		(width 0.508)
		(layer "B.Cu")
		(net "GND")
	)
	(segment
		(start 198.00316 -68.712842)
		(end 198.390256 -69.099938)
		(width 0.3048)
		(layer "B.Cu")
		(net "GND")
	)
	(segment
		(start 203.6064 -78.613)
		(end 203.6064 -77.978)
		(width 0.254)
		(layer "B.Cu")
		(net "GND")
	)
	(segment
		(start 32.2199 -123.21286)
		(end 33.562544 -123.21286)
		(width 0.254)
		(layer "B.Cu")
		(net "GND")
	)
	(segment
		(start 215.5444 -122.301)
		(end 215.6587 -122.1867)
		(width 0.508)
		(layer "B.Cu")
		(net "GND")
	)
	(segment
		(start 47.4726 -135.2931)
		(end 47.479966 -135.285734)
		(width 0.508)
		(layer "B.Cu")
		(net "GND")
	)
	(segment
		(start 140.38834 -16.4338)
		(end 140.34516 -16.39062)
		(width 0.508)
		(layer "B.Cu")
		(net "GND")
	)
	(segment
		(start 194.09664 -53.4035)
		(end 193.60007 -53.90007)
		(width 0.508)
		(layer "B.Cu")
		(net "GND")
	)
	(segment
		(start 43.18127 -148.605494)
		(end 42.752264 -148.605494)
		(width 0.127)
		(layer "In2.Cu")
		(net "GND")
	)
	(segment
		(start 42.494454 -149.281134)
		(end 42.494454 -148.852128)
		(width 0.127)
		(layer "In2.Cu")
		(net "GND")
	)
	(segment
		(start 42.618914 -147.794218)
		(end 43.181016 -147.794218)
		(width 0.127)
		(layer "In2.Cu")
		(net "GND")
	)
	(segment
		(start 52.0954 -149.1996)
		(end 52.0954 -148.7678)
		(width 0.127)
		(layer "In5.Cu")
		(net "GND")
	)
	(segment
		(start 50.4952 -149.225)
		(end 50.4952 -148.7932)
		(width 0.127)
		(layer "In5.Cu")
		(net "GND")
	)
	(segment
		(start 52.8955 -149.9997)
		(end 52.8955 -148.604224)
		(width 0.127)
		(layer "In5.Cu")
		(net "GND")
	)
	(segment
		(start 52.8955 -148.604224)
		(end 53.299868 -148.199856)
		(width 0.254)
		(layer "In5.Cu")
		(net "GND")
	)
	(segment
		(start 51.2953 -149.2123)
		(end 51.2953 -148.7805)
		(width 0.127)
		(layer "In5.Cu")
		(net "GND")
	)
	(segment
		(start 52.8955 -148.604224)
		(end 52.198524 -148.604224)
		(width 0.127)
		(layer "In5.Cu")
		(net "GND")
	)
	(segment
		(start 74.90587 -138.914124)
		(end 76.32065 -138.914124)
		(width 0.127)
		(layer "F.Cu")
		(net "FP_PWR_BTN_N")
	)
	(segment
		(start 21.799804 -14.19479)
		(end 21.492464 -13.88745)
		(width 0.127)
		(layer "F.Cu")
		(net "FP_PWR_BTN_N")
	)
	(segment
		(start 24.7904 -13.92174)
		(end 24.7904 -13.93444)
		(width 0.127)
		(layer "F.Cu")
		(net "FP_PWR_BTN_N")
	)
	(segment
		(start 24.7904 -13.93444)
		(end 23.78456 -13.93444)
		(width 0.127)
		(layer "F.Cu")
		(net "FP_PWR_BTN_N")
	)
	(segment
		(start 23.52421 -14.19479)
		(end 22.614636 -14.19479)
		(width 0.127)
		(layer "F.Cu")
		(net "FP_PWR_BTN_N")
	)
	(segment
		(start 21.75002 -8.750046)
		(end 21.75002 -13.629894)
		(width 0.127)
		(layer "F.Cu")
		(net "FP_PWR_BTN_N")
	)
	(segment
		(start 23.78456 -13.93444)
		(end 23.52421 -14.19479)
		(width 0.127)
		(layer "F.Cu")
		(net "FP_PWR_BTN_N")
	)
	(segment
		(start 21.75002 -13.629894)
		(end 21.492464 -13.88745)
		(width 0.127)
		(layer "F.Cu")
		(net "FP_PWR_BTN_N")
	)
	(segment
		(start 22.614636 -14.19479)
		(end 21.799804 -14.19479)
		(width 0.127)
		(layer "F.Cu")
		(net "FP_PWR_BTN_N")
	)
	(segment
		(start 76.32065 -138.914124)
		(end 76.320904 -138.914378)
		(width 0.127)
		(layer "F.Cu")
		(net "FP_PWR_BTN_N")
	)
	(via
		(at 76.320904 -138.914378)
		(size 0.508)
		(drill 0.254)
		(layers "F.Cu" "B.Cu")
		(net "FP_PWR_BTN_N")
	)
	(via
		(at 24.7904 -13.92174)
		(size 0.508)
		(drill 0.254)
		(layers "F.Cu" "B.Cu")
		(net "FP_PWR_BTN_N")
	)
	(via
		(at 76.75245 -132.340604)
		(size 0.6096)
		(drill 0.3048)
		(layers "F.Cu" "B.Cu")
		(net "FP_PWR_BTN_N")
	)
	(via
		(at 29.05506 -115.10899)
		(size 0.508)
		(drill 0.254)
		(layers "F.Cu" "B.Cu")
		(net "FP_PWR_BTN_N")
	)
	(segment
		(start 76.320904 -133.531864)
		(end 76.320904 -138.914378)
		(width 0.127)
		(layer "B.Cu")
		(net "FP_PWR_BTN_N")
	)
	(segment
		(start 76.75245 -132.340604)
		(end 76.75245 -133.100318)
		(width 0.127)
		(layer "B.Cu")
		(net "FP_PWR_BTN_N")
	)
	(segment
		(start 72.32777 -127.604012)
		(end 63.736474 -127.604012)
		(width 0.127)
		(layer "B.Cu")
		(net "FP_PWR_BTN_N")
	)
	(segment
		(start 63.736474 -127.604012)
		(end 52.177188 -116.044726)
		(width 0.127)
		(layer "B.Cu")
		(net "FP_PWR_BTN_N")
	)
	(segment
		(start 76.75245 -132.028692)
		(end 72.32777 -127.604012)
		(width 0.127)
		(layer "B.Cu")
		(net "FP_PWR_BTN_N")
	)
	(segment
		(start 76.75245 -132.340604)
		(end 76.75245 -132.028692)
		(width 0.127)
		(layer "B.Cu")
		(net "FP_PWR_BTN_N")
	)
	(segment
		(start 76.75245 -133.100318)
		(end 76.320904 -133.531864)
		(width 0.127)
		(layer "B.Cu")
		(net "FP_PWR_BTN_N")
	)
	(segment
		(start 36.863274 -116.044726)
		(end 36.3474 -116.5606)
		(width 0.127)
		(layer "B.Cu")
		(net "FP_PWR_BTN_N")
	)
	(segment
		(start 36.3474 -116.5606)
		(end 30.50667 -116.5606)
		(width 0.127)
		(layer "B.Cu")
		(net "FP_PWR_BTN_N")
	)
	(segment
		(start 52.177188 -116.044726)
		(end 36.863274 -116.044726)
		(width 0.127)
		(layer "B.Cu")
		(net "FP_PWR_BTN_N")
	)
	(segment
		(start 30.50667 -116.5606)
		(end 29.05506 -115.10899)
		(width 0.127)
		(layer "B.Cu")
		(net "FP_PWR_BTN_N")
	)
	(segment
		(start 27.03195 -113.08588)
		(end 27.03195 -42.963338)
		(width 0.127)
		(layer "In2.Cu")
		(net "FP_PWR_BTN_N")
	)
	(segment
		(start 29.05506 -115.10899)
		(end 27.03195 -113.08588)
		(width 0.127)
		(layer "In2.Cu")
		(net "FP_PWR_BTN_N")
	)
	(segment
		(start 26.7335 -15.86484)
		(end 24.7904 -13.92174)
		(width 0.127)
		(layer "In2.Cu")
		(net "FP_PWR_BTN_N")
	)
	(segment
		(start 27.03195 -42.963338)
		(end 26.7335 -42.664888)
		(width 0.127)
		(layer "In2.Cu")
		(net "FP_PWR_BTN_N")
	)
	(segment
		(start 26.7335 -42.664888)
		(end 26.7335 -15.86484)
		(width 0.127)
		(layer "In2.Cu")
		(net "FP_PWR_BTN_N")
	)
	(segment
		(start 67.1195 -135.9154)
		(end 67.1195 -137.033)
		(width 0.127)
		(layer "F.Cu")
		(net "FP_PWRBTN")
	)
	(segment
		(start 68.953634 -137.033)
		(end 67.1195 -137.033)
		(width 0.127)
		(layer "F.Cu")
		(net "FP_PWRBTN")
	)
	(segment
		(start 69.65823 -137.737596)
		(end 69.271642 -137.351008)
		(width 0.127)
		(layer "F.Cu")
		(net "FP_PWRBTN")
	)
	(segment
		(start 68.4784 -135.0137)
		(end 68.0212 -135.0137)
		(width 0.127)
		(layer "F.Cu")
		(net "FP_PWRBTN")
	)
	(segment
		(start 69.65823 -138.895836)
		(end 69.65823 -137.737596)
		(width 0.127)
		(layer "F.Cu")
		(net "FP_PWRBTN")
	)
	(segment
		(start 68.0212 -135.0137)
		(end 67.1195 -135.9154)
		(width 0.127)
		(layer "F.Cu")
		(net "FP_PWRBTN")
	)
	(segment
		(start 69.271642 -137.351008)
		(end 68.953634 -137.033)
		(width 0.127)
		(layer "F.Cu")
		(net "FP_PWRBTN")
	)
	(via
		(at 69.271642 -137.351008)
		(size 0.6604)
		(drill 0.3302)
		(layers "F.Cu" "B.Cu")
		(net "FP_PWRBTN")
	)
	(segment
		(start 63.1444 -177.6222)
		(end 63.4619 -177.9397)
		(width 0.127)
		(layer "F.Cu")
		(net "FM_BMC_RESET_N")
	)
	(segment
		(start 63.126874 -175.964596)
		(end 63.126874 -177.604674)
		(width 0.127)
		(layer "F.Cu")
		(net "FM_BMC_RESET_N")
	)
	(segment
		(start 63.4619 -178.6128)
		(end 63.459868 -178.614832)
		(width 0.127)
		(layer "F.Cu")
		(net "FM_BMC_RESET_N")
	)
	(segment
		(start 63.459868 -179.64404)
		(end 64.007492 -179.64404)
		(width 0.127)
		(layer "F.Cu")
		(net "FM_BMC_RESET_N")
	)
	(segment
		(start 63.4619 -177.9397)
		(end 63.4619 -178.6128)
		(width 0.127)
		(layer "F.Cu")
		(net "FM_BMC_RESET_N")
	)
	(segment
		(start 64.007492 -179.64404)
		(end 64.311784 -179.339748)
		(width 0.127)
		(layer "F.Cu")
		(net "FM_BMC_RESET_N")
	)
	(segment
		(start 63.459868 -178.614832)
		(end 63.459868 -179.64404)
		(width 0.127)
		(layer "F.Cu")
		(net "FM_BMC_RESET_N")
	)
	(segment
		(start 63.126874 -177.604674)
		(end 63.1444 -177.6222)
		(width 0.127)
		(layer "F.Cu")
		(net "FM_BMC_RESET_N")
	)
	(via
		(at 70.265036 -126.570994)
		(size 0.508)
		(drill 0.254)
		(layers "F.Cu" "B.Cu")
		(net "FM_BMC_RESET_N")
	)
	(via
		(at 70.807326 -177.977038)
		(size 0.508)
		(drill 0.254)
		(layers "F.Cu" "B.Cu")
		(net "FM_BMC_RESET_N")
	)
	(via
		(at 64.311784 -179.339748)
		(size 0.508)
		(drill 0.254)
		(layers "F.Cu" "B.Cu")
		(net "FM_BMC_RESET_N")
	)
	(via
		(at 42.3418 -126.9492)
		(size 0.508)
		(drill 0.254)
		(layers "F.Cu" "B.Cu")
		(net "FM_BMC_RESET_N")
	)
	(via
		(at 63.1444 -177.6222)
		(size 0.6604)
		(drill 0.3302)
		(layers "F.Cu" "B.Cu")
		(net "FM_BMC_RESET_N")
	)
	(segment
		(start 41.3512 -125.5649)
		(end 41.3512 -125.7046)
		(width 0.127)
		(layer "B.Cu")
		(net "FM_BMC_RESET_N")
	)
	(segment
		(start 42.377614 -125.5649)
		(end 41.3512 -125.5649)
		(width 0.127)
		(layer "B.Cu")
		(net "FM_BMC_RESET_N")
	)
	(segment
		(start 42.382694 -125.56998)
		(end 42.377614 -125.5649)
		(width 0.127)
		(layer "B.Cu")
		(net "FM_BMC_RESET_N")
	)
	(segment
		(start 42.382694 -126.028196)
		(end 42.382694 -125.56998)
		(width 0.127)
		(layer "B.Cu")
		(net "FM_BMC_RESET_N")
	)
	(segment
		(start 42.3418 -126.9492)
		(end 42.3418 -126.06909)
		(width 0.127)
		(layer "B.Cu")
		(net "FM_BMC_RESET_N")
	)
	(segment
		(start 42.3418 -126.06909)
		(end 42.382694 -126.028196)
		(width 0.127)
		(layer "B.Cu")
		(net "FM_BMC_RESET_N")
	)
	(segment
		(start 42.3418 -127.7747)
		(end 42.3418 -126.9492)
		(width 0.127)
		(layer "B.Cu")
		(net "FM_BMC_RESET_N")
	)
	(segment
		(start 41.3512 -125.7046)
		(end 40.4876 -126.5682)
		(width 0.127)
		(layer "B.Cu")
		(net "FM_BMC_RESET_N")
	)
	(segment
		(start 72.7456 -161.381186)
		(end 72.4408 -161.076386)
		(width 0.127)
		(layer "In2.Cu")
		(net "FM_BMC_RESET_N")
	)
	(segment
		(start 70.3326 -135.894064)
		(end 70.096126 -135.65759)
		(width 0.127)
		(layer "In2.Cu")
		(net "FM_BMC_RESET_N")
	)
	(segment
		(start 72.7456 -173.232318)
		(end 72.7456 -161.381186)
		(width 0.127)
		(layer "In2.Cu")
		(net "FM_BMC_RESET_N")
	)
	(segment
		(start 73.579736 -153.907744)
		(end 73.579736 -153.90749)
		(width 0.127)
		(layer "In2.Cu")
		(net "FM_BMC_RESET_N")
	)
	(segment
		(start 72.19061 -143.312134)
		(end 71.79818 -142.919704)
		(width 0.127)
		(layer "In2.Cu")
		(net "FM_BMC_RESET_N")
	)
	(segment
		(start 70.096126 -135.65759)
		(end 70.096126 -129.24917)
		(width 0.127)
		(layer "In2.Cu")
		(net "FM_BMC_RESET_N")
	)
	(segment
		(start 73.579736 -153.90749)
		(end 72.51954 -152.847294)
		(width 0.127)
		(layer "In2.Cu")
		(net "FM_BMC_RESET_N")
	)
	(segment
		(start 70.807326 -175.170592)
		(end 72.7456 -173.232318)
		(width 0.127)
		(layer "In2.Cu")
		(net "FM_BMC_RESET_N")
	)
	(segment
		(start 70.096126 -129.24917)
		(end 70.265036 -129.08026)
		(width 0.127)
		(layer "In2.Cu")
		(net "FM_BMC_RESET_N")
	)
	(segment
		(start 74.45502 -158.185104)
		(end 74.45502 -154.783028)
		(width 0.127)
		(layer "In2.Cu")
		(net "FM_BMC_RESET_N")
	)
	(segment
		(start 72.4408 -160.199324)
		(end 74.45502 -158.185104)
		(width 0.127)
		(layer "In2.Cu")
		(net "FM_BMC_RESET_N")
	)
	(segment
		(start 72.51954 -152.847294)
		(end 72.51954 -145.412968)
		(width 0.127)
		(layer "In2.Cu")
		(net "FM_BMC_RESET_N")
	)
	(segment
		(start 71.79818 -141.365478)
		(end 71.08952 -140.656818)
		(width 0.127)
		(layer "In2.Cu")
		(net "FM_BMC_RESET_N")
	)
	(segment
		(start 70.265036 -129.08026)
		(end 70.265036 -126.570994)
		(width 0.127)
		(layer "In2.Cu")
		(net "FM_BMC_RESET_N")
	)
	(segment
		(start 71.79818 -142.919704)
		(end 71.79818 -141.365478)
		(width 0.127)
		(layer "In2.Cu")
		(net "FM_BMC_RESET_N")
	)
	(segment
		(start 72.4408 -161.076386)
		(end 72.4408 -160.199324)
		(width 0.127)
		(layer "In2.Cu")
		(net "FM_BMC_RESET_N")
	)
	(segment
		(start 70.3326 -136.245854)
		(end 70.3326 -135.894064)
		(width 0.127)
		(layer "In2.Cu")
		(net "FM_BMC_RESET_N")
	)
	(segment
		(start 74.45502 -154.783028)
		(end 73.579736 -153.907744)
		(width 0.127)
		(layer "In2.Cu")
		(net "FM_BMC_RESET_N")
	)
	(segment
		(start 72.19061 -145.084038)
		(end 72.19061 -143.312134)
		(width 0.127)
		(layer "In2.Cu")
		(net "FM_BMC_RESET_N")
	)
	(segment
		(start 72.51954 -145.412968)
		(end 72.19061 -145.084038)
		(width 0.127)
		(layer "In2.Cu")
		(net "FM_BMC_RESET_N")
	)
	(segment
		(start 71.08952 -137.002774)
		(end 70.3326 -136.245854)
		(width 0.127)
		(layer "In2.Cu")
		(net "FM_BMC_RESET_N")
	)
	(segment
		(start 70.807326 -177.977038)
		(end 70.807326 -175.170592)
		(width 0.127)
		(layer "In2.Cu")
		(net "FM_BMC_RESET_N")
	)
	(segment
		(start 71.08952 -140.656818)
		(end 71.08952 -137.002774)
		(width 0.127)
		(layer "In2.Cu")
		(net "FM_BMC_RESET_N")
	)
	(segment
		(start 70.206616 -126.512574)
		(end 70.265036 -126.570994)
		(width 0.127)
		(layer "In5.Cu")
		(net "FM_BMC_RESET_N")
	)
	(segment
		(start 51.13782 -128.016)
		(end 52.030884 -127.122936)
		(width 0.127)
		(layer "In5.Cu")
		(net "FM_BMC_RESET_N")
	)
	(segment
		(start 67.22872 -178.2953)
		(end 66.184272 -179.339748)
		(width 0.127)
		(layer "In5.Cu")
		(net "FM_BMC_RESET_N")
	)
	(segment
		(start 43.4086 -128.016)
		(end 51.13782 -128.016)
		(width 0.127)
		(layer "In5.Cu")
		(net "FM_BMC_RESET_N")
	)
	(segment
		(start 42.3418 -126.9492)
		(end 43.4086 -128.016)
		(width 0.127)
		(layer "In5.Cu")
		(net "FM_BMC_RESET_N")
	)
	(segment
		(start 55.670958 -126.360174)
		(end 68.27774 -126.360174)
		(width 0.127)
		(layer "In5.Cu")
		(net "FM_BMC_RESET_N")
	)
	(segment
		(start 70.231 -177.9778)
		(end 69.8754 -177.6222)
		(width 0.127)
		(layer "In5.Cu")
		(net "FM_BMC_RESET_N")
	)
	(segment
		(start 70.790562 -177.977038)
		(end 70.7898 -177.9778)
		(width 0.127)
		(layer "In5.Cu")
		(net "FM_BMC_RESET_N")
	)
	(segment
		(start 69.24294 -177.6222)
		(end 68.697094 -178.168046)
		(width 0.127)
		(layer "In5.Cu")
		(net "FM_BMC_RESET_N")
	)
	(segment
		(start 70.807326 -177.977038)
		(end 70.790562 -177.977038)
		(width 0.127)
		(layer "In5.Cu")
		(net "FM_BMC_RESET_N")
	)
	(segment
		(start 70.7898 -177.9778)
		(end 70.231 -177.9778)
		(width 0.127)
		(layer "In5.Cu")
		(net "FM_BMC_RESET_N")
	)
	(segment
		(start 69.8754 -177.6222)
		(end 69.24294 -177.6222)
		(width 0.127)
		(layer "In5.Cu")
		(net "FM_BMC_RESET_N")
	)
	(segment
		(start 54.908196 -127.122936)
		(end 55.670958 -126.360174)
		(width 0.127)
		(layer "In5.Cu")
		(net "FM_BMC_RESET_N")
	)
	(segment
		(start 68.43014 -126.512574)
		(end 70.206616 -126.512574)
		(width 0.127)
		(layer "In5.Cu")
		(net "FM_BMC_RESET_N")
	)
	(segment
		(start 68.570094 -178.2953)
		(end 67.22872 -178.2953)
		(width 0.127)
		(layer "In5.Cu")
		(net "FM_BMC_RESET_N")
	)
	(segment
		(start 66.184272 -179.339748)
		(end 64.311784 -179.339748)
		(width 0.127)
		(layer "In5.Cu")
		(net "FM_BMC_RESET_N")
	)
	(segment
		(start 68.27774 -126.360174)
		(end 68.43014 -126.512574)
		(width 0.127)
		(layer "In5.Cu")
		(net "FM_BMC_RESET_N")
	)
	(segment
		(start 68.697094 -178.1683)
		(end 68.570094 -178.2953)
		(width 0.127)
		(layer "In5.Cu")
		(net "FM_BMC_RESET_N")
	)
	(segment
		(start 68.697094 -178.168046)
		(end 68.697094 -178.1683)
		(width 0.127)
		(layer "In5.Cu")
		(net "FM_BMC_RESET_N")
	)
	(segment
		(start 52.030884 -127.122936)
		(end 54.908196 -127.122936)
		(width 0.127)
		(layer "In5.Cu")
		(net "FM_BMC_RESET_N")
	)
	(segment
		(start 98.440494 -136.629394)
		(end 97.9424 -136.1313)
		(width 0.127)
		(layer "F.Cu")
		(net "EEPROM_WP")
	)
	(segment
		(start 98.440494 -137.385806)
		(end 98.440494 -136.629394)
		(width 0.127)
		(layer "F.Cu")
		(net "EEPROM_WP")
	)
	(segment
		(start 96.858074 -135.046974)
		(end 97.9424 -136.1313)
		(width 0.127)
		(layer "F.Cu")
		(net "EEPROM_WP")
	)
	(segment
		(start 96.288352 -135.046974)
		(end 96.858074 -135.046974)
		(width 0.127)
		(layer "F.Cu")
		(net "EEPROM_WP")
	)
	(via
		(at 98.440494 -137.385806)
		(size 0.6604)
		(drill 0.3302)
		(layers "F.Cu" "B.Cu")
		(net "EEPROM_WP")
	)
	(segment
		(start 43.688 -146.5961)
		(end 43.696382 -146.5961)
		(width 0.3302)
		(layer "F.Cu")
		(net "DDR_VREF")
	)
	(segment
		(start 43.696382 -146.5961)
		(end 44.099988 -146.999706)
		(width 0.3302)
		(layer "F.Cu")
		(net "DDR_VREF")
	)
	(segment
		(start 15.881858 -139.761468)
		(end 15.818104 -139.825222)
		(width 0.254)
		(layer "F.Cu")
		(net "DDR_VREF")
	)
	(segment
		(start 44.099988 -146.999706)
		(end 44.099988 -146.99996)
		(width 0.3302)
		(layer "F.Cu")
		(net "DDR_VREF")
	)
	(segment
		(start 16.834612 -139.761468)
		(end 15.881858 -139.761468)
		(width 0.254)
		(layer "F.Cu")
		(net "DDR_VREF")
	)
	(via
		(at 15.818104 -139.825222)
		(size 0.508)
		(drill 0.254)
		(layers "F.Cu" "B.Cu")
		(net "DDR_VREF")
	)
	(via
		(at 38.692328 -148.162772)
		(size 0.6096)
		(drill 0.3048)
		(layers "F.Cu" "B.Cu")
		(net "DDR_VREF")
	)
	(via
		(at 43.688 -146.5961)
		(size 0.4572)
		(drill 0.2032)
		(layers "F.Cu" "B.Cu")
		(net "DDR_VREF")
	)
	(segment
		(start 39.420292 -146.078956)
		(end 39.1541 -146.345148)
		(width 0.381)
		(layer "B.Cu")
		(net "DDR_VREF")
	)
	(segment
		(start 16.057626 -139.5857)
		(end 15.818104 -139.825222)
		(width 0.508)
		(layer "B.Cu")
		(net "DDR_VREF")
	)
	(segment
		(start 39.1541 -146.345148)
		(end 39.1541 -147.701)
		(width 0.381)
		(layer "B.Cu")
		(net "DDR_VREF")
	)
	(segment
		(start 37.2745 -148.513546)
		(end 36.564316 -148.513546)
		(width 0.508)
		(layer "B.Cu")
		(net "DDR_VREF")
	)
	(segment
		(start 38.692328 -148.162772)
		(end 38.341554 -148.513546)
		(width 0.381)
		(layer "B.Cu")
		(net "DDR_VREF")
	)
	(segment
		(start 36.564316 -148.513546)
		(end 35.862006 -149.215856)
		(width 0.508)
		(layer "B.Cu")
		(net "DDR_VREF")
	)
	(segment
		(start 16.6116 -139.5857)
		(end 16.057626 -139.5857)
		(width 0.508)
		(layer "B.Cu")
		(net "DDR_VREF")
	)
	(segment
		(start 43.08475 -146.078956)
		(end 39.420292 -146.078956)
		(width 0.381)
		(layer "B.Cu")
		(net "DDR_VREF")
	)
	(segment
		(start 39.1541 -147.701)
		(end 38.692328 -148.162772)
		(width 0.381)
		(layer "B.Cu")
		(net "DDR_VREF")
	)
	(segment
		(start 35.862006 -149.215856)
		(end 35.862006 -149.996398)
		(width 0.508)
		(layer "B.Cu")
		(net "DDR_VREF")
	)
	(segment
		(start 38.341554 -148.513546)
		(end 37.2745 -148.513546)
		(width 0.381)
		(layer "B.Cu")
		(net "DDR_VREF")
	)
	(segment
		(start 49.299622 -151.400002)
		(end 49.299622 -151.399748)
		(width 0.1778)
		(layer "F.Cu")
		(net "DACRSET")
	)
	(segment
		(start 48.87722 -164.4523)
		(end 49.40046 -163.92906)
		(width 0.1778)
		(layer "F.Cu")
		(net "DACRSET")
	)
	(segment
		(start 49.299622 -151.399748)
		(end 48.899826 -150.999952)
		(width 0.1778)
		(layer "F.Cu")
		(net "DACRSET")
	)
	(segment
		(start 47.8536 -164.4523)
		(end 48.87722 -164.4523)
		(width 0.1778)
		(layer "F.Cu")
		(net "DACRSET")
	)
	(via
		(at 49.40046 -163.92906)
		(size 0.508)
		(drill 0.254)
		(layers "F.Cu" "B.Cu")
		(net "DACRSET")
	)
	(via
		(at 49.299622 -151.400002)
		(size 0.4572)
		(drill 0.2032)
		(layers "F.Cu" "B.Cu")
		(net "DACRSET")
	)
	(segment
		(start 49.53 -155.16098)
		(end 49.53 -157.594046)
		(width 0.1778)
		(layer "In2.Cu")
		(net "DACRSET")
	)
	(segment
		(start 50.543206 -163.756594)
		(end 49.572926 -163.756594)
		(width 0.1778)
		(layer "In2.Cu")
		(net "DACRSET")
	)
	(segment
		(start 49.572926 -163.756594)
		(end 49.40046 -163.92906)
		(width 0.1778)
		(layer "In2.Cu")
		(net "DACRSET")
	)
	(segment
		(start 49.53 -157.594046)
		(end 51.6763 -159.740346)
		(width 0.1778)
		(layer "In2.Cu")
		(net "DACRSET")
	)
	(segment
		(start 51.12512 -163.16706)
		(end 50.543206 -163.748974)
		(width 0.1778)
		(layer "In2.Cu")
		(net "DACRSET")
	)
	(segment
		(start 49.7205 -151.82088)
		(end 49.7205 -152.02789)
		(width 0.1778)
		(layer "In2.Cu")
		(net "DACRSET")
	)
	(segment
		(start 51.204114 -163.16706)
		(end 51.12512 -163.16706)
		(width 0.1778)
		(layer "In2.Cu")
		(net "DACRSET")
	)
	(segment
		(start 50.518822 -154.172158)
		(end 49.53 -155.16098)
		(width 0.1778)
		(layer "In2.Cu")
		(net "DACRSET")
	)
	(segment
		(start 50.518822 -152.826212)
		(end 50.518822 -154.172158)
		(width 0.1778)
		(layer "In2.Cu")
		(net "DACRSET")
	)
	(segment
		(start 49.299622 -151.400002)
		(end 49.7205 -151.82088)
		(width 0.1778)
		(layer "In2.Cu")
		(net "DACRSET")
	)
	(segment
		(start 50.543206 -163.748974)
		(end 50.543206 -163.756594)
		(width 0.1778)
		(layer "In2.Cu")
		(net "DACRSET")
	)
	(segment
		(start 49.7205 -152.02789)
		(end 50.518822 -152.826212)
		(width 0.1778)
		(layer "In2.Cu")
		(net "DACRSET")
	)
	(segment
		(start 51.6763 -159.740346)
		(end 51.6763 -162.694874)
		(width 0.1778)
		(layer "In2.Cu")
		(net "DACRSET")
	)
	(segment
		(start 51.6763 -162.694874)
		(end 51.204114 -163.16706)
		(width 0.1778)
		(layer "In2.Cu")
		(net "DACRSET")
	)
	(segment
		(start 175.751236 -68.067936)
		(end 176.3141 -68.067936)
		(width 0.127)
		(layer "F.Cu")
		(net "CP_DONE")
	)
	(segment
		(start 175.0187 -67.3354)
		(end 175.751236 -68.067936)
		(width 0.127)
		(layer "F.Cu")
		(net "CP_DONE")
	)
	(segment
		(start 178.173634 -67.1068)
		(end 177.818034 -67.4624)
		(width 0.127)
		(layer "F.Cu")
		(net "CP_DONE")
	)
	(segment
		(start 181.200044 -66.299842)
		(end 179.92471 -66.299842)
		(width 0.127)
		(layer "F.Cu")
		(net "CP_DONE")
	)
	(segment
		(start 179.117752 -67.1068)
		(end 178.173634 -67.1068)
		(width 0.127)
		(layer "F.Cu")
		(net "CP_DONE")
	)
	(segment
		(start 177.818034 -67.4624)
		(end 177.440336 -67.4624)
		(width 0.127)
		(layer "F.Cu")
		(net "CP_DONE")
	)
	(segment
		(start 177.440336 -67.4624)
		(end 176.8348 -68.067936)
		(width 0.127)
		(layer "F.Cu")
		(net "CP_DONE")
	)
	(segment
		(start 176.8348 -68.067936)
		(end 176.3141 -68.067936)
		(width 0.127)
		(layer "F.Cu")
		(net "CP_DONE")
	)
	(segment
		(start 179.92471 -66.299842)
		(end 179.117752 -67.1068)
		(width 0.127)
		(layer "F.Cu")
		(net "CP_DONE")
	)
	(via
		(at 176.3141 -68.067936)
		(size 0.6604)
		(drill 0.3302)
		(layers "F.Cu" "B.Cu")
		(net "CP_DONE")
	)
	(segment
		(start 56.97982 -152.246584)
		(end 56.8706 -152.137364)
		(width 0.127)
		(layer "F.Cu")
		(net "CLK_50M_BMC_NCSI")
	)
	(segment
		(start 69.8754 -153.0096)
		(end 68.58 -153.0096)
		(width 0.127)
		(layer "F.Cu")
		(net "CLK_50M_BMC_NCSI")
	)
	(segment
		(start 69.9516 -153.0858)
		(end 69.8754 -153.0096)
		(width 0.127)
		(layer "F.Cu")
		(net "CLK_50M_BMC_NCSI")
	)
	(segment
		(start 57.725056 -153.43886)
		(end 56.97982 -152.693624)
		(width 0.127)
		(layer "F.Cu")
		(net "CLK_50M_BMC_NCSI")
	)
	(segment
		(start 56.8706 -152.137364)
		(end 56.8706 -152.0317)
		(width 0.127)
		(layer "F.Cu")
		(net "CLK_50M_BMC_NCSI")
	)
	(segment
		(start 58.368184 -154.966416)
		(end 57.725056 -154.323288)
		(width 0.127)
		(layer "F.Cu")
		(net "CLK_50M_BMC_NCSI")
	)
	(segment
		(start 56.8706 -152.0317)
		(end 56.239664 -151.400764)
		(width 0.127)
		(layer "F.Cu")
		(net "CLK_50M_BMC_NCSI")
	)
	(segment
		(start 55.700676 -151.400764)
		(end 55.299864 -150.999952)
		(width 0.127)
		(layer "F.Cu")
		(net "CLK_50M_BMC_NCSI")
	)
	(segment
		(start 56.97982 -152.693624)
		(end 56.97982 -152.246584)
		(width 0.127)
		(layer "F.Cu")
		(net "CLK_50M_BMC_NCSI")
	)
	(segment
		(start 57.725056 -154.323288)
		(end 57.725056 -153.43886)
		(width 0.127)
		(layer "F.Cu")
		(net "CLK_50M_BMC_NCSI")
	)
	(segment
		(start 56.239664 -151.400764)
		(end 55.700676 -151.400764)
		(width 0.127)
		(layer "F.Cu")
		(net "CLK_50M_BMC_NCSI")
	)
	(via
		(at 68.58 -153.0096)
		(size 0.508)
		(drill 0.254)
		(layers "F.Cu" "B.Cu")
		(net "CLK_50M_BMC_NCSI")
	)
	(via
		(at 63.4238 -155.85186)
		(size 0.6096)
		(drill 0.3048)
		(layers "F.Cu" "B.Cu")
		(net "CLK_50M_BMC_NCSI")
	)
	(via
		(at 58.368184 -154.966416)
		(size 0.508)
		(drill 0.254)
		(layers "F.Cu" "B.Cu")
		(net "CLK_50M_BMC_NCSI")
	)
	(segment
		(start 58.97372 -154.93238)
		(end 58.40222 -154.93238)
		(width 0.127)
		(layer "B.Cu")
		(net "CLK_50M_BMC_NCSI")
	)
	(segment
		(start 68.24599 -152.67559)
		(end 65.291208 -152.67559)
		(width 0.127)
		(layer "B.Cu")
		(net "CLK_50M_BMC_NCSI")
	)
	(segment
		(start 65.291208 -152.67559)
		(end 65.041526 -152.925272)
		(width 0.127)
		(layer "B.Cu")
		(net "CLK_50M_BMC_NCSI")
	)
	(segment
		(start 64.00038 -155.85186)
		(end 63.4238 -155.85186)
		(width 0.127)
		(layer "B.Cu")
		(net "CLK_50M_BMC_NCSI")
	)
	(segment
		(start 59.97194 -155.9306)
		(end 58.97372 -154.93238)
		(width 0.127)
		(layer "B.Cu")
		(net "CLK_50M_BMC_NCSI")
	)
	(segment
		(start 58.40222 -154.93238)
		(end 58.368184 -154.966416)
		(width 0.127)
		(layer "B.Cu")
		(net "CLK_50M_BMC_NCSI")
	)
	(segment
		(start 65.041526 -152.925272)
		(end 65.041526 -154.810714)
		(width 0.127)
		(layer "B.Cu")
		(net "CLK_50M_BMC_NCSI")
	)
	(segment
		(start 65.041526 -154.810714)
		(end 64.00038 -155.85186)
		(width 0.127)
		(layer "B.Cu")
		(net "CLK_50M_BMC_NCSI")
	)
	(segment
		(start 63.4238 -155.85186)
		(end 63.34506 -155.9306)
		(width 0.127)
		(layer "B.Cu")
		(net "CLK_50M_BMC_NCSI")
	)
	(segment
		(start 68.58 -153.0096)
		(end 68.24599 -152.67559)
		(width 0.127)
		(layer "B.Cu")
		(net "CLK_50M_BMC_NCSI")
	)
	(segment
		(start 63.34506 -155.9306)
		(end 59.97194 -155.9306)
		(width 0.127)
		(layer "B.Cu")
		(net "CLK_50M_BMC_NCSI")
	)
	(segment
		(start 43.299888 -139.799822)
		(end 43.299888 -139.800076)
		(width 0.127)
		(layer "F.Cu")
		(net "BMC0_SRST_N")
	)
	(segment
		(start 42.900092 -139.400026)
		(end 43.299888 -139.799822)
		(width 0.127)
		(layer "F.Cu")
		(net "BMC0_SRST_N")
	)
	(via
		(at 43.558968 -126.088902)
		(size 0.6096)
		(drill 0.3048)
		(layers "F.Cu" "B.Cu")
		(net "BMC0_SRST_N")
	)
	(via
		(at 42.900092 -139.400026)
		(size 0.4572)
		(drill 0.2032)
		(layers "F.Cu" "B.Cu")
		(net "BMC0_SRST_N")
	)
	(via
		(at 42.3164 -129.4892)
		(size 0.508)
		(drill 0.254)
		(layers "F.Cu" "B.Cu")
		(net "BMC0_SRST_N")
	)
	(segment
		(start 42.3164 -129.4892)
		(end 42.3418 -129.4638)
		(width 0.127)
		(layer "B.Cu")
		(net "BMC0_SRST_N")
	)
	(segment
		(start 42.3418 -129.4638)
		(end 42.3418 -128.6637)
		(width 0.127)
		(layer "B.Cu")
		(net "BMC0_SRST_N")
	)
	(segment
		(start 42.8117 -126.83617)
		(end 42.8117 -128.2319)
		(width 0.127)
		(layer "B.Cu")
		(net "BMC0_SRST_N")
	)
	(segment
		(start 42.8117 -128.2319)
		(end 42.3799 -128.6637)
		(width 0.127)
		(layer "B.Cu")
		(net "BMC0_SRST_N")
	)
	(segment
		(start 42.3799 -128.6637)
		(end 42.3418 -128.6637)
		(width 0.127)
		(layer "B.Cu")
		(net "BMC0_SRST_N")
	)
	(segment
		(start 43.558968 -126.088902)
		(end 42.8117 -126.83617)
		(width 0.127)
		(layer "B.Cu")
		(net "BMC0_SRST_N")
	)
	(segment
		(start 43.2054 -132.778246)
		(end 43.2054 -134.9502)
		(width 0.127)
		(layer "In2.Cu")
		(net "BMC0_SRST_N")
	)
	(segment
		(start 43.274742 -139.025376)
		(end 42.900092 -139.400026)
		(width 0.0889)
		(layer "In2.Cu")
		(net "BMC0_SRST_N")
	)
	(segment
		(start 43.2054 -134.9502)
		(end 43.5229 -135.2677)
		(width 0.127)
		(layer "In2.Cu")
		(net "BMC0_SRST_N")
	)
	(segment
		(start 42.3164 -129.4892)
		(end 41.8465 -129.9591)
		(width 0.127)
		(layer "In2.Cu")
		(net "BMC0_SRST_N")
	)
	(segment
		(start 43.274742 -137.3632)
		(end 43.274742 -139.025376)
		(width 0.0889)
		(layer "In2.Cu")
		(net "BMC0_SRST_N")
	)
	(segment
		(start 43.5229 -137.115042)
		(end 43.274742 -137.3632)
		(width 0.127)
		(layer "In2.Cu")
		(net "BMC0_SRST_N")
	)
	(segment
		(start 41.8465 -131.419346)
		(end 43.2054 -132.778246)
		(width 0.127)
		(layer "In2.Cu")
		(net "BMC0_SRST_N")
	)
	(segment
		(start 43.5229 -135.2677)
		(end 43.5229 -137.115042)
		(width 0.127)
		(layer "In2.Cu")
		(net "BMC0_SRST_N")
	)
	(segment
		(start 41.8465 -129.9591)
		(end 41.8465 -131.419346)
		(width 0.127)
		(layer "In2.Cu")
		(net "BMC0_SRST_N")
	)
	(segment
		(start 54.500018 -147.000214)
		(end 54.500018 -146.99996)
		(width 0.127)
		(layer "F.Cu")
		(net "BMC0_JTAG_RTCK")
	)
	(segment
		(start 54.899814 -147.40001)
		(end 54.500018 -147.000214)
		(width 0.127)
		(layer "F.Cu")
		(net "BMC0_JTAG_RTCK")
	)
	(via
		(at 54.899814 -147.40001)
		(size 0.4572)
		(drill 0.2032)
		(layers "F.Cu" "B.Cu")
		(net "BMC0_JTAG_RTCK")
	)
	(segment
		(start 55.416196 -147.916392)
		(end 55.74919 -147.916392)
		(width 0.127)
		(layer "B.Cu")
		(net "BMC0_JTAG_RTCK")
	)
	(segment
		(start 55.74919 -147.916392)
		(end 56.747664 -147.916392)
		(width 0.127)
		(layer "B.Cu")
		(net "BMC0_JTAG_RTCK")
	)
	(segment
		(start 54.899814 -147.40001)
		(end 55.416196 -147.916392)
		(width 0.127)
		(layer "B.Cu")
		(net "BMC0_JTAG_RTCK")
	)
	(segment
		(start 56.747664 -147.916392)
		(end 56.920892 -147.743164)
		(width 0.127)
		(layer "B.Cu")
		(net "BMC0_JTAG_RTCK")
	)
	(segment
		(start 194.385692 -53.885592)
		(end 194.799966 -54.299866)
		(width 0.2032)
		(layer "F.Cu")
		(net "AVSO_VREF")
	)
	(segment
		(start 194.385692 -52.948332)
		(end 194.385692 -53.885592)
		(width 0.2032)
		(layer "F.Cu")
		(net "AVSO_VREF")
	)
	(segment
		(start 194.2846 -52.84724)
		(end 194.385692 -52.948332)
		(width 0.2032)
		(layer "F.Cu")
		(net "AVSO_VREF")
	)
	(segment
		(start 194.2846 -52.6288)
		(end 194.2846 -52.84724)
		(width 0.2032)
		(layer "F.Cu")
		(net "AVSO_VREF")
	)
	(via
		(at 196.7738 -122.8344)
		(size 0.508)
		(drill 0.254)
		(layers "F.Cu" "B.Cu")
		(net "AVSO_VREF")
	)
	(via
		(at 194.2846 -52.6288)
		(size 0.508)
		(drill 0.254)
		(layers "F.Cu" "B.Cu")
		(net "AVSO_VREF")
	)
	(via
		(at 191.7954 -123.6218)
		(size 0.6096)
		(drill 0.3048)
		(layers "F.Cu" "B.Cu")
		(net "AVSO_VREF")
	)
	(via
		(at 216.1413 -124.2822)
		(size 0.508)
		(drill 0.254)
		(layers "F.Cu" "B.Cu")
		(net "AVSO_VREF")
	)
	(via
		(at 211.365592 -51.928776)
		(size 0.508)
		(drill 0.254)
		(layers "F.Cu" "B.Cu")
		(net "AVSO_VREF")
	)
	(segment
		(start 191.7954 -123.6218)
		(end 191.8208 -123.5964)
		(width 0.254)
		(layer "B.Cu")
		(net "AVSO_VREF")
	)
	(segment
		(start 191.2493 -124.1679)
		(end 191.7954 -123.6218)
		(width 0.254)
		(layer "B.Cu")
		(net "AVSO_VREF")
	)
	(segment
		(start 195.0466 -123.5964)
		(end 195.8086 -122.8344)
		(width 0.254)
		(layer "B.Cu")
		(net "AVSO_VREF")
	)
	(segment
		(start 190.6524 -124.1679)
		(end 191.2493 -124.1679)
		(width 0.254)
		(layer "B.Cu")
		(net "AVSO_VREF")
	)
	(segment
		(start 193.0146 -123.5964)
		(end 195.0466 -123.5964)
		(width 0.254)
		(layer "B.Cu")
		(net "AVSO_VREF")
	)
	(segment
		(start 191.8208 -123.5964)
		(end 193.0146 -123.5964)
		(width 0.254)
		(layer "B.Cu")
		(net "AVSO_VREF")
	)
	(segment
		(start 195.8086 -122.8344)
		(end 196.7738 -122.8344)
		(width 0.254)
		(layer "B.Cu")
		(net "AVSO_VREF")
	)
	(segment
		(start 216.7128 -103.72598)
		(end 216.7128 -103.28402)
		(width 0.254)
		(layer "In2.Cu")
		(net "AVSO_VREF")
	)
	(segment
		(start 216.5604 -105.18013)
		(end 216.5604 -103.87838)
		(width 0.254)
		(layer "In2.Cu")
		(net "AVSO_VREF")
	)
	(segment
		(start 216.627964 -105.247694)
		(end 216.5604 -105.18013)
		(width 0.254)
		(layer "In2.Cu")
		(net "AVSO_VREF")
	)
	(segment
		(start 216.5604 -103.87838)
		(end 216.7128 -103.72598)
		(width 0.254)
		(layer "In2.Cu")
		(net "AVSO_VREF")
	)
	(segment
		(start 219.724478 -60.287662)
		(end 211.365592 -51.928776)
		(width 0.254)
		(layer "In2.Cu")
		(net "AVSO_VREF")
	)
	(segment
		(start 216.5604 -103.13162)
		(end 216.5604 -90.294968)
		(width 0.254)
		(layer "In2.Cu")
		(net "AVSO_VREF")
	)
	(segment
		(start 216.7128 -103.28402)
		(end 216.5604 -103.13162)
		(width 0.254)
		(layer "In2.Cu")
		(net "AVSO_VREF")
	)
	(segment
		(start 216.1413 -124.2822)
		(end 216.763092 -123.660408)
		(width 0.254)
		(layer "In2.Cu")
		(net "AVSO_VREF")
	)
	(segment
		(start 216.5604 -90.294968)
		(end 216.624916 -90.230452)
		(width 0.254)
		(layer "In2.Cu")
		(net "AVSO_VREF")
	)
	(segment
		(start 216.763092 -123.660408)
		(end 216.763092 -105.392982)
		(width 0.254)
		(layer "In2.Cu")
		(net "AVSO_VREF")
	)
	(segment
		(start 216.624916 -90.230452)
		(end 216.624916 -80.925924)
		(width 0.254)
		(layer "In2.Cu")
		(net "AVSO_VREF")
	)
	(segment
		(start 216.763092 -105.392982)
		(end 216.627964 -105.257854)
		(width 0.254)
		(layer "In2.Cu")
		(net "AVSO_VREF")
	)
	(segment
		(start 216.627964 -105.257854)
		(end 216.627964 -105.247694)
		(width 0.254)
		(layer "In2.Cu")
		(net "AVSO_VREF")
	)
	(segment
		(start 216.624916 -80.925924)
		(end 219.724478 -77.826362)
		(width 0.254)
		(layer "In2.Cu")
		(net "AVSO_VREF")
	)
	(segment
		(start 219.724478 -77.826362)
		(end 219.724478 -60.287662)
		(width 0.254)
		(layer "In2.Cu")
		(net "AVSO_VREF")
	)
	(segment
		(start 196.7738 -122.8344)
		(end 200.80478 -122.8344)
		(width 0.254)
		(layer "In5.Cu")
		(net "AVSO_VREF")
	)
	(segment
		(start 211.795106 -51.499262)
		(end 211.795106 -50.200306)
		(width 0.254)
		(layer "In5.Cu")
		(net "AVSO_VREF")
	)
	(segment
		(start 207.396334 -50.898806)
		(end 194.769994 -50.898806)
		(width 0.254)
		(layer "In5.Cu")
		(net "AVSO_VREF")
	)
	(segment
		(start 211.286852 -49.692052)
		(end 208.603088 -49.692052)
		(width 0.254)
		(layer "In5.Cu")
		(net "AVSO_VREF")
	)
	(segment
		(start 194.31 -52.6034)
		(end 194.2846 -52.6288)
		(width 0.254)
		(layer "In5.Cu")
		(net "AVSO_VREF")
	)
	(segment
		(start 208.603088 -49.692052)
		(end 207.396334 -50.898806)
		(width 0.254)
		(layer "In5.Cu")
		(net "AVSO_VREF")
	)
	(segment
		(start 202.25258 -124.2822)
		(end 216.1413 -124.2822)
		(width 0.254)
		(layer "In5.Cu")
		(net "AVSO_VREF")
	)
	(segment
		(start 194.31 -51.3588)
		(end 194.31 -52.6034)
		(width 0.254)
		(layer "In5.Cu")
		(net "AVSO_VREF")
	)
	(segment
		(start 211.365592 -51.928776)
		(end 211.795106 -51.499262)
		(width 0.254)
		(layer "In5.Cu")
		(net "AVSO_VREF")
	)
	(segment
		(start 211.795106 -50.200306)
		(end 211.286852 -49.692052)
		(width 0.254)
		(layer "In5.Cu")
		(net "AVSO_VREF")
	)
	(segment
		(start 200.80478 -122.8344)
		(end 202.25258 -124.2822)
		(width 0.254)
		(layer "In5.Cu")
		(net "AVSO_VREF")
	)
	(segment
		(start 194.769994 -50.898806)
		(end 194.31 -51.3588)
		(width 0.254)
		(layer "In5.Cu")
		(net "AVSO_VREF")
	)
	(segment
		(start 195.214494 -53.914294)
		(end 195.600066 -54.299866)
		(width 0.2032)
		(layer "F.Cu")
		(net "AVSO_IDDTN18")
	)
	(segment
		(start 195.219066 -51.806856)
		(end 195.219066 -53.33746)
		(width 0.254)
		(layer "F.Cu")
		(net "AVSO_IDDTN18")
	)
	(segment
		(start 195.219066 -53.33746)
		(end 195.214494 -53.342032)
		(width 0.254)
		(layer "F.Cu")
		(net "AVSO_IDDTN18")
	)
	(segment
		(start 195.214494 -53.342032)
		(end 195.214494 -53.914294)
		(width 0.2032)
		(layer "F.Cu")
		(net "AVSO_IDDTN18")
	)
	(via
		(at 195.219066 -51.806856)
		(size 0.508)
		(drill 0.254)
		(layers "F.Cu" "B.Cu")
		(net "AVSO_IDDTN18")
	)
	(segment
		(start 195.206366 -51.794156)
		(end 195.219066 -51.806856)
		(width 0.254)
		(layer "B.Cu")
		(net "AVSO_IDDTN18")
	)
	(segment
		(start 195.206366 -50.648616)
		(end 195.206366 -51.794156)
		(width 0.254)
		(layer "B.Cu")
		(net "AVSO_IDDTN18")
	)
	(segment
		(start 157.52064 -139.26312)
		(end 157.52064 -138.377422)
		(width 0.508)
		(layer "F.Cu")
		(net "AGND_P1V8_STBY")
	)
	(segment
		(start 157.849062 -141.0716)
		(end 157.96514 -140.955522)
		(width 0.508)
		(layer "F.Cu")
		(net "AGND_P1V8_STBY")
	)
	(segment
		(start 157.52064 -138.377422)
		(end 157.684216 -138.213846)
		(width 0.254)
		(layer "F.Cu")
		(net "AGND_P1V8_STBY")
	)
	(segment
		(start 157.684216 -138.213846)
		(end 158.548578 -138.213846)
		(width 0.254)
		(layer "F.Cu")
		(net "AGND_P1V8_STBY")
	)
	(segment
		(start 157.96514 -140.955522)
		(end 157.96514 -139.70762)
		(width 0.508)
		(layer "F.Cu")
		(net "AGND_P1V8_STBY")
	)
	(segment
		(start 160.687512 -141.751558)
		(end 160.687512 -142.602712)
		(width 0.254)
		(layer "F.Cu")
		(net "AGND_P1V8_STBY")
	)
	(segment
		(start 160.687512 -142.602712)
		(end 160.7312 -142.6464)
		(width 0.254)
		(layer "F.Cu")
		(net "AGND_P1V8_STBY")
	)
	(segment
		(start 157.96514 -139.70762)
		(end 157.52064 -139.26312)
		(width 0.508)
		(layer "F.Cu")
		(net "AGND_P1V8_STBY")
	)
	(segment
		(start 156.9974 -141.0716)
		(end 157.849062 -141.0716)
		(width 0.508)
		(layer "F.Cu")
		(net "AGND_P1V8_STBY")
	)
	(via
		(at 159.361632 -140.662914)
		(size 0.6096)
		(drill 0.3048)
		(layers "F.Cu" "B.Cu")
		(net "AGND_P1V8_STBY")
	)
	(via
		(at 160.7312 -142.6464)
		(size 0.508)
		(drill 0.254)
		(layers "F.Cu" "B.Cu")
		(net "AGND_P1V8_STBY")
	)
	(via
		(at 157.52064 -138.377422)
		(size 0.508)
		(drill 0.254)
		(layers "F.Cu" "B.Cu")
		(net "AGND_P1V8_STBY")
	)
	(segment
		(start 160.26638 -142.156942)
		(end 160.26638 -141.567662)
		(width 0.254)
		(layer "B.Cu")
		(net "AGND_P1V8_STBY")
	)
	(segment
		(start 157.52064 -138.377422)
		(end 157.52064 -138.821922)
		(width 0.254)
		(layer "B.Cu")
		(net "AGND_P1V8_STBY")
	)
	(segment
		(start 157.52064 -138.821922)
		(end 159.361632 -140.662914)
		(width 0.254)
		(layer "B.Cu")
		(net "AGND_P1V8_STBY")
	)
	(segment
		(start 160.7312 -142.621762)
		(end 160.26638 -142.156942)
		(width 0.254)
		(layer "B.Cu")
		(net "AGND_P1V8_STBY")
	)
	(segment
		(start 160.26638 -141.567662)
		(end 159.361632 -140.662914)
		(width 0.254)
		(layer "B.Cu")
		(net "AGND_P1V8_STBY")
	)
	(segment
		(start 160.7312 -142.6464)
		(end 160.7312 -142.621762)
		(width 0.254)
		(layer "B.Cu")
		(net "AGND_P1V8_STBY")
	)
	(segment
		(start 51.699668 -150.599902)
		(end 52.099718 -150.199852)
		(width 0.127)
		(layer "F.Cu")
		(net "ADC_P5V_STBY")
	)
	(segment
		(start 52.099718 -150.199852)
		(end 52.099972 -150.199852)
		(width 0.127)
		(layer "F.Cu")
		(net "ADC_P5V_STBY")
	)
	(via
		(at 55.372 -160.1216)
		(size 0.6096)
		(drill 0.3048)
		(layers "F.Cu" "B.Cu")
		(net "ADC_P5V_STBY")
	)
	(via
		(at 51.699668 -150.599902)
		(size 0.4572)
		(drill 0.2032)
		(layers "F.Cu" "B.Cu")
		(net "ADC_P5V_STBY")
	)
	(segment
		(start 56.405526 -162.022282)
		(end 56.405526 -161.083752)
		(width 0.127)
		(layer "B.Cu")
		(net "ADC_P5V_STBY")
	)
	(segment
		(start 52.893468 -151.23668)
		(end 52.893468 -152.367488)
		(width 0.127)
		(layer "B.Cu")
		(net "ADC_P5V_STBY")
	)
	(segment
		(start 56.398668 -163.069524)
		(end 56.402732 -163.06546)
		(width 0.127)
		(layer "B.Cu")
		(net "ADC_P5V_STBY")
	)
	(segment
		(start 56.405526 -161.083752)
		(end 56.257952 -161.083752)
		(width 0.127)
		(layer "B.Cu")
		(net "ADC_P5V_STBY")
	)
	(segment
		(start 55.372 -160.1978)
		(end 55.372 -160.1216)
		(width 0.127)
		(layer "B.Cu")
		(net "ADC_P5V_STBY")
	)
	(segment
		(start 56.402732 -163.06546)
		(end 56.402732 -162.025076)
		(width 0.127)
		(layer "B.Cu")
		(net "ADC_P5V_STBY")
	)
	(segment
		(start 55.47995 -158.07055)
		(end 55.47995 -159.3469)
		(width 0.127)
		(layer "B.Cu")
		(net "ADC_P5V_STBY")
	)
	(segment
		(start 54.93893 -156.685742)
		(end 54.93893 -156.919422)
		(width 0.127)
		(layer "B.Cu")
		(net "ADC_P5V_STBY")
	)
	(segment
		(start 53.15966 -152.63368)
		(end 53.15966 -154.906472)
		(width 0.127)
		(layer "B.Cu")
		(net "ADC_P5V_STBY")
	)
	(segment
		(start 55.044594 -157.025086)
		(end 55.044594 -157.635194)
		(width 0.127)
		(layer "B.Cu")
		(net "ADC_P5V_STBY")
	)
	(segment
		(start 55.47995 -159.3469)
		(end 55.372 -159.45485)
		(width 0.127)
		(layer "B.Cu")
		(net "ADC_P5V_STBY")
	)
	(segment
		(start 52.093368 -150.993602)
		(end 52.65039 -150.993602)
		(width 0.127)
		(layer "B.Cu")
		(net "ADC_P5V_STBY")
	)
	(segment
		(start 56.402732 -162.025076)
		(end 56.405526 -162.022282)
		(width 0.127)
		(layer "B.Cu")
		(net "ADC_P5V_STBY")
	)
	(segment
		(start 55.044594 -157.635194)
		(end 55.47995 -158.07055)
		(width 0.127)
		(layer "B.Cu")
		(net "ADC_P5V_STBY")
	)
	(segment
		(start 52.893468 -152.367488)
		(end 53.15966 -152.63368)
		(width 0.127)
		(layer "B.Cu")
		(net "ADC_P5V_STBY")
	)
	(segment
		(start 52.65039 -150.993602)
		(end 52.893468 -151.23668)
		(width 0.127)
		(layer "B.Cu")
		(net "ADC_P5V_STBY")
	)
	(segment
		(start 51.699668 -150.599902)
		(end 52.093368 -150.993602)
		(width 0.127)
		(layer "B.Cu")
		(net "ADC_P5V_STBY")
	)
	(segment
		(start 56.257952 -161.083752)
		(end 55.372 -160.1978)
		(width 0.127)
		(layer "B.Cu")
		(net "ADC_P5V_STBY")
	)
	(segment
		(start 54.93893 -156.919422)
		(end 55.044594 -157.025086)
		(width 0.127)
		(layer "B.Cu")
		(net "ADC_P5V_STBY")
	)
	(segment
		(start 55.372 -159.45485)
		(end 55.372 -160.1216)
		(width 0.127)
		(layer "B.Cu")
		(net "ADC_P5V_STBY")
	)
	(segment
		(start 53.15966 -154.906472)
		(end 54.93893 -156.685742)
		(width 0.127)
		(layer "B.Cu")
		(net "ADC_P5V_STBY")
	)
	(segment
		(start 58.7502 -163.0807)
		(end 57.785 -163.0807)
		(width 0.127)
		(layer "F.Cu")
		(net "ADC_P3V3_STBY")
	)
	(segment
		(start 58.7502 -162.3441)
		(end 59.1439 -161.9504)
		(width 0.127)
		(layer "F.Cu")
		(net "ADC_P3V3_STBY")
	)
	(segment
		(start 55.7403 -160.489646)
		(end 56.309514 -161.059114)
		(width 0.127)
		(layer "F.Cu")
		(net "ADC_P3V3_STBY")
	)
	(segment
		(start 53.304948 -153.005028)
		(end 53.304948 -154.015948)
		(width 0.127)
		(layer "F.Cu")
		(net "ADC_P3V3_STBY")
	)
	(segment
		(start 57.2135 -161.479992)
		(end 56.792622 -161.059114)
		(width 0.127)
		(layer "F.Cu")
		(net "ADC_P3V3_STBY")
	)
	(segment
		(start 57.2135 -161.8742)
		(end 57.2135 -161.479992)
		(width 0.127)
		(layer "F.Cu")
		(net "ADC_P3V3_STBY")
	)
	(segment
		(start 52.899818 -152.599898)
		(end 53.304948 -153.005028)
		(width 0.127)
		(layer "F.Cu")
		(net "ADC_P3V3_STBY")
	)
	(segment
		(start 53.304948 -154.015948)
		(end 55.3085 -156.0195)
		(width 0.127)
		(layer "F.Cu")
		(net "ADC_P3V3_STBY")
	)
	(segment
		(start 55.3085 -157.714188)
		(end 55.7403 -158.145988)
		(width 0.127)
		(layer "F.Cu")
		(net "ADC_P3V3_STBY")
	)
	(segment
		(start 57.785 -162.4457)
		(end 57.2135 -161.8742)
		(width 0.127)
		(layer "F.Cu")
		(net "ADC_P3V3_STBY")
	)
	(segment
		(start 55.7403 -158.145988)
		(end 55.7403 -160.489646)
		(width 0.127)
		(layer "F.Cu")
		(net "ADC_P3V3_STBY")
	)
	(segment
		(start 58.7502 -163.0807)
		(end 58.7502 -162.3441)
		(width 0.127)
		(layer "F.Cu")
		(net "ADC_P3V3_STBY")
	)
	(segment
		(start 55.3085 -156.0195)
		(end 55.3085 -157.714188)
		(width 0.127)
		(layer "F.Cu")
		(net "ADC_P3V3_STBY")
	)
	(segment
		(start 56.309514 -161.059114)
		(end 56.792622 -161.059114)
		(width 0.127)
		(layer "F.Cu")
		(net "ADC_P3V3_STBY")
	)
	(segment
		(start 57.785 -163.0807)
		(end 57.785 -162.4457)
		(width 0.127)
		(layer "F.Cu")
		(net "ADC_P3V3_STBY")
	)
	(via
		(at 56.792622 -161.059114)
		(size 0.6604)
		(drill 0.3302)
		(layers "F.Cu" "B.Cu")
		(net "ADC_P3V3_STBY")
	)
	(segment
		(start 55.2196 -161.12998)
		(end 54.713124 -161.636456)
		(width 0.127)
		(layer "F.Cu")
		(net "ADC_P1V8_STBY")
	)
	(segment
		(start 56.7436 -162.0393)
		(end 56.3372 -162.0393)
		(width 0.127)
		(layer "F.Cu")
		(net "ADC_P1V8_STBY")
	)
	(segment
		(start 56.3372 -162.0393)
		(end 55.6768 -162.6997)
		(width 0.127)
		(layer "F.Cu")
		(net "ADC_P1V8_STBY")
	)
	(segment
		(start 54.5719 -155.8671)
		(end 52.899818 -154.195018)
		(width 0.127)
		(layer "F.Cu")
		(net "ADC_P1V8_STBY")
	)
	(segment
		(start 55.6768 -162.6997)
		(end 55.375556 -162.6997)
		(width 0.127)
		(layer "F.Cu")
		(net "ADC_P1V8_STBY")
	)
	(segment
		(start 54.864 -158.1023)
		(end 54.5719 -157.8102)
		(width 0.127)
		(layer "F.Cu")
		(net "ADC_P1V8_STBY")
	)
	(segment
		(start 54.5719 -157.8102)
		(end 54.5719 -155.8671)
		(width 0.127)
		(layer "F.Cu")
		(net "ADC_P1V8_STBY")
	)
	(segment
		(start 54.864 -158.1023)
		(end 55.2196 -158.4579)
		(width 0.127)
		(layer "F.Cu")
		(net "ADC_P1V8_STBY")
	)
	(segment
		(start 55.2196 -158.4579)
		(end 55.2196 -161.12998)
		(width 0.127)
		(layer "F.Cu")
		(net "ADC_P1V8_STBY")
	)
	(segment
		(start 55.375556 -162.6997)
		(end 54.713124 -162.037268)
		(width 0.127)
		(layer "F.Cu")
		(net "ADC_P1V8_STBY")
	)
	(segment
		(start 54.713124 -161.636456)
		(end 54.713124 -162.037268)
		(width 0.127)
		(layer "F.Cu")
		(net "ADC_P1V8_STBY")
	)
	(segment
		(start 52.899818 -154.195018)
		(end 52.899818 -153.399998)
		(width 0.127)
		(layer "F.Cu")
		(net "ADC_P1V8_STBY")
	)
	(via
		(at 54.864 -158.1023)
		(size 0.6604)
		(drill 0.3302)
		(layers "F.Cu" "B.Cu")
		(net "ADC_P1V8_STBY")
	)
	(segment
		(start 52.099972 -151.000206)
		(end 52.099972 -150.999952)
		(width 0.127)
		(layer "F.Cu")
		(net "ADC_12V")
	)
	(segment
		(start 52.499768 -151.400002)
		(end 52.099972 -151.000206)
		(width 0.127)
		(layer "F.Cu")
		(net "ADC_12V")
	)
	(via
		(at 52.499768 -151.400002)
		(size 0.4572)
		(drill 0.2032)
		(layers "F.Cu" "B.Cu")
		(net "ADC_12V")
	)
	(via
		(at 54.864 -159.2326)
		(size 0.6096)
		(drill 0.3048)
		(layers "F.Cu" "B.Cu")
		(net "ADC_12V")
	)
	(segment
		(start 54.55793 -157.07741)
		(end 54.55793 -156.84373)
		(width 0.127)
		(layer "B.Cu")
		(net "ADC_12V")
	)
	(segment
		(start 54.663594 -157.889194)
		(end 54.663594 -157.183074)
		(width 0.127)
		(layer "B.Cu")
		(net "ADC_12V")
	)
	(segment
		(start 54.663594 -157.183074)
		(end 54.55793 -157.07741)
		(width 0.127)
		(layer "B.Cu")
		(net "ADC_12V")
	)
	(segment
		(start 52.82946 -153.89606)
		(end 52.106068 -153.172668)
		(width 0.127)
		(layer "B.Cu")
		(net "ADC_12V")
	)
	(segment
		(start 53.7591 -162.179)
		(end 53.7591 -163.1188)
		(width 0.127)
		(layer "B.Cu")
		(net "ADC_12V")
	)
	(segment
		(start 53.7845 -162.1536)
		(end 53.7591 -162.179)
		(width 0.127)
		(layer "B.Cu")
		(net "ADC_12V")
	)
	(segment
		(start 52.106068 -153.172668)
		(end 52.106068 -151.793702)
		(width 0.127)
		(layer "B.Cu")
		(net "ADC_12V")
	)
	(segment
		(start 53.7845 -161.163)
		(end 53.7845 -162.1536)
		(width 0.127)
		(layer "B.Cu")
		(net "ADC_12V")
	)
	(segment
		(start 54.008782 -159.8549)
		(end 53.7337 -160.129982)
		(width 0.127)
		(layer "B.Cu")
		(net "ADC_12V")
	)
	(segment
		(start 54.864 -159.2326)
		(end 54.2417 -159.8549)
		(width 0.127)
		(layer "B.Cu")
		(net "ADC_12V")
	)
	(segment
		(start 53.7337 -160.129982)
		(end 53.7337 -161.1122)
		(width 0.127)
		(layer "B.Cu")
		(net "ADC_12V")
	)
	(segment
		(start 52.106068 -151.793702)
		(end 52.499768 -151.400002)
		(width 0.127)
		(layer "B.Cu")
		(net "ADC_12V")
	)
	(segment
		(start 52.82946 -155.11526)
		(end 52.82946 -153.89606)
		(width 0.127)
		(layer "B.Cu")
		(net "ADC_12V")
	)
	(segment
		(start 54.864 -159.2326)
		(end 54.864 -158.0896)
		(width 0.127)
		(layer "B.Cu")
		(net "ADC_12V")
	)
	(segment
		(start 54.55793 -156.84373)
		(end 52.82946 -155.11526)
		(width 0.127)
		(layer "B.Cu")
		(net "ADC_12V")
	)
	(segment
		(start 54.2417 -159.8549)
		(end 54.008782 -159.8549)
		(width 0.127)
		(layer "B.Cu")
		(net "ADC_12V")
	)
	(segment
		(start 54.864 -158.0896)
		(end 54.663594 -157.889194)
		(width 0.127)
		(layer "B.Cu")
		(net "ADC_12V")
	)
	(segment
		(start 53.7337 -161.1122)
		(end 53.7845 -161.163)
		(width 0.127)
		(layer "B.Cu")
		(net "ADC_12V")
	)
	(segment
		(start 49.299876 -152.999948)
		(end 49.699926 -153.399998)
		(width 0.1778)
		(layer "F.Cu")
		(net "ADCVREXT")
	)
	(via
		(at 49.299876 -152.999948)
		(size 0.4572)
		(drill 0.2032)
		(layers "F.Cu" "B.Cu")
		(net "ADCVREXT")
	)
	(via
		(at 50.088292 -151.260302)
		(size 0.6096)
		(drill 0.3048)
		(layers "F.Cu" "B.Cu")
		(net "ADCVREXT")
	)
	(segment
		(start 49.96434 -151.384254)
		(end 50.088292 -151.260302)
		(width 0.1778)
		(layer "B.Cu")
		(net "ADCVREXT")
	)
	(segment
		(start 49.96434 -152.23236)
		(end 49.96434 -151.384254)
		(width 0.1778)
		(layer "B.Cu")
		(net "ADCVREXT")
	)
	(segment
		(start 49.96434 -152.335484)
		(end 49.299876 -152.999948)
		(width 0.1778)
		(layer "B.Cu")
		(net "ADCVREXT")
	)
	(segment
		(start 49.96434 -152.23236)
		(end 49.96434 -152.335484)
		(width 0.1778)
		(layer "B.Cu")
		(net "ADCVREXT")
	)
	(segment
		(start 50.868326 -152.968198)
		(end 50.500026 -152.599898)
		(width 0.1778)
		(layer "F.Cu")
		(net "ADCVREFFP")
	)
	(segment
		(start 53.3908 -156.992574)
		(end 53.3908 -158.323026)
		(width 0.1778)
		(layer "F.Cu")
		(net "ADCVREFFP")
	)
	(segment
		(start 52.900072 -159.93618)
		(end 52.978812 -159.85744)
		(width 0.1778)
		(layer "F.Cu")
		(net "ADCVREFFP")
	)
	(segment
		(start 53.5051 -159.82442)
		(end 53.47208 -159.85744)
		(width 0.1778)
		(layer "F.Cu")
		(net "ADCVREFFP")
	)
	(segment
		(start 52.722018 -155.574746)
		(end 50.868326 -153.721054)
		(width 0.1778)
		(layer "F.Cu")
		(net "ADCVREFFP")
	)
	(segment
		(start 53.7464 -156.636974)
		(end 53.3908 -156.992574)
		(width 0.1778)
		(layer "F.Cu")
		(net "ADCVREFFP")
	)
	(segment
		(start 53.263546 -155.574746)
		(end 52.722018 -155.574746)
		(width 0.1778)
		(layer "F.Cu")
		(net "ADCVREFFP")
	)
	(segment
		(start 53.7464 -156.0576)
		(end 53.7464 -156.636974)
		(width 0.1778)
		(layer "F.Cu")
		(net "ADCVREFFP")
	)
	(segment
		(start 52.59324 -159.93618)
		(end 52.900072 -159.93618)
		(width 0.1778)
		(layer "F.Cu")
		(net "ADCVREFFP")
	)
	(segment
		(start 53.7464 -156.0576)
		(end 53.263546 -155.574746)
		(width 0.1778)
		(layer "F.Cu")
		(net "ADCVREFFP")
	)
	(segment
		(start 53.3908 -158.323026)
		(end 53.5051 -158.437326)
		(width 0.1778)
		(layer "F.Cu")
		(net "ADCVREFFP")
	)
	(segment
		(start 50.868326 -153.721054)
		(end 50.868326 -152.968198)
		(width 0.1778)
		(layer "F.Cu")
		(net "ADCVREFFP")
	)
	(segment
		(start 53.5051 -158.437326)
		(end 53.5051 -159.82442)
		(width 0.1778)
		(layer "F.Cu")
		(net "ADCVREFFP")
	)
	(segment
		(start 52.978812 -159.85744)
		(end 53.47208 -159.85744)
		(width 0.1778)
		(layer "F.Cu")
		(net "ADCVREFFP")
	)
	(via
		(at 53.7464 -156.0576)
		(size 0.6604)
		(drill 0.3302)
		(layers "F.Cu" "B.Cu")
		(net "ADCVREFFP")
	)
	(segment
		(start 52.638452 -158.2039)
		(end 52.638452 -156.651452)
		(width 0.1778)
		(layer "F.Cu")
		(net "ADCVREFFN")
	)
	(segment
		(start 51.7271 -160.8074)
		(end 52.57546 -160.8074)
		(width 0.1778)
		(layer "F.Cu")
		(net "ADCVREFFN")
	)
	(segment
		(start 52.638452 -156.651452)
		(end 52.07 -156.083)
		(width 0.1778)
		(layer "F.Cu")
		(net "ADCVREFFN")
	)
	(segment
		(start 52.07 -155.829)
		(end 52.07 -156.083)
		(width 0.1778)
		(layer "F.Cu")
		(net "ADCVREFFN")
	)
	(segment
		(start 51.7271 -160.8074)
		(end 51.98999 -160.54451)
		(width 0.1778)
		(layer "F.Cu")
		(net "ADCVREFFN")
	)
	(segment
		(start 51.98999 -160.54451)
		(end 51.98999 -158.852362)
		(width 0.1778)
		(layer "F.Cu")
		(net "ADCVREFFN")
	)
	(segment
		(start 50.500026 -154.259026)
		(end 52.07 -155.829)
		(width 0.1778)
		(layer "F.Cu")
		(net "ADCVREFFN")
	)
	(segment
		(start 50.500026 -153.399998)
		(end 50.500026 -154.259026)
		(width 0.1778)
		(layer "F.Cu")
		(net "ADCVREFFN")
	)
	(segment
		(start 51.98999 -158.852362)
		(end 52.638452 -158.2039)
		(width 0.1778)
		(layer "F.Cu")
		(net "ADCVREFFN")
	)
	(segment
		(start 52.57546 -160.8074)
		(end 52.59324 -160.82518)
		(width 0.1778)
		(layer "F.Cu")
		(net "ADCVREFFN")
	)
	(via
		(at 52.07 -156.083)
		(size 0.6604)
		(drill 0.3302)
		(layers "F.Cu" "B.Cu")
		(net "ADCVREFFN")
	)
	(segment
		(start 53.88356 -160.74644)
		(end 53.47208 -160.74644)
		(width 0.508)
		(layer "F.Cu")
		(net "ADCAV33")
	)
	(segment
		(start 54.3052 -160.3248)
		(end 53.88356 -160.74644)
		(width 0.508)
		(layer "F.Cu")
		(net "ADCAV33")
	)
	(segment
		(start 50.099722 -149.800056)
		(end 49.699926 -149.40026)
		(width 0.254)
		(layer "F.Cu")
		(net "ADCAV33")
	)
	(segment
		(start 49.699926 -149.40026)
		(end 49.699926 -149.400006)
		(width 0.254)
		(layer "F.Cu")
		(net "ADCAV33")
	)
	(via
		(at 53.848 -154.6098)
		(size 0.6096)
		(drill 0.3048)
		(layers "F.Cu" "B.Cu")
		(net "ADCAV33")
	)
	(via
		(at 53.926232 -153.911046)
		(size 0.508)
		(drill 0.254)
		(layers "F.Cu" "B.Cu")
		(net "ADCAV33")
	)
	(via
		(at 54.3052 -160.3248)
		(size 0.508)
		(drill 0.254)
		(layers "F.Cu" "B.Cu")
		(net "ADCAV33")
	)
	(via
		(at 50.099722 -149.800056)
		(size 0.4572)
		(drill 0.2032)
		(layers "F.Cu" "B.Cu")
		(net "ADCAV33")
	)
	(segment
		(start 55.2958 -155.956)
		(end 55.2958 -155.280614)
		(width 0.508)
		(layer "In2.Cu")
		(net "ADCAV33")
	)
	(segment
		(start 54.864 -159.766)
		(end 54.864 -156.3878)
		(width 0.508)
		(layer "In2.Cu")
		(net "ADCAV33")
	)
	(segment
		(start 55.2958 -155.280614)
		(end 53.926232 -153.911046)
		(width 0.508)
		(layer "In2.Cu")
		(net "ADCAV33")
	)
	(segment
		(start 54.3052 -160.3248)
		(end 54.864 -159.766)
		(width 0.508)
		(layer "In2.Cu")
		(net "ADCAV33")
	)
	(segment
		(start 54.864 -156.3878)
		(end 55.2958 -155.956)
		(width 0.508)
		(layer "In2.Cu")
		(net "ADCAV33")
	)
	(segment
		(start 50.683922 -153.578814)
		(end 51.518058 -154.41295)
		(width 0.508)
		(layer "In5.Cu")
		(net "ADCAV33")
	)
	(segment
		(start 50.4952 -150.195534)
		(end 50.4952 -150.9776)
		(width 0.127)
		(layer "In5.Cu")
		(net "ADCAV33")
	)
	(segment
		(start 50.099722 -149.800056)
		(end 50.4952 -150.195534)
		(width 0.127)
		(layer "In5.Cu")
		(net "ADCAV33")
	)
	(segment
		(start 53.424328 -154.41295)
		(end 53.926232 -153.911046)
		(width 0.508)
		(layer "In5.Cu")
		(net "ADCAV33")
	)
	(segment
		(start 50.165 -151.3078)
		(end 50.165 -152.238964)
		(width 0.508)
		(layer "In5.Cu")
		(net "ADCAV33")
	)
	(segment
		(start 50.165 -152.238964)
		(end 50.683922 -152.757886)
		(width 0.508)
		(layer "In5.Cu")
		(net "ADCAV33")
	)
	(segment
		(start 50.4952 -150.9776)
		(end 50.165 -151.3078)
		(width 0.127)
		(layer "In5.Cu")
		(net "ADCAV33")
	)
	(segment
		(start 51.518058 -154.41295)
		(end 53.424328 -154.41295)
		(width 0.508)
		(layer "In5.Cu")
		(net "ADCAV33")
	)
	(segment
		(start 50.683922 -152.757886)
		(end 50.683922 -153.578814)
		(width 0.508)
		(layer "In5.Cu")
		(net "ADCAV33")
	)
	(segment
		(start 50.099722 -149.800056)
		(end 49.706022 -150.193756)
		(width 0.127)
		(layer "In5.Cu")
		(net "ADCAV33")
	)
	(segment
		(start 49.706022 -150.193756)
		(end 49.706022 -150.848822)
		(width 0.127)
		(layer "In5.Cu")
		(net "ADCAV33")
	)
	(segment
		(start 49.706022 -150.848822)
		(end 50.165 -151.3078)
		(width 0.127)
		(layer "In5.Cu")
		(net "ADCAV33")
	)
	(zone
		(net "GND")
		(layer "F.Cu")
		(hatch none 0.5)
		(connect_pads
			(clearance 0.5)
		)
		(min_thickness 0.25)
		(fill yes
			(thermal_gap 0.5)
			(thermal_bridge_width 0.5)
			(island_removal_mode 0)
		)
		(polygon
			(pts
				(xy 161.541206 -40.650414) (xy 161.09442 -41.0972) (xy 159.89046 -41.0972) (xy 159.70758 -41.28008)
				(xy 159.70758 -43.24858) (xy 159.7914 -43.3324) (xy 161.6202 -43.3324) (xy 162.59302 -42.35958)
				(xy 162.59302 -40.721026) (xy 162.522408 -40.650414)
			)
		)
		(polygon
			(pts
				(xy 162.13836 -41.09974) (xy 161.93516 -41.09974) (xy 161.93516 -41.30294) (xy 162.13836 -41.30294)
			)
		)
	)
	(zone
		(layer "F.Cu")
		(hatch none 0.5)
		(connect_pads
			(clearance 0)
		)
		(min_thickness 0.25)
		(keepout
			(tracks not_allowed)
			(vias allowed)
			(pads allowed)
			(copperpour not_allowed)
			(footprints allowed)
		)
		(placement
			(enabled no)
			(sheetname "")
		)
		(fill
			(thermal_gap 0.5)
			(thermal_bridge_width 0.5)
			(island_removal_mode 0)
		)
		(polygon
			(pts
				(arc
					(start 207.941672 -64.262)
					(mid 207.960368 -64.284402)
					(end 207.967072 -64.3128)
				)
				(arc
					(start 207.967072 -64.516)
					(mid 207.960368 -64.544398)
					(end 207.941672 -64.5668)
				)
				(arc
					(start 208.170272 -64.5668)
					(mid 208.151576 -64.544398)
					(end 208.144872 -64.516)
				)
				(arc
					(start 208.144872 -64.3128)
					(mid 208.151576 -64.284402)
					(end 208.170272 -64.262)
				)
			)
		)
	)
	(zone
		(layer "F.Cu")
		(hatch none 0.5)
		(connect_pads
			(clearance 0)
		)
		(min_thickness 0.25)
		(keepout
			(tracks allowed)
			(vias allowed)
			(pads allowed)
			(copperpour allowed)
			(footprints allowed)
		)
		(placement
			(enabled no)
			(sheetname "")
		)
		(fill
			(thermal_gap 0.5)
			(thermal_bridge_width 0.5)
			(island_removal_mode 0)
		)
		(polygon
			(pts
				(xy 24.63673 -150.308564) (xy 24.63673 -132.833364) (xy 15.08633 -132.833364) (xy 15.08633 -134.5438)
				(xy 14.6812 -134.5438) (xy 14.4272 -134.7978) (xy 14.4272 -150.2156) (xy 14.520164 -150.308564)
				(xy 15.08633 -150.308564)
			)
		)
	)
	(zone
		(layer "F.Cu")
		(hatch none 0.5)
		(connect_pads
			(clearance 0)
		)
		(min_thickness 0.25)
		(keepout
			(tracks not_allowed)
			(vias allowed)
			(pads allowed)
			(copperpour not_allowed)
			(footprints allowed)
		)
		(placement
			(enabled no)
			(sheetname "")
		)
		(fill
			(thermal_gap 0.5)
			(thermal_bridge_width 0.5)
			(island_removal_mode 0)
		)
		(polygon
			(pts
				(arc
					(start 191.998092 -86.950296)
					(mid 191.998092 -86.411308)
					(end 191.459104 -86.411308)
				)
				(xy 191.315594 -86.554818) (xy 191.37757 -86.616794)
				(arc
					(start 191.380872 -86.620096)
					(mid 191.418536 -86.649852)
					(end 191.462152 -86.66988)
				)
				(arc
					(start 191.462152 -86.66988)
					(mid 191.981302 -86.595855)
					(end 191.523366 -86.851236)
				)
				(arc
					(start 191.523366 -86.851236)
					(mid 191.397951 -86.829169)
					(end 191.287146 -86.7664)
				)
				(xy 191.284606 -86.7664) (xy 191.266572 -86.748366) (xy 191.25946 -86.741508) (xy 191.256158 -86.738206)
				(xy 191.194436 -86.67623) (xy 191.095376 -86.775036) (xy 191.157606 -86.837012) (xy 191.160908 -86.840314)
				(xy 191.167766 -86.847426) (xy 191.1858 -86.86546)
				(arc
					(start 191.1858 -86.868)
					(mid 191.24853 -86.978674)
					(end 191.270636 -87.103966)
				)
				(arc
					(start 191.270636 -87.103966)
					(mid 191.014879 -87.561958)
					(end 191.089026 -87.042752)
				)
				(arc
					(start 191.089026 -87.042752)
					(mid 191.06907 -86.9993)
					(end 191.039496 -86.961726)
				)
				(xy 191.036194 -86.958424) (xy 190.974218 -86.896448)
				(arc
					(start 190.835534 -87.035132)
					(mid 190.828455 -87.576246)
					(end 191.369696 -87.578692)
				)
			)
		)
	)
	(zone
		(layer "F.Cu")
		(hatch none 0.5)
		(connect_pads
			(clearance 0)
		)
		(min_thickness 0.25)
		(keepout
			(tracks not_allowed)
			(vias allowed)
			(pads allowed)
			(copperpour not_allowed)
			(footprints allowed)
		)
		(placement
			(enabled no)
			(sheetname "")
		)
		(fill
			(thermal_gap 0.5)
			(thermal_bridge_width 0.5)
			(island_removal_mode 0)
		)
		(polygon
			(pts
				(arc
					(start 77.667358 -73.708768)
					(mid 77.283818 -73.325228)
					(end 76.900278 -73.708768)
				)
				(xy 76.900278 -73.905364) (xy 76.996798 -73.905364)
				(arc
					(start 77.00137 -73.905364)
					(mid 77.044321 -73.900608)
					(end 77.08519 -73.886568)
				)
				(arc
					(start 77.08519 -73.886568)
					(mid 77.405306 -73.471579)
					(end 77.256894 -73.974198)
				)
				(arc
					(start 77.256894 -73.974198)
					(mid 77.156283 -74.043055)
					(end 77.038708 -74.07529)
				)
				(xy 77.03693 -74.077068) (xy 77.011022 -74.077068) (xy 77.00137 -74.077068) (xy 76.996798 -74.077068)
				(xy 76.900278 -74.077068) (xy 76.900278 -74.216768) (xy 76.983844 -74.216768) (xy 76.988416 -74.216514)
				(xy 76.998322 -74.216768) (xy 77.023976 -74.216768)
				(arc
					(start 77.0255 -74.218292)
					(mid 77.153688 -74.254261)
					(end 77.26172 -74.332084)
				)
				(arc
					(start 77.26172 -74.332084)
					(mid 77.399381 -74.838021)
					(end 77.090016 -74.414634)
				)
				(arc
					(start 77.090016 -74.414634)
					(mid 77.040897 -74.394959)
					(end 76.988416 -74.388218)
				)
				(xy 76.983844 -74.387964) (xy 76.900278 -74.387964)
				(arc
					(start 76.900278 -74.597514)
					(mid 77.283691 -74.981308)
					(end 77.667358 -74.597768)
				)
			)
		)
	)
	(zone
		(net "P1V8_STBY")
		(layer "F.Cu")
		(hatch none 0.5)
		(connect_pads
			(clearance 0.5)
		)
		(min_thickness 0.25)
		(fill yes
			(thermal_gap 0.5)
			(thermal_bridge_width 0.5)
			(island_removal_mode 0)
		)
		(polygon
			(pts
				(xy 160.3756 -113.5888) (xy 157.1752 -116.7892) (xy 157.1752 -126.58725) (xy 157.329886 -126.741936)
				(xy 162.868864 -126.741936) (xy 163.957 -125.6538) (xy 163.957 -119.8626) (xy 165.6334 -118.1862)
				(xy 165.6334 -113.7158) (xy 165.5064 -113.5888)
			)
		)
		(polygon
			(pts
				(xy 157.9626 -118.8212) (xy 157.7594 -118.8212) (xy 157.7594 -119.0244) (xy 157.9626 -119.0244)
			)
		)
		(polygon
			(pts
				(xy 157.9626 -118.2116) (xy 157.7594 -118.2116) (xy 157.7594 -118.4148) (xy 157.9626 -118.4148)
			)
		)
	)
	(zone
		(layer "F.Cu")
		(hatch none 0.5)
		(connect_pads
			(clearance 0)
		)
		(min_thickness 0.25)
		(keepout
			(tracks not_allowed)
			(vias allowed)
			(pads allowed)
			(copperpour not_allowed)
			(footprints allowed)
		)
		(placement
			(enabled no)
			(sheetname "")
		)
		(fill
			(thermal_gap 0.5)
			(thermal_bridge_width 0.5)
			(island_removal_mode 0)
		)
		(polygon
			(pts
				(arc
					(start 207.941672 -74.3204)
					(mid 207.960368 -74.342802)
					(end 207.967072 -74.3712)
				)
				(arc
					(start 207.967072 -74.5744)
					(mid 207.960368 -74.602798)
					(end 207.941672 -74.6252)
				)
				(arc
					(start 208.170272 -74.6252)
					(mid 208.151576 -74.602798)
					(end 208.144872 -74.5744)
				)
				(arc
					(start 208.144872 -74.3712)
					(mid 208.151576 -74.342802)
					(end 208.170272 -74.3204)
				)
			)
		)
	)
	(zone
		(layer "F.Cu")
		(hatch none 0.5)
		(connect_pads
			(clearance 0)
		)
		(min_thickness 0.25)
		(keepout
			(tracks not_allowed)
			(vias allowed)
			(pads allowed)
			(copperpour not_allowed)
			(footprints allowed)
		)
		(placement
			(enabled no)
			(sheetname "")
		)
		(fill
			(thermal_gap 0.5)
			(thermal_bridge_width 0.5)
			(island_removal_mode 0)
		)
		(polygon
			(pts
				(arc
					(start 87.749888 -187.999878)
					(mid 92.499942 -183.249824)
					(end 97.249996 -187.999878)
				)
				(arc
					(start 97.249996 -187.999878)
					(mid 92.499942 -192.749932)
					(end 87.749888 -187.999878)
				)
			)
		)
	)
	(zone
		(net "SAS0_AVDD")
		(layer "F.Cu")
		(hatch none 0.5)
		(connect_pads
			(clearance 0.5)
		)
		(min_thickness 0.25)
		(fill yes
			(thermal_gap 0.5)
			(thermal_bridge_width 0.5)
			(island_removal_mode 0)
		)
		(polygon
			(pts
				(xy 207.974946 -90.567002) (xy 207.690212 -90.851736) (xy 207.690212 -94.893638) (xy 207.672686 -94.911164)
				(xy 207.672686 -96.166686) (xy 208.1276 -96.6216) (xy 217.7034 -96.6216) (xy 219.388436 -98.306636)
				(xy 227.25761 -98.306636) (xy 227.803456 -97.76079) (xy 227.803456 -91.202256) (xy 227.168202 -90.567002)
			)
		)
		(polygon
			(pts
				(xy 224.110042 -97.210118) (xy 223.906842 -97.210118) (xy 223.906842 -97.413318) (xy 224.110042 -97.413318)
			)
		)
		(polygon
			(pts
				(xy 223.246442 -97.210118) (xy 223.043242 -97.210118) (xy 223.043242 -97.413318) (xy 223.246442 -97.413318)
			)
		)
	)
	(zone
		(layer "F.Cu")
		(hatch none 0.5)
		(connect_pads
			(clearance 0)
		)
		(min_thickness 0.25)
		(keepout
			(tracks not_allowed)
			(vias allowed)
			(pads allowed)
			(copperpour not_allowed)
			(footprints allowed)
		)
		(placement
			(enabled no)
			(sheetname "")
		)
		(fill
			(thermal_gap 0.5)
			(thermal_bridge_width 0.5)
			(island_removal_mode 0)
		)
		(polygon
			(pts
				(arc
					(start 194.720464 -88.652096)
					(mid 194.720464 -88.113108)
					(end 194.181476 -88.113108)
				)
				(xy 194.037966 -88.256618) (xy 194.099942 -88.318594)
				(arc
					(start 194.103244 -88.321896)
					(mid 194.140908 -88.351652)
					(end 194.184524 -88.37168)
				)
				(arc
					(start 194.184524 -88.37168)
					(mid 194.703674 -88.297655)
					(end 194.245738 -88.553036)
				)
				(arc
					(start 194.245738 -88.553036)
					(mid 194.120323 -88.530969)
					(end 194.009518 -88.4682)
				)
				(xy 194.006978 -88.4682) (xy 193.988944 -88.450166) (xy 193.981832 -88.443308) (xy 193.97853 -88.440006)
				(xy 193.916808 -88.37803) (xy 193.817748 -88.476836) (xy 193.879978 -88.538812) (xy 193.88328 -88.542114)
				(xy 193.890138 -88.549226) (xy 193.908172 -88.56726)
				(arc
					(start 193.908172 -88.5698)
					(mid 193.970902 -88.680474)
					(end 193.993008 -88.805766)
				)
				(arc
					(start 193.993008 -88.805766)
					(mid 193.737251 -89.263758)
					(end 193.811398 -88.744552)
				)
				(arc
					(start 193.811398 -88.744552)
					(mid 193.791442 -88.7011)
					(end 193.761868 -88.663526)
				)
				(xy 193.758566 -88.660224) (xy 193.69659 -88.598248)
				(arc
					(start 193.557906 -88.736932)
					(mid 193.550827 -89.278046)
					(end 194.092068 -89.280492)
				)
			)
		)
	)
	(zone
		(layer "F.Cu")
		(hatch none 0.5)
		(connect_pads
			(clearance 0)
		)
		(min_thickness 0.25)
		(keepout
			(tracks not_allowed)
			(vias allowed)
			(pads allowed)
			(copperpour not_allowed)
			(footprints allowed)
		)
		(placement
			(enabled no)
			(sheetname "")
		)
		(fill
			(thermal_gap 0.5)
			(thermal_bridge_width 0.5)
			(island_removal_mode 0)
		)
		(polygon
			(pts
				(arc
					(start 77.667358 -80.109568)
					(mid 77.283818 -79.726028)
					(end 76.900278 -80.109568)
				)
				(xy 76.900278 -80.311752) (xy 76.99121 -80.311752)
				(arc
					(start 76.995782 -80.311752)
					(mid 77.042787 -80.306212)
					(end 77.087222 -80.289908)
				)
				(arc
					(start 77.087222 -80.289908)
					(mid 77.401967 -79.87071)
					(end 77.258926 -80.374998)
				)
				(arc
					(start 77.258926 -80.374998)
					(mid 77.155198 -80.44776)
					(end 77.03312 -80.481678)
				)
				(xy 77.031342 -80.483456) (xy 77.005434 -80.483456) (xy 76.995782 -80.483456) (xy 76.99121 -80.483456)
				(xy 76.900278 -80.483456) (xy 76.900278 -80.623156) (xy 76.989432 -80.623156) (xy 76.994004 -80.622902)
				(xy 77.003656 -80.623156) (xy 77.029564 -80.623156)
				(arc
					(start 77.031342 -80.62468)
					(mid 77.154888 -80.659005)
					(end 77.259688 -80.732884)
				)
				(arc
					(start 77.259688 -80.732884)
					(mid 77.40166 -81.237908)
					(end 77.087984 -80.817466)
				)
				(arc
					(start 77.087984 -80.817466)
					(mid 77.042366 -80.800406)
					(end 76.994004 -80.794606)
				)
				(xy 76.989432 -80.794352) (xy 76.900278 -80.794352)
				(arc
					(start 76.900278 -80.998314)
					(mid 77.283691 -81.382108)
					(end 77.667358 -80.998568)
				)
			)
		)
	)
	(zone
		(layer "F.Cu")
		(hatch none 0.5)
		(connect_pads
			(clearance 0)
		)
		(min_thickness 0.25)
		(keepout
			(tracks allowed)
			(vias allowed)
			(pads allowed)
			(copperpour allowed)
			(footprints not_allowed)
		)
		(placement
			(enabled no)
			(sheetname "")
		)
		(fill
			(thermal_gap 0.5)
			(thermal_bridge_width 0.5)
			(island_removal_mode 0)
		)
		(polygon
			(pts
				(arc
					(start 75.25004 -120.000014)
					(mid 80.000094 -115.24996)
					(end 84.749894 -120.000014)
				)
				(arc
					(start 84.749894 -120.000014)
					(mid 80.000094 -124.749814)
					(end 75.25004 -120.000014)
				)
			)
		)
	)
	(zone
		(net "GND")
		(layer "F.Cu")
		(hatch none 0.5)
		(connect_pads
			(clearance 0.5)
		)
		(min_thickness 0.25)
		(fill yes
			(thermal_gap 0.5)
			(thermal_bridge_width 0.5)
			(island_removal_mode 0)
		)
		(polygon
			(pts
				(xy 27.736038 -13.59535)
				(arc
					(start 27.736038 -109.050074)
					(mid 28.847274 -111.732836)
					(end 31.530036 -112.844072)
				)
				(xy 52.920392 -112.844072) (xy 52.920392 -110.813088)
				(arc
					(start 31.530036 -110.813088)
					(mid 30.283397 -110.296713)
					(end 29.767022 -109.050074)
				)
				(xy 29.767022 -13.59535)
			)
		)
	)
	(zone
		(net "P2V5_STBY")
		(layer "F.Cu")
		(hatch none 0.5)
		(connect_pads
			(clearance 0.5)
		)
		(min_thickness 0.25)
		(fill yes
			(thermal_gap 0.5)
			(thermal_bridge_width 0.5)
			(island_removal_mode 0)
		)
		(polygon
			(pts
				(xy 14.5415 -147.1422) (xy 13.96365 -147.72005) (xy 13.96365 -153.0096) (xy 18.877788 -157.923738)
				(xy 20.901406 -157.923738) (xy 22.1107 -159.133032) (xy 22.989032 -159.133032) (xy 24.198072 -160.342072)
				(xy 26.474928 -160.342072) (xy 27.422856 -161.290254) (xy 27.422856 -169.510456) (xy 28.0162 -170.1038)
				(xy 31.2166 -170.1038) (xy 31.700978 -169.619422) (xy 31.700978 -167.8178) (xy 31.6738 -167.8178)
				(xy 31.6738 -167.4876) (xy 29.434536 -165.248336) (xy 29.434536 -159.768794) (xy 28.050744 -158.385256)
				(xy 25.4508 -158.385256) (xy 21.319744 -154.2542) (xy 19.374612 -154.2542) (xy 15.475712 -150.3553)
				(xy 15.475712 -148.176488) (xy 15.6972 -147.955) (xy 16.9418 -147.955) (xy 17.018 -147.8788) (xy 17.018 -147.6756)
				(xy 16.9164 -147.574) (xy 15.7226 -147.574) (xy 15.2908 -147.1422)
			)
		)
	)
	(zone
		(net "P1V8_STBY")
		(layer "F.Cu")
		(hatch none 0.5)
		(connect_pads
			(clearance 0.5)
		)
		(min_thickness 0.25)
		(fill yes
			(thermal_gap 0.5)
			(thermal_bridge_width 0.5)
			(island_removal_mode 0)
		)
		(polygon
			(pts
				(xy 79.7306 -163.322) (xy 79.7052 -163.3474) (xy 79.7052 -164.1094) (xy 79.6544 -164.1602) (xy 77.618844 -164.1602)
				(xy 77.618844 -166.010844) (xy 78.2066 -166.5986) (xy 78.2066 -167.767) (xy 78.3844 -167.9448) (xy 82.0674 -167.9448)
				(xy 82.296 -167.7162) (xy 82.296 -165.348666) (xy 82.0547 -165.107366) (xy 82.0547 -164.498528)
				(xy 82.292444 -164.260784) (xy 82.292444 -163.750244) (xy 82.1436 -163.6014) (xy 81.28 -163.6014)
				(xy 81.0006 -163.322)
			)
		)
		(polygon
			(pts
				(xy 81.6102 -164.1094) (xy 81.407 -164.1094) (xy 81.407 -164.3126) (xy 81.6102 -164.3126)
			)
		)
	)
	(zone
		(net "P5V_STBY")
		(layer "F.Cu")
		(hatch none 0.5)
		(connect_pads
			(clearance 0.5)
		)
		(min_thickness 0.25)
		(fill yes
			(thermal_gap 0.5)
			(thermal_bridge_width 0.5)
			(island_removal_mode 0)
		)
		(polygon
			(pts
				(xy 77.391768 -49.482756) (xy 77.224128 -49.650396) (xy 77.224128 -50.069496) (xy 77.229716 -50.075084)
				(xy 77.229716 -50.407316) (xy 77.5843 -50.7619) (xy 78.340204 -50.7619) (xy 79.1464 -51.568096)
				(xy 81.237328 -51.568096) (xy 81.465166 -51.795934) (xy 81.874106 -51.795934) (xy 82.049874 -51.620166)
				(xy 82.049874 -49.68621) (xy 81.860898 -49.497234) (xy 77.874368 -49.497234) (xy 77.85989 -49.482756)
			)
		)
	)
	(zone
		(layer "F.Cu")
		(hatch none 0.5)
		(connect_pads
			(clearance 0)
		)
		(min_thickness 0.25)
		(keepout
			(tracks allowed)
			(vias allowed)
			(pads allowed)
			(copperpour allowed)
			(footprints not_allowed)
		)
		(placement
			(enabled no)
			(sheetname "")
		)
		(fill
			(thermal_gap 0.5)
			(thermal_bridge_width 0.5)
			(island_removal_mode 0)
		)
		(polygon
			(pts
				(arc
					(start 97.249996 -187.999878)
					(mid 92.499942 -192.749932)
					(end 87.749888 -187.999878)
				)
				(arc
					(start 87.749888 -187.999878)
					(mid 92.499942 -183.249824)
					(end 97.249996 -187.999878)
				)
			)
		)
	)
	(zone
		(net "P12V_STBY")
		(layer "F.Cu")
		(hatch none 0.5)
		(connect_pads
			(clearance 0.5)
		)
		(min_thickness 0.25)
		(fill yes
			(thermal_gap 0.5)
			(thermal_bridge_width 0.5)
			(island_removal_mode 0)
		)
		(polygon
			(pts
				(xy 174.848012 -131.19608) (xy 174.490888 -131.553204) (xy 174.490888 -134.646416) (xy 174.961042 -135.11657)
				(xy 177.085752 -135.11657) (xy 177.673 -134.529322) (xy 177.673 -132.037074) (xy 176.832006 -131.19608)
			)
		)
		(polygon
			(pts
				(xy 176.5681 -133.8199) (xy 176.3649 -133.8199) (xy 176.3649 -134.0231) (xy 176.5681 -134.0231)
			)
		)
		(polygon
			(pts
				(xy 175.1711 -133.8199) (xy 174.9679 -133.8199) (xy 174.9679 -134.0231) (xy 175.1711 -134.0231)
			)
		)
	)
	(zone
		(layer "F.Cu")
		(hatch none 0.5)
		(connect_pads
			(clearance 0)
		)
		(min_thickness 0.25)
		(keepout
			(tracks not_allowed)
			(vias allowed)
			(pads allowed)
			(copperpour not_allowed)
			(footprints allowed)
		)
		(placement
			(enabled no)
			(sheetname "")
		)
		(fill
			(thermal_gap 0.5)
			(thermal_bridge_width 0.5)
			(island_removal_mode 0)
		)
		(polygon
			(pts
				(arc
					(start 215.303354 -68.953126)
					(mid 215.303354 -68.414646)
					(end 214.764874 -68.414646)
				)
				(xy 214.76462 -68.414392) (xy 214.55761 -68.621402)
				(arc
					(start 214.700104 -68.763896)
					(mid 214.741894 -68.78956)
					(end 214.790782 -68.79336)
				)
				(arc
					(start 214.790782 -68.79336)
					(mid 215.232861 -68.506077)
					(end 214.897208 -68.91274)
				)
				(arc
					(start 214.897208 -68.91274)
					(mid 214.755031 -68.943825)
					(end 214.619078 -68.891912)
				)
				(xy 214.61603 -68.891912) (xy 214.451438 -68.727574) (xy 214.371174 -68.807838) (xy 214.270082 -68.90893)
				(xy 214.434674 -69.073522)
				(arc
					(start 214.434674 -69.07657)
					(mid 214.486644 -69.21298)
					(end 214.454994 -69.355462)
				)
				(arc
					(start 214.454994 -69.355462)
					(mid 214.048198 -69.69109)
					(end 214.335868 -69.249036)
				)
				(arc
					(start 214.335868 -69.249036)
					(mid 214.332402 -69.199757)
					(end 214.306658 -69.157596)
				)
				(xy 214.164164 -69.014848) (xy 213.956392 -69.22262)
				(arc
					(start 213.956646 -69.222874)
					(mid 213.956646 -69.761354)
					(end 214.495126 -69.761354)
				)
				(xy 214.49538 -69.761608) (xy 215.303354 -68.95338)
			)
		)
	)
	(zone
		(layer "F.Cu")
		(hatch none 0.5)
		(connect_pads
			(clearance 0)
		)
		(min_thickness 0.25)
		(keepout
			(tracks allowed)
			(vias allowed)
			(pads allowed)
			(copperpour allowed)
			(footprints not_allowed)
		)
		(placement
			(enabled no)
			(sheetname "")
		)
		(fill
			(thermal_gap 0.5)
			(thermal_bridge_width 0.5)
			(island_removal_mode 0)
		)
		(polygon
			(pts
				(arc
					(start 78.550008 -109.799882)
					(mid 73.800208 -105.050082)
					(end 78.550008 -100.300028)
				)
				(xy 92.700094 -100.300028) (xy 92.700094 -109.799882)
			)
		)
	)
	(zone
		(layer "F.Cu")
		(hatch none 0.5)
		(connect_pads
			(clearance 0)
		)
		(min_thickness 0.25)
		(keepout
			(tracks not_allowed)
			(vias allowed)
			(pads allowed)
			(copperpour not_allowed)
			(footprints allowed)
		)
		(placement
			(enabled no)
			(sheetname "")
		)
		(fill
			(thermal_gap 0.5)
			(thermal_bridge_width 0.5)
			(island_removal_mode 0)
		)
		(polygon
			(pts
				(arc
					(start 77.667358 -92.911168)
					(mid 77.283818 -92.527628)
					(end 76.900278 -92.911168)
				)
				(xy 76.900278 -93.111828) (xy 77.029056 -93.111828)
				(arc
					(start 77.033628 -93.111828)
					(mid 77.065066 -93.108842)
					(end 77.09535 -93.09989)
				)
				(arc
					(start 77.09535 -93.09989)
					(mid 77.388378 -92.665804)
					(end 77.27823 -93.177868)
				)
				(arc
					(start 77.27823 -93.177868)
					(mid 77.183934 -93.24809)
					(end 77.07122 -93.2815)
				)
				(xy 77.069188 -93.283532) (xy 77.042772 -93.283532) (xy 77.033628 -93.283532) (xy 77.029056 -93.283532)
				(xy 76.900278 -93.283532) (xy 76.900278 -93.423232) (xy 77.029056 -93.423232) (xy 77.033628 -93.422978)
				(xy 77.042772 -93.423232) (xy 77.069188 -93.423232)
				(arc
					(start 77.07122 -93.42501)
					(mid 77.186928 -93.459897)
					(end 77.282802 -93.533468)
				)
				(arc
					(start 77.282802 -93.533468)
					(mid 77.384107 -94.047295)
					(end 77.098652 -93.608144)
				)
				(arc
					(start 77.098652 -93.608144)
					(mid 77.066825 -93.598117)
					(end 77.033628 -93.594682)
				)
				(xy 77.029056 -93.594428) (xy 76.900278 -93.594428)
				(arc
					(start 76.900278 -93.799914)
					(mid 77.283691 -94.183708)
					(end 77.667358 -93.800168)
				)
			)
		)
	)
	(zone
		(net "P1V5")
		(layer "F.Cu")
		(hatch none 0.5)
		(connect_pads
			(clearance 0.5)
		)
		(min_thickness 0.25)
		(fill yes
			(thermal_gap 0.5)
			(thermal_bridge_width 0.5)
			(island_removal_mode 0)
		)
		(polygon
			(pts
				(xy 213.614 -117.0686) (xy 213.4108 -117.2718) (xy 213.4108 -119.8372) (xy 213.6394 -120.0658) (xy 216.154 -120.0658)
				(xy 216.3318 -119.888) (xy 216.3318 -117.2464) (xy 216.154 -117.0686)
			)
		)
	)
	(zone
		(layer "F.Cu")
		(hatch none 0.5)
		(connect_pads
			(clearance 0)
		)
		(min_thickness 0.25)
		(keepout
			(tracks allowed)
			(vias allowed)
			(pads allowed)
			(copperpour allowed)
			(footprints not_allowed)
		)
		(placement
			(enabled no)
			(sheetname "")
		)
		(fill
			(thermal_gap 0.5)
			(thermal_bridge_width 0.5)
			(island_removal_mode 0)
		)
		(polygon
			(pts
				(arc
					(start 0 -0.999998)
					(mid 0.292893 -0.292893)
					(end 0.999998 0)
				)
				(xy 4.99999 0)
				(arc
					(start 4.99999 -193.786252)
					(mid 4.843029 -193.632013)
					(end 4.723638 -193.447162)
				)
				(arc
					(start 0.105664 -184.211214)
					(mid 0.026808 -183.993717)
					(end 0 -183.76392)
				)
			)
		)
	)
	(zone
		(layer "F.Cu")
		(hatch none 0.5)
		(connect_pads
			(clearance 0)
		)
		(min_thickness 0.25)
		(keepout
			(tracks allowed)
			(vias allowed)
			(pads allowed)
			(copperpour allowed)
			(footprints allowed)
		)
		(placement
			(enabled no)
			(sheetname "")
		)
		(fill
			(thermal_gap 0.5)
			(thermal_bridge_width 0.5)
			(island_removal_mode 0)
		)
		(polygon
			(pts
				(xy 81.2419 -53.6321) (xy 79.3877 -53.6321) (xy 76.9493 -53.6321) (xy 75.6793 -53.6321) (xy 75.1332 -53.086)
				(xy 75.1332 -51.8668) (xy 75.2729 -51.7271) (xy 76.5175 -51.7271) (xy 80.6831 -51.7271) (xy 81.2419 -52.2859)
			)
		)
	)
	(zone
		(layer "F.Cu")
		(hatch none 0.5)
		(connect_pads
			(clearance 0)
		)
		(min_thickness 0.25)
		(keepout
			(tracks not_allowed)
			(vias allowed)
			(pads allowed)
			(copperpour not_allowed)
			(footprints allowed)
		)
		(placement
			(enabled no)
			(sheetname "")
		)
		(fill
			(thermal_gap 0.5)
			(thermal_bridge_width 0.5)
			(island_removal_mode 0)
		)
		(polygon
			(pts
				(arc
					(start 216.799922 -84.479892)
					(mid 219.799916 -81.479898)
					(end 222.79991 -84.479892)
				)
				(arc
					(start 222.79991 -84.479892)
					(mid 219.799916 -87.479886)
					(end 216.799922 -84.479892)
				)
			)
		)
	)
	(zone
		(net "GND")
		(layer "F.Cu")
		(hatch none 0.5)
		(connect_pads
			(clearance 0.5)
		)
		(min_thickness 0.25)
		(fill yes
			(thermal_gap 0.5)
			(thermal_bridge_width 0.5)
			(island_removal_mode 0)
		)
		(polygon
			(pts
				(xy 190.0936 -102.4636) (xy 189.5602 -102.997) (xy 189.5602 -105.5624) (xy 190.0428 -106.045) (xy 202.0824 -106.045)
				(xy 202.2348 -105.8926) (xy 202.2348 -102.9462) (xy 201.7522 -102.4636)
			)
		)
		(polygon
			(pts
				(xy 201.1426 -105.3846) (xy 200.9394 -105.3846) (xy 200.9394 -105.5878) (xy 201.1426 -105.5878)
			)
		)
		(polygon
			(pts
				(xy 200.5838 -105.3846) (xy 200.3806 -105.3846) (xy 200.3806 -105.5878) (xy 200.5838 -105.5878)
			)
		)
		(polygon
			(pts
				(xy 200.2028 -105.3084) (xy 199.9996 -105.3084) (xy 199.9996 -105.5116) (xy 200.2028 -105.5116)
			)
		)
		(polygon
			(pts
				(xy 199.5932 -105.3084) (xy 199.39 -105.3084) (xy 199.39 -105.5116) (xy 199.5932 -105.5116)
			)
		)
		(polygon
			(pts
				(xy 199.2884 -104.9274) (xy 199.0852 -104.9274) (xy 199.0852 -105.1306) (xy 199.2884 -105.1306)
			)
		)
		(polygon
			(pts
				(xy 198.4248 -104.9274) (xy 198.2216 -104.9274) (xy 198.2216 -105.1306) (xy 198.4248 -105.1306)
			)
		)
	)
	(zone
		(layer "F.Cu")
		(hatch none 0.5)
		(connect_pads
			(clearance 0)
		)
		(min_thickness 0.25)
		(keepout
			(tracks allowed)
			(vias allowed)
			(pads allowed)
			(copperpour allowed)
			(footprints allowed)
		)
		(placement
			(enabled no)
			(sheetname "")
		)
		(fill
			(thermal_gap 0.5)
			(thermal_bridge_width 0.5)
			(island_removal_mode 0)
		)
		(polygon
			(pts
				(xy 96.647 -130.2258) (xy 96.647 -131.0132) (xy 94.7928 -131.0132) (xy 94.6658 -130.8862) (xy 94.6658 -129.1336)
				(xy 94.9198 -128.8796) (xy 96.5454 -128.8796) (xy 96.6978 -129.032) (xy 96.6978 -129.2606) (xy 96.6978 -130.175)
			)
		)
	)
	(zone
		(layer "F.Cu")
		(hatch none 0.5)
		(connect_pads
			(clearance 0)
		)
		(min_thickness 0.25)
		(keepout
			(tracks allowed)
			(vias allowed)
			(pads allowed)
			(copperpour allowed)
			(footprints allowed)
		)
		(placement
			(enabled no)
			(sheetname "")
		)
		(fill
			(thermal_gap 0.5)
			(thermal_bridge_width 0.5)
			(island_removal_mode 0)
		)
		(polygon
			(pts
				(xy 115.131342 -6.644894) (xy 116.985542 -6.644894) (xy 116.985542 -10.8966) (xy 115.131342 -10.8966)
			)
		)
	)
	(zone
		(net "P2V5_STBY")
		(layer "F.Cu")
		(hatch none 0.5)
		(connect_pads
			(clearance 0.5)
		)
		(min_thickness 0.25)
		(fill yes
			(thermal_gap 0.5)
			(thermal_bridge_width 0.5)
			(island_removal_mode 0)
		)
		(polygon
			(pts
				(xy 75.588876 -170.816524) (xy 75.565 -170.8404) (xy 75.565 -172.0088) (xy 75.70978 -172.15358)
				(xy 79.201264 -172.15358) (xy 79.307182 -172.047662) (xy 79.307182 -170.938698) (xy 79.185008 -170.816524)
			)
		)
	)
	(zone
		(layer "F.Cu")
		(hatch none 0.5)
		(connect_pads
			(clearance 0)
		)
		(min_thickness 0.25)
		(keepout
			(tracks allowed)
			(vias allowed)
			(pads allowed)
			(copperpour allowed)
			(footprints allowed)
		)
		(placement
			(enabled no)
			(sheetname "")
		)
		(fill
			(thermal_gap 0.5)
			(thermal_bridge_width 0.5)
			(island_removal_mode 0)
		)
		(polygon
			(pts
				(xy 182.3593 -48.6029) (xy 182.3593 -46.3677) (xy 183.0705 -46.3677) (xy 183.0705 -48.6029)
			)
		)
	)
	(zone
		(layer "F.Cu")
		(hatch none 0.5)
		(connect_pads
			(clearance 0)
		)
		(min_thickness 0.25)
		(keepout
			(tracks allowed)
			(vias allowed)
			(pads allowed)
			(copperpour allowed)
			(footprints not_allowed)
		)
		(placement
			(enabled no)
			(sheetname "")
		)
		(fill
			(thermal_gap 0.5)
			(thermal_bridge_width 0.5)
			(island_removal_mode 0)
		)
		(polygon
			(pts
				(arc
					(start 217.749882 -187.999878)
					(mid 222.499936 -183.249824)
					(end 227.24999 -187.999878)
				)
				(arc
					(start 227.24999 -187.999878)
					(mid 222.499936 -192.749932)
					(end 217.749882 -187.999878)
				)
			)
		)
	)
	(zone
		(layer "F.Cu")
		(hatch none 0.5)
		(connect_pads
			(clearance 0)
		)
		(min_thickness 0.25)
		(keepout
			(tracks not_allowed)
			(vias allowed)
			(pads allowed)
			(copperpour not_allowed)
			(footprints allowed)
		)
		(placement
			(enabled no)
			(sheetname "")
		)
		(fill
			(thermal_gap 0.5)
			(thermal_bridge_width 0.5)
			(island_removal_mode 0)
		)
		(polygon
			(pts
				(arc
					(start 227.24999 -14.99997)
					(mid 222.499936 -19.750024)
					(end 217.749882 -14.99997)
				)
				(arc
					(start 217.749882 -14.99997)
					(mid 222.499936 -10.249916)
					(end 227.24999 -14.99997)
				)
			)
		)
	)
	(zone
		(layer "F.Cu")
		(hatch none 0.5)
		(connect_pads
			(clearance 0)
		)
		(min_thickness 0.25)
		(keepout
			(tracks not_allowed)
			(vias allowed)
			(pads allowed)
			(copperpour not_allowed)
			(footprints allowed)
		)
		(placement
			(enabled no)
			(sheetname "")
		)
		(fill
			(thermal_gap 0.5)
			(thermal_bridge_width 0.5)
			(island_removal_mode 0)
		)
		(polygon
			(pts
				(arc
					(start 207.941672 -69.85)
					(mid 207.960368 -69.872402)
					(end 207.967072 -69.9008)
				)
				(arc
					(start 207.967072 -70.104)
					(mid 207.960368 -70.132398)
					(end 207.941672 -70.1548)
				)
				(arc
					(start 208.170272 -70.1548)
					(mid 208.151576 -70.132398)
					(end 208.144872 -70.104)
				)
				(arc
					(start 208.144872 -69.9008)
					(mid 208.151576 -69.872402)
					(end 208.170272 -69.85)
				)
			)
		)
	)
	(zone
		(layer "F.Cu")
		(hatch none 0.5)
		(connect_pads
			(clearance 0)
		)
		(min_thickness 0.25)
		(keepout
			(tracks allowed)
			(vias allowed)
			(pads allowed)
			(copperpour allowed)
			(footprints allowed)
		)
		(placement
			(enabled no)
			(sheetname "")
		)
		(fill
			(thermal_gap 0.5)
			(thermal_bridge_width 0.5)
			(island_removal_mode 0)
		)
		(polygon
			(pts
				(xy 156.2354 -137.287) (xy 156.2354 -136.7028) (xy 156.5656 -136.3726) (xy 158.0896 -136.3726) (xy 158.3182 -136.6012)
				(xy 158.3182 -136.7028) (xy 158.3182 -137.287)
			)
		)
	)
	(zone
		(layer "F.Cu")
		(hatch none 0.5)
		(connect_pads
			(clearance 0)
		)
		(min_thickness 0.25)
		(keepout
			(tracks allowed)
			(vias allowed)
			(pads allowed)
			(copperpour allowed)
			(footprints not_allowed)
		)
		(placement
			(enabled no)
			(sheetname "")
		)
		(fill
			(thermal_gap 0.5)
			(thermal_bridge_width 0.5)
			(island_removal_mode 0)
		)
		(polygon
			(pts
				(xy 161.800032 -34.100008) (xy 223.799908 -34.100008) (xy 223.799908 -96.099884) (xy 161.800032 -96.099884)
			)
		)
	)
	(zone
		(net "P1V8")
		(layer "F.Cu")
		(hatch none 0.5)
		(connect_pads
			(clearance 0.5)
		)
		(min_thickness 0.25)
		(fill yes
			(thermal_gap 0.5)
			(thermal_bridge_width 0.5)
			(island_removal_mode 0)
		)
		(polygon
			(pts
				(xy 201.92746 -62.12078) (xy 201.78776 -62.26048) (xy 201.78776 -62.56782) (xy 202.19924 -62.9793)
				(xy 202.19924 -63.41618) (xy 201.8157 -63.79972) (xy 201.8157 -64.0461) (xy 201.88682 -64.11722)
				(xy 202.11288 -64.11722) (xy 202.98664 -63.24346) (xy 202.98664 -62.91834) (xy 202.18908 -62.12078)
			)
		)
	)
	(zone
		(layer "F.Cu")
		(hatch none 0.5)
		(connect_pads
			(clearance 0)
		)
		(min_thickness 0.25)
		(keepout
			(tracks allowed)
			(vias allowed)
			(pads allowed)
			(copperpour allowed)
			(footprints allowed)
		)
		(placement
			(enabled no)
			(sheetname "")
		)
		(fill
			(thermal_gap 0.5)
			(thermal_bridge_width 0.5)
			(island_removal_mode 0)
		)
		(polygon
			(pts
				(xy 65.278 -177.5714) (xy 65.278 -175.7172) (xy 66.6242 -175.7172) (xy 66.6242 -177.5714)
			)
		)
	)
	(zone
		(layer "F.Cu")
		(hatch none 0.5)
		(connect_pads
			(clearance 0)
		)
		(min_thickness 0.25)
		(keepout
			(tracks allowed)
			(vias allowed)
			(pads allowed)
			(copperpour allowed)
			(footprints not_allowed)
		)
		(placement
			(enabled no)
			(sheetname "")
		)
		(fill
			(thermal_gap 0.5)
			(thermal_bridge_width 0.5)
			(island_removal_mode 0)
		)
		(polygon
			(pts
				(arc
					(start 217.749882 -110.000034)
					(mid 222.499936 -105.24998)
					(end 227.24999 -110.000034)
				)
				(arc
					(start 227.24999 -110.000034)
					(mid 222.499936 -114.750088)
					(end 217.749882 -110.000034)
				)
			)
		)
	)
	(zone
		(net "P3V3_STBY")
		(layer "F.Cu")
		(hatch none 0.5)
		(connect_pads
			(clearance 0.5)
		)
		(min_thickness 0.25)
		(fill yes
			(thermal_gap 0.5)
			(thermal_bridge_width 0.5)
			(island_removal_mode 0)
		)
		(polygon
			(pts
				(xy 93.873828 -49.548796) (xy 93.869256 -49.553368) (xy 93.869256 -50.086768) (xy 93.915484 -50.132996)
				(xy 94.585028 -50.132996) (xy 94.85503 -50.402998) (xy 94.85503 -52.443888) (xy 94.598236 -52.700682)
				(xy 93.666818 -52.700682) (xy 93.575632 -52.609496) (xy 93.575632 -51.7906) (xy 93.442028 -51.656996)
				(xy 92.934028 -51.656996) (xy 92.807028 -51.783996) (xy 92.807028 -52.393596) (xy 92.959428 -52.545996)
				(xy 92.959428 -54.069996) (xy 93.016578 -54.127146) (xy 94.311978 -54.127146) (xy 94.508828 -54.323996)
				(xy 95.19412 -54.323996) (xy 95.52432 -53.993796) (xy 95.52432 -50.081688) (xy 95.093028 -49.650396)
				(xy 94.458028 -49.650396) (xy 94.356428 -49.548796)
			)
		)
	)
	(zone
		(net "TPS74801_P1V5_FB")
		(layer "F.Cu")
		(hatch none 0.5)
		(connect_pads
			(clearance 0.5)
		)
		(min_thickness 0.25)
		(fill yes
			(thermal_gap 0.5)
			(thermal_bridge_width 0.5)
			(island_removal_mode 0)
		)
		(polygon
			(pts
				(xy 203.252832 -119.634) (xy 202.747372 -120.13946) (xy 202.747372 -124.837698) (xy 202.928474 -125.0188)
				(xy 204.597 -125.0188) (xy 204.6478 -124.968) (xy 204.6478 -123.5456) (xy 204.9653 -123.2281) (xy 204.9653 -119.6975)
				(xy 204.9018 -119.634)
			)
		)
		(polygon
			(pts
				(xy 204.529436 -122.3264) (xy 204.326236 -122.3264) (xy 204.326236 -122.5296) (xy 204.529436 -122.5296)
			)
		)
		(polygon
			(pts
				(xy 204.529436 -121.7676) (xy 204.326236 -121.7676) (xy 204.326236 -121.9708) (xy 204.529436 -121.9708)
			)
		)
		(polygon
			(pts
				(xy 204.4954 -121.412) (xy 204.2922 -121.412) (xy 204.2922 -121.6152) (xy 204.4954 -121.6152)
			)
		)
		(polygon
			(pts
				(xy 204.4954 -120.8024) (xy 204.2922 -120.8024) (xy 204.2922 -121.0056) (xy 204.4954 -121.0056)
			)
		)
		(polygon
			(pts
				(xy 204.5208 -120.4468) (xy 204.3176 -120.4468) (xy 204.3176 -120.65) (xy 204.5208 -120.65)
			)
		)
		(polygon
			(pts
				(xy 204.5208 -119.888) (xy 204.3176 -119.888) (xy 204.3176 -120.0912) (xy 204.5208 -120.0912)
			)
		)
	)
	(zone
		(net "MB0_CM_GATE_2")
		(layer "F.Cu")
		(hatch none 0.5)
		(connect_pads
			(clearance 0.5)
		)
		(min_thickness 0.25)
		(fill yes
			(thermal_gap 0.5)
			(thermal_bridge_width 0.5)
			(island_removal_mode 0)
		)
		(polygon
			(pts
				(xy 126.3015 -6.35) (xy 126.1364 -6.5151) (xy 126.1364 -6.985) (xy 126.7206 -7.5692) (xy 126.7206 -9.2964)
				(xy 126.871222 -9.447022) (xy 128.511046 -9.447022) (xy 128.514094 -9.45007) (xy 128.514094 -8.064754)
				(xy 128.495806 -8.046466) (xy 128.228598 -8.046466) (xy 128.1049 -7.922768) (xy 128.1049 -7.8105)
				(xy 128.0922 -7.7978) (xy 128.0922 -6.72338) (xy 128.03886 -6.67004) (xy 127.4572 -6.67004) (xy 127.13716 -6.35)
			)
		)
		(polygon
			(pts
				(xy 127.335788 -7.440422) (xy 127.132588 -7.440422) (xy 127.132588 -7.643622) (xy 127.335788 -7.643622)
			)
		)
	)
	(zone
		(layer "F.Cu")
		(hatch none 0.5)
		(connect_pads
			(clearance 0)
		)
		(min_thickness 0.25)
		(keepout
			(tracks not_allowed)
			(vias allowed)
			(pads allowed)
			(copperpour not_allowed)
			(footprints allowed)
		)
		(placement
			(enabled no)
			(sheetname "")
		)
		(fill
			(thermal_gap 0.5)
			(thermal_bridge_width 0.5)
			(island_removal_mode 0)
		)
		(polygon
			(pts
				(arc
					(start 204.698092 -85.146896)
					(mid 204.698092 -84.607908)
					(end 204.159104 -84.607908)
				)
				(xy 204.01534 -84.751672) (xy 204.103732 -84.840064)
				(arc
					(start 204.107034 -84.843366)
					(mid 204.132634 -84.864297)
					(end 204.161898 -84.879688)
				)
				(arc
					(start 204.161898 -84.879688)
					(mid 204.675289 -84.776023)
					(end 204.237336 -85.06333)
				)
				(arc
					(start 204.237336 -85.06333)
					(mid 204.118827 -85.046637)
					(end 204.013562 -84.98967)
				)
				(xy 204.010768 -84.98967) (xy 203.992226 -84.971128) (xy 203.985622 -84.964778) (xy 203.98232 -84.961476)
				(xy 203.894182 -84.873084) (xy 203.795122 -84.972144) (xy 203.883514 -85.060282) (xy 203.886816 -85.063584)
				(xy 203.893166 -85.070188) (xy 203.911708 -85.08873)
				(arc
					(start 203.911708 -85.091524)
					(mid 203.968424 -85.196054)
					(end 203.985368 -85.313774)
				)
				(arc
					(start 203.985368 -85.313774)
					(mid 203.699774 -85.752929)
					(end 203.801472 -85.239098)
				)
				(arc
					(start 203.801472 -85.239098)
					(mid 203.786125 -85.210255)
					(end 203.765404 -85.184996)
				)
				(xy 203.762102 -85.181694) (xy 203.673964 -85.093302)
				(arc
					(start 203.535534 -85.231732)
					(mid 203.528455 -85.772846)
					(end 204.069696 -85.775292)
				)
			)
		)
	)
	(zone
		(layer "F.Cu")
		(hatch none 0.5)
		(connect_pads
			(clearance 0)
		)
		(min_thickness 0.25)
		(keepout
			(tracks allowed)
			(vias allowed)
			(pads allowed)
			(copperpour allowed)
			(footprints allowed)
		)
		(placement
			(enabled no)
			(sheetname "")
		)
		(fill
			(thermal_gap 0.5)
			(thermal_bridge_width 0.5)
			(island_removal_mode 0)
		)
		(polygon
			(pts
				(xy 179.5018 -48.6791) (xy 179.5018 -46.4439) (xy 180.213 -46.4439) (xy 180.213 -48.6791)
			)
		)
	)
	(zone
		(layer "F.Cu")
		(hatch none 0.5)
		(connect_pads
			(clearance 0)
		)
		(min_thickness 0.25)
		(keepout
			(tracks not_allowed)
			(vias allowed)
			(pads allowed)
			(copperpour not_allowed)
			(footprints allowed)
		)
		(placement
			(enabled no)
			(sheetname "")
		)
		(fill
			(thermal_gap 0.5)
			(thermal_bridge_width 0.5)
			(island_removal_mode 0)
		)
		(polygon
			(pts
				(arc
					(start 207.941672 -76.5556)
					(mid 207.960368 -76.578002)
					(end 207.967072 -76.6064)
				)
				(arc
					(start 207.967072 -76.8096)
					(mid 207.960368 -76.837998)
					(end 207.941672 -76.8604)
				)
				(arc
					(start 208.170272 -76.8604)
					(mid 208.151576 -76.837998)
					(end 208.144872 -76.8096)
				)
				(arc
					(start 208.144872 -76.6064)
					(mid 208.151576 -76.578002)
					(end 208.170272 -76.5556)
				)
			)
		)
	)
	(zone
		(layer "F.Cu")
		(hatch none 0.5)
		(connect_pads
			(clearance 0)
		)
		(min_thickness 0.25)
		(keepout
			(tracks allowed)
			(vias allowed)
			(pads allowed)
			(copperpour allowed)
			(footprints allowed)
		)
		(placement
			(enabled no)
			(sheetname "")
		)
		(fill
			(thermal_gap 0.5)
			(thermal_bridge_width 0.5)
			(island_removal_mode 0)
		)
		(polygon
			(pts
				(xy 179.2605 -157.7213) (xy 180.7591 -157.7213) (xy 180.9115 -157.5689) (xy 180.9115 -155.4353)
				(xy 180.5813 -155.1051) (xy 179.3875 -155.1051) (xy 179.2097 -155.2829) (xy 179.2097 -157.6705)
			)
		)
	)
	(zone
		(net "TPS74801_P1V2_STBY_OUT")
		(layer "F.Cu")
		(hatch none 0.5)
		(connect_pads
			(clearance 0.5)
		)
		(min_thickness 0.25)
		(fill yes
			(thermal_gap 0.5)
			(thermal_bridge_width 0.5)
			(island_removal_mode 0)
		)
		(polygon
			(pts
				(xy 16.665956 -161.286444) (xy 16.2052 -161.7472) (xy 16.2052 -163.6014) (xy 16.21282 -163.60902)
				(xy 16.21282 -163.83762) (xy 16.32712 -163.95192) (xy 16.9164 -163.95192) (xy 17.0942 -164.12972)
				(xy 17.0942 -165.608) (xy 16.4846 -166.2176) (xy 16.4846 -167.1574) (xy 16.51 -167.1828) (xy 18.5674 -167.1828)
				(xy 18.6182 -167.2336) (xy 18.6182 -167.9956) (xy 19.812 -167.9956) (xy 19.9136 -167.894) (xy 19.9136 -167.5892)
				(xy 20.1676 -167.3352) (xy 23.622 -167.3352) (xy 23.9776 -166.9796) (xy 23.9776 -161.8742) (xy 23.389844 -161.286444)
			)
		)
		(polygon
			(pts
				(xy 16.886936 -163.1442) (xy 16.683736 -163.1442) (xy 16.683736 -163.3474) (xy 16.886936 -163.3474)
			)
		)
		(polygon
			(pts
				(xy 16.853916 -162.7251) (xy 16.650716 -162.7251) (xy 16.650716 -162.9283) (xy 16.853916 -162.9283)
			)
		)
		(polygon
			(pts
				(xy 16.853916 -162.1663) (xy 16.650716 -162.1663) (xy 16.650716 -162.3695) (xy 16.853916 -162.3695)
			)
		)
		(polygon
			(pts
				(xy 22.1234 -161.8234) (xy 21.9202 -161.8234) (xy 21.9202 -162.0266) (xy 22.1234 -162.0266)
			)
		)
		(polygon
			(pts
				(xy 21.5138 -161.8234) (xy 21.3106 -161.8234) (xy 21.3106 -162.0266) (xy 21.5138 -162.0266)
			)
		)
	)
	(zone
		(net "GND")
		(layer "F.Cu")
		(hatch none 0.5)
		(connect_pads
			(clearance 0.5)
		)
		(min_thickness 0.25)
		(fill yes
			(thermal_gap 0.5)
			(thermal_bridge_width 0.5)
			(island_removal_mode 0)
		)
		(polygon
			(pts
				(xy 33.108646 -177.09261) (xy 32.600646 -177.60061) (xy 32.600646 -178.828446) (xy 32.7406 -178.9684)
				(xy 32.7406 -186.5122) (xy 32.9692 -186.7408) (xy 34.3916 -186.7408) (xy 34.544 -186.5884) (xy 34.544 -184.4548)
				(xy 34.64814 -184.35066) (xy 35.2425 -184.35066) (xy 35.2425 -184.6199) (xy 35.5854 -184.6199) (xy 35.59048 -184.61482)
				(xy 35.59048 -184.37606) (xy 35.60572 -184.36082) (xy 35.60826 -184.36336) (xy 35.902646 -184.36336)
				(xy 35.902646 -177.60061) (xy 35.394646 -177.09261)
			)
		)
	)
	(zone
		(layer "F.Cu")
		(hatch none 0.5)
		(connect_pads
			(clearance 0)
		)
		(min_thickness 0.25)
		(keepout
			(tracks not_allowed)
			(vias allowed)
			(pads allowed)
			(copperpour not_allowed)
			(footprints allowed)
		)
		(placement
			(enabled no)
			(sheetname "")
		)
		(fill
			(thermal_gap 0.5)
			(thermal_bridge_width 0.5)
			(island_removal_mode 0)
		)
		(polygon
			(pts
				(arc
					(start 77.658214 -67.322446)
					(mid 77.274801 -66.938652)
					(end 76.891134 -67.322192)
				)
				(xy 76.891134 -67.518788) (xy 77.054456 -67.518788)
				(arc
					(start 77.059028 -67.518788)
					(mid 77.074765 -67.517832)
					(end 77.09027 -67.514978)
				)
				(arc
					(start 77.09027 -67.514978)
					(mid 77.368765 -67.072839)
					(end 77.284834 -67.588638)
				)
				(arc
					(start 77.284834 -67.588638)
					(mid 77.199918 -67.655526)
					(end 77.096874 -67.688206)
				)
				(xy 77.094588 -67.690492) (xy 77.067664 -67.690492) (xy 77.059028 -67.690492) (xy 77.054456 -67.690492)
				(xy 76.891134 -67.690492) (xy 76.891134 -67.830192) (xy 77.054456 -67.830192) (xy 77.059028 -67.829938)
				(xy 77.067664 -67.830192) (xy 77.094588 -67.830192)
				(arc
					(start 77.096874 -67.832224)
					(mid 77.207734 -67.869049)
					(end 77.296264 -67.945254)
				)
				(arc
					(start 77.296264 -67.945254)
					(mid 77.357482 -68.464891)
					(end 77.101192 -68.008754)
				)
				(arc
					(start 77.101192 -68.008754)
					(mid 77.080405 -68.003443)
					(end 77.059028 -68.001642)
				)
				(xy 77.054456 -68.001388) (xy 76.891134 -68.001388)
				(arc
					(start 76.891134 -68.211192)
					(mid 77.274674 -68.594732)
					(end 77.658214 -68.211192)
				)
			)
		)
	)
	(zone
		(layer "F.Cu")
		(hatch none 0.5)
		(connect_pads
			(clearance 0)
		)
		(min_thickness 0.25)
		(keepout
			(tracks allowed)
			(vias allowed)
			(pads allowed)
			(copperpour allowed)
			(footprints not_allowed)
		)
		(placement
			(enabled no)
			(sheetname "")
		)
		(fill
			(thermal_gap 0.5)
			(thermal_bridge_width 0.5)
			(island_removal_mode 0)
		)
		(polygon
			(pts
				(arc
					(start 222.79991 -84.479892)
					(mid 219.799916 -87.479886)
					(end 216.799922 -84.479892)
				)
				(arc
					(start 216.799922 -84.479892)
					(mid 219.799916 -81.479898)
					(end 222.79991 -84.479892)
				)
			)
		)
	)
	(zone
		(layer "F.Cu")
		(hatch none 0.5)
		(connect_pads
			(clearance 0)
		)
		(min_thickness 0.25)
		(keepout
			(tracks allowed)
			(vias allowed)
			(pads allowed)
			(copperpour allowed)
			(footprints allowed)
		)
		(placement
			(enabled no)
			(sheetname "")
		)
		(fill
			(thermal_gap 0.5)
			(thermal_bridge_width 0.5)
			(island_removal_mode 0)
		)
		(polygon
			(pts
				(xy 207.4164 -70.2818) (xy 207.4164 -69.1642) (xy 208.7118 -69.1642) (xy 208.7118 -70.2818)
			)
		)
	)
	(zone
		(layer "F.Cu")
		(hatch none 0.5)
		(connect_pads
			(clearance 0)
		)
		(min_thickness 0.25)
		(keepout
			(tracks not_allowed)
			(vias allowed)
			(pads allowed)
			(copperpour not_allowed)
			(footprints allowed)
		)
		(placement
			(enabled no)
			(sheetname "")
		)
		(fill
			(thermal_gap 0.5)
			(thermal_bridge_width 0.5)
			(island_removal_mode 0)
		)
		(polygon
			(pts
				(arc
					(start 107.750102 -9.99998)
					(mid 103.000048 -14.750034)
					(end 98.249994 -9.99998)
				)
				(arc
					(start 98.249994 -9.99998)
					(mid 103.000048 -5.249926)
					(end 107.750102 -9.99998)
				)
			)
		)
	)
	(zone
		(net "P5V_VBUS_CONN")
		(layer "F.Cu")
		(hatch none 0.5)
		(connect_pads
			(clearance 0.5)
		)
		(min_thickness 0.25)
		(fill yes
			(thermal_gap 0.5)
			(thermal_bridge_width 0.5)
			(island_removal_mode 0)
		)
		(polygon
			(pts
				(xy 84.5058 -20.2438) (xy 84.0232 -20.7264) (xy 84.0232 -26.716482) (xy 84.728304 -27.421586) (xy 88.16594 -27.421586)
				(xy 88.429846 -27.685492) (xy 90.05951 -27.685492) (xy 90.299286 -27.445716) (xy 90.299286 -24.12746)
				(xy 89.1286 -22.956774) (xy 89.1286 -20.7518) (xy 88.6206 -20.2438)
			)
		)
		(polygon
			(pts
				(xy 90.1319 -26.0477) (xy 89.9287 -26.0477) (xy 89.9287 -26.2509) (xy 90.1319 -26.2509)
			)
		)
		(polygon
			(pts
				(xy 88.9889 -26.0477) (xy 88.7857 -26.0477) (xy 88.7857 -26.2509) (xy 88.9889 -26.2509)
			)
		)
	)
	(zone
		(layer "F.Cu")
		(hatch none 0.5)
		(connect_pads
			(clearance 0)
		)
		(min_thickness 0.25)
		(keepout
			(tracks allowed)
			(vias allowed)
			(pads allowed)
			(copperpour allowed)
			(footprints allowed)
		)
		(placement
			(enabled no)
			(sheetname "")
		)
		(fill
			(thermal_gap 0.5)
			(thermal_bridge_width 0.5)
			(island_removal_mode 0)
		)
		(polygon
			(pts
				(xy 35.4838 -175.9712) (xy 35.4838 -174.1678) (xy 35.4838 -174.0154) (xy 37.0586 -174.0154) (xy 37.1221 -174.0789)
				(xy 37.719 -173.482) (xy 38.1 -173.482) (xy 38.989 -174.371) (xy 38.989 -175.768) (xy 38.7858 -175.9712)
				(xy 37.3126 -175.9712)
			)
		)
	)
	(zone
		(layer "F.Cu")
		(hatch none 0.5)
		(connect_pads
			(clearance 0)
		)
		(min_thickness 0.25)
		(keepout
			(tracks not_allowed)
			(vias allowed)
			(pads allowed)
			(copperpour not_allowed)
			(footprints allowed)
		)
		(placement
			(enabled no)
			(sheetname "")
		)
		(fill
			(thermal_gap 0.5)
			(thermal_bridge_width 0.5)
			(island_removal_mode 0)
		)
		(polygon
			(pts
				(arc
					(start 207.941672 -70.9676)
					(mid 207.960368 -70.990002)
					(end 207.967072 -71.0184)
				)
				(arc
					(start 207.967072 -71.2216)
					(mid 207.960368 -71.249998)
					(end 207.941672 -71.2724)
				)
				(arc
					(start 208.170272 -71.2724)
					(mid 208.151576 -71.249998)
					(end 208.144872 -71.2216)
				)
				(arc
					(start 208.144872 -71.0184)
					(mid 208.151576 -70.990002)
					(end 208.170272 -70.9676)
				)
			)
		)
	)
	(zone
		(layer "F.Cu")
		(hatch none 0.5)
		(connect_pads
			(clearance 0)
		)
		(min_thickness 0.25)
		(keepout
			(tracks allowed)
			(vias allowed)
			(pads allowed)
			(copperpour allowed)
			(footprints allowed)
		)
		(placement
			(enabled no)
			(sheetname "")
		)
		(fill
			(thermal_gap 0.5)
			(thermal_bridge_width 0.5)
			(island_removal_mode 0)
		)
		(polygon
			(pts
				(xy 92.4052 -129.5908) (xy 92.4052 -130.3782) (xy 90.551 -130.3782) (xy 90.2462 -130.3782) (xy 89.9414 -130.0734)
				(xy 89.9414 -128.397) (xy 92.2528 -128.397) (xy 92.4052 -128.5494) (xy 92.4052 -128.9558)
			)
		)
	)
	(zone
		(layer "F.Cu")
		(hatch none 0.5)
		(connect_pads
			(clearance 0)
		)
		(min_thickness 0.25)
		(keepout
			(tracks allowed)
			(vias allowed)
			(pads allowed)
			(copperpour allowed)
			(footprints allowed)
		)
		(placement
			(enabled no)
			(sheetname "")
		)
		(fill
			(thermal_gap 0.5)
			(thermal_bridge_width 0.5)
			(island_removal_mode 0)
		)
		(polygon
			(pts
				(xy 155.829 -89.7128) (xy 155.829 -87.4776) (xy 157.4292 -87.4776) (xy 157.4292 -89.7128)
			)
		)
	)
	(zone
		(layer "F.Cu")
		(hatch none 0.5)
		(connect_pads
			(clearance 0)
		)
		(min_thickness 0.25)
		(keepout
			(tracks not_allowed)
			(vias allowed)
			(pads allowed)
			(copperpour not_allowed)
			(footprints allowed)
		)
		(placement
			(enabled no)
			(sheetname "")
		)
		(fill
			(thermal_gap 0.5)
			(thermal_bridge_width 0.5)
			(island_removal_mode 0)
		)
		(polygon
			(pts
				(arc
					(start 212.137498 -63.3857)
					(mid 212.137498 -62.84722)
					(end 211.599018 -62.84722)
				)
				(xy 211.598764 -62.846966) (xy 211.391246 -63.054484)
				(arc
					(start 211.57184 -63.235078)
					(mid 211.601336 -63.249517)
					(end 211.633562 -63.242952)
				)
				(arc
					(start 211.633562 -63.242952)
					(mid 212.057383 -62.928539)
					(end 211.740242 -63.350394)
				)
				(xy 211.727542 -63.363094)
				(arc
					(start 211.723478 -63.363094)
					(mid 211.607654 -63.399902)
					(end 211.49183 -63.363094)
				)
				(xy 211.487766 -63.363094) (xy 211.285074 -63.160656) (xy 211.103718 -63.342012) (xy 211.306156 -63.54445)
				(arc
					(start 211.306156 -63.548514)
					(mid 211.34311 -63.664488)
					(end 211.306156 -63.780416)
				)
				(xy 211.306156 -63.78448)
				(arc
					(start 211.293964 -63.796672)
					(mid 210.871542 -64.113471)
					(end 211.186522 -63.689738)
				)
				(arc
					(start 211.186522 -63.689738)
					(mid 211.192707 -63.657707)
					(end 211.17814 -63.628524)
				)
				(xy 210.9978 -63.44793) (xy 210.790536 -63.655194)
				(arc
					(start 210.79079 -63.655448)
					(mid 210.79079 -64.193928)
					(end 211.32927 -64.193928)
				)
				(xy 211.329524 -64.194182) (xy 212.137498 -63.385954)
			)
		)
	)
	(zone
		(layer "F.Cu")
		(hatch none 0.5)
		(connect_pads
			(clearance 0)
		)
		(min_thickness 0.25)
		(keepout
			(tracks allowed)
			(vias allowed)
			(pads allowed)
			(copperpour allowed)
			(footprints not_allowed)
		)
		(placement
			(enabled no)
			(sheetname "")
		)
		(fill
			(thermal_gap 0.5)
			(thermal_bridge_width 0.5)
			(island_removal_mode 0)
		)
		(polygon
			(pts
				(arc
					(start 37.69995 -169.999914)
					(mid 41.450006 -166.249858)
					(end 45.200062 -169.999914)
				)
				(arc
					(start 45.200062 -169.999914)
					(mid 41.450006 -173.74997)
					(end 37.69995 -169.999914)
				)
			)
		)
	)
	(zone
		(net "P12V_STBY_VIN_PU2")
		(layer "F.Cu")
		(hatch none 0.5)
		(connect_pads
			(clearance 0.5)
		)
		(min_thickness 0.25)
		(fill yes
			(thermal_gap 0.5)
			(thermal_bridge_width 0.5)
			(island_removal_mode 0)
		)
		(polygon
			(pts
				(xy 31.041594 -181.53761) (xy 30.745684 -181.83352) (xy 27.506422 -181.83352) (xy 27.325574 -181.652672)
				(xy 24.153368 -181.652672) (xy 23.687532 -182.118254) (xy 23.687532 -184.555638) (xy 23.173944 -185.069226)
				(xy 23.173944 -186.18962) (xy 23.135082 -186.228482) (xy 25.099518 -186.228482) (xy 25.107646 -186.23661)
				(xy 30.61208 -186.23661) (xy 31.01213 -186.63666) (xy 32.38754 -186.63666) (xy 32.41675 -186.60745)
				(xy 32.41675 -184.71134) (xy 32.346646 -184.641236) (xy 32.346646 -181.79161) (xy 32.092646 -181.53761)
			)
		)
		(polygon
			(pts
				(xy 24.9301 -184.1627) (xy 24.7269 -184.1627) (xy 24.7269 -184.3659) (xy 24.9301 -184.3659)
			)
		)
		(polygon
			(pts
				(xy 24.9301 -182.7657) (xy 24.7269 -182.7657) (xy 24.7269 -182.9689) (xy 24.9301 -182.9689)
			)
		)
	)
	(zone
		(layer "F.Cu")
		(hatch none 0.5)
		(connect_pads
			(clearance 0)
		)
		(min_thickness 0.25)
		(keepout
			(tracks allowed)
			(vias allowed)
			(pads allowed)
			(copperpour allowed)
			(footprints not_allowed)
		)
		(placement
			(enabled no)
			(sheetname "")
		)
		(fill
			(thermal_gap 0.5)
			(thermal_bridge_width 0.5)
			(island_removal_mode 0)
		)
		(polygon
			(pts
				(xy 161.800032 -34.100008) (xy 161.800032 -96.099884) (xy 223.799908 -96.099884) (xy 223.799908 -34.100008)
			)
		)
	)
	(zone
		(layer "F.Cu")
		(hatch none 0.5)
		(connect_pads
			(clearance 0)
		)
		(min_thickness 0.25)
		(keepout
			(tracks not_allowed)
			(vias allowed)
			(pads allowed)
			(copperpour not_allowed)
			(footprints allowed)
		)
		(placement
			(enabled no)
			(sheetname "")
		)
		(fill
			(thermal_gap 0.5)
			(thermal_bridge_width 0.5)
			(island_removal_mode 0)
		)
		(polygon
			(pts
				(arc
					(start 207.941672 -72.644)
					(mid 207.960368 -72.666402)
					(end 207.967072 -72.6948)
				)
				(arc
					(start 207.967072 -72.898)
					(mid 207.960368 -72.926398)
					(end 207.941672 -72.9488)
				)
				(arc
					(start 208.170272 -72.9488)
					(mid 208.151576 -72.926398)
					(end 208.144872 -72.898)
				)
				(arc
					(start 208.144872 -72.6948)
					(mid 208.151576 -72.666402)
					(end 208.170272 -72.644)
				)
			)
		)
	)
	(zone
		(layer "F.Cu")
		(hatch none 0.5)
		(connect_pads
			(clearance 0)
		)
		(min_thickness 0.25)
		(keepout
			(tracks allowed)
			(vias allowed)
			(pads allowed)
			(copperpour allowed)
			(footprints allowed)
		)
		(placement
			(enabled no)
			(sheetname "")
		)
		(fill
			(thermal_gap 0.5)
			(thermal_bridge_width 0.5)
			(island_removal_mode 0)
		)
		(polygon
			(pts
				(xy 36.6014 -181.229) (xy 36.6014 -179.4256) (xy 36.6014 -179.2732) (xy 36.6014 -177.7746) (xy 37.084 -177.292)
				(xy 38.354 -177.292) (xy 38.4302 -177.3682) (xy 38.4302 -179.5272) (xy 38.4302 -181.229)
			)
		)
	)
	(zone
		(layer "F.Cu")
		(hatch none 0.5)
		(connect_pads
			(clearance 0)
		)
		(min_thickness 0.25)
		(keepout
			(tracks allowed)
			(vias allowed)
			(pads allowed)
			(copperpour allowed)
			(footprints allowed)
		)
		(placement
			(enabled no)
			(sheetname "")
		)
		(fill
			(thermal_gap 0.5)
			(thermal_bridge_width 0.5)
			(island_removal_mode 0)
		)
		(polygon
			(pts
				(xy 184.5056 -150.5458) (xy 186.0042 -150.5458) (xy 186.1566 -150.3934) (xy 186.1566 -148.2598)
				(xy 185.8264 -147.9296) (xy 184.6326 -147.9296) (xy 184.4548 -148.1074) (xy 184.4548 -150.495)
			)
		)
	)
	(zone
		(net "P3V3")
		(layer "F.Cu")
		(hatch none 0.5)
		(connect_pads
			(clearance 0.5)
		)
		(min_thickness 0.25)
		(fill yes
			(thermal_gap 0.5)
			(thermal_bridge_width 0.5)
			(island_removal_mode 0)
		)
		(polygon
			(pts
				(xy 77.089762 -54.966362) (xy 76.944728 -55.111396) (xy 74.417428 -55.111396) (xy 74.341228 -55.187596)
				(xy 74.341228 -57.905396) (xy 74.430128 -57.994296) (xy 76.627228 -57.994296) (xy 77.440028 -57.181496)
				(xy 78.075028 -57.181496) (xy 78.557628 -57.664096) (xy 78.557628 -58.492898) (xy 78.859126 -58.794396)
				(xy 81.072228 -58.794396) (xy 81.173828 -58.692796) (xy 81.173828 -55.974996) (xy 81.123028 -55.924196)
				(xy 78.329028 -55.924196) (xy 78.228698 -55.823866) (xy 78.228698 -55.353966) (xy 78.227428 -55.352696)
				(xy 78.227428 -55.1942) (xy 77.99959 -54.966362)
			)
		)
	)
	(zone
		(net "P3V3_STBY_LL")
		(layer "F.Cu")
		(hatch none 0.5)
		(connect_pads
			(clearance 0.5)
		)
		(min_thickness 0.25)
		(fill yes
			(thermal_gap 0.5)
			(thermal_bridge_width 0.5)
			(island_removal_mode 0)
		)
		(polygon
			(pts
				(xy 36.410646 -181.53761) (xy 36.283646 -181.66461) (xy 36.283646 -186.6646) (xy 36.957 -187.337954)
				(xy 36.957 -188.426852) (xy 37.0459 -188.515752) (xy 40.777668 -188.515752) (xy 41.25722 -188.0362)
				(xy 41.25722 -181.79415) (xy 41.00068 -181.53761)
			)
		)
		(polygon
			(pts
				(xy 37.655246 -188.16701) (xy 37.452046 -188.16701) (xy 37.452046 -188.37021) (xy 37.655246 -188.37021)
			)
		)
		(polygon
			(pts
				(xy 37.655246 -187.55741) (xy 37.452046 -187.55741) (xy 37.452046 -187.76061) (xy 37.655246 -187.76061)
			)
		)
	)
	(zone
		(layer "F.Cu")
		(hatch none 0.5)
		(connect_pads
			(clearance 0)
		)
		(min_thickness 0.25)
		(keepout
			(tracks allowed)
			(vias allowed)
			(pads allowed)
			(copperpour allowed)
			(footprints allowed)
		)
		(placement
			(enabled no)
			(sheetname "")
		)
		(fill
			(thermal_gap 0.5)
			(thermal_bridge_width 0.5)
			(island_removal_mode 0)
		)
		(polygon
			(pts
				(xy 180.9369 -48.5902) (xy 180.9369 -46.355) (xy 181.6481 -46.355) (xy 181.6481 -48.5902)
			)
		)
	)
	(zone
		(net "P12V_STBY")
		(layer "F.Cu")
		(hatch none 0.5)
		(connect_pads
			(clearance 0.5)
		)
		(min_thickness 0.25)
		(fill yes
			(thermal_gap 0.5)
			(thermal_bridge_width 0.5)
			(island_removal_mode 0)
		)
		(polygon
			(pts
				(xy 74.753978 -46.09338) (xy 74.384154 -46.463204) (xy 74.384154 -48.601122) (xy 74.392028 -48.608996)
				(xy 74.392028 -50.77841) (xy 76.635356 -50.77841) (xy 76.635356 -49.825148) (xy 77.278738 -49.181766)
				(xy 78.035658 -49.181766) (xy 78.146148 -49.071276) (xy 78.146148 -48.088296) (xy 77.403452 -47.3456)
				(xy 77.386688 -47.3456) (xy 76.134468 -46.09338)
			)
		)
	)
	(zone
		(net "GND")
		(layer "F.Cu")
		(hatch none 0.5)
		(connect_pads
			(clearance 0.5)
		)
		(min_thickness 0.25)
		(fill yes
			(thermal_gap 0.5)
			(thermal_bridge_width 0.5)
			(island_removal_mode 0)
		)
		(polygon
			(pts
				(xy 163.5506 -129.032) (xy 163.2966 -129.286) (xy 163.2966 -133.604) (xy 163.6395 -133.9469) (xy 168.5925 -133.9469)
				(xy 169.2656 -133.2738) (xy 169.2656 -129.5146) (xy 168.783 -129.032)
			)
		)
		(polygon
			(pts
				(xy 164.3126 -133.2484) (xy 164.1094 -133.2484) (xy 164.1094 -133.4516) (xy 164.3126 -133.4516)
			)
		)
		(polygon
			(pts
				(xy 163.703 -133.2484) (xy 163.4998 -133.2484) (xy 163.4998 -133.4516) (xy 163.703 -133.4516)
			)
		)
	)
	(zone
		(net "RST_BTN_GND")
		(layer "F.Cu")
		(hatch none 0.5)
		(connect_pads
			(clearance 0.5)
		)
		(min_thickness 0.25)
		(fill yes
			(thermal_gap 0.5)
			(thermal_bridge_width 0.5)
			(island_removal_mode 0)
		)
		(polygon
			(pts
				(xy 7.43839 -2.84861) (xy 7.112 -3.175) (xy 7.112 -5.8166) (xy 6.7818 -6.1468) (xy 6.7818 -10.541)
				(xy 7.0866 -10.8458) (xy 8.8392 -10.8458) (xy 9.76884 -9.91616) (xy 9.76884 -8.14578) (xy 8.9281 -7.30504)
				(xy 8.9281 -5.62102) (xy 9.13384 -5.41528) (xy 12.6873 -5.41528) (xy 12.70762 -5.4356) (xy 12.70762 -8.29056)
				(xy 12.02944 -8.96874) (xy 12.02944 -12.70508) (xy 12.13358 -12.80922) (xy 15.70228 -12.80922) (xy 16.73098 -11.78052)
				(xy 16.73098 -3.175) (xy 16.40459 -2.84861)
			)
		)
		(polygon
			(pts
				(xy 15.11554 -12.09294) (xy 14.91234 -12.09294) (xy 14.91234 -12.29614) (xy 15.11554 -12.29614)
			)
		)
		(polygon
			(pts
				(xy 14.55674 -12.09294) (xy 14.35354 -12.09294) (xy 14.35354 -12.29614) (xy 14.55674 -12.29614)
			)
		)
	)
	(zone
		(net "P3V3_STBY")
		(layer "F.Cu")
		(hatch none 0.5)
		(connect_pads
			(clearance 0.5)
		)
		(min_thickness 0.25)
		(fill yes
			(thermal_gap 0.5)
			(thermal_bridge_width 0.5)
			(island_removal_mode 0)
		)
		(polygon
			(pts
				(xy 36.8554 -161.6456) (xy 36.7792 -161.7218) (xy 36.7792 -163.195) (xy 37.6428 -164.0586) (xy 38.3286 -164.0586)
				(xy 38.3794 -164.0078) (xy 38.3794 -163.5506) (xy 38.1254 -163.2966) (xy 38.1254 -162.287458) (xy 38.246812 -162.166046)
				(xy 38.827202 -162.166046) (xy 38.879018 -162.11423) (xy 38.879018 -161.6456)
			)
		)
		(polygon
			(pts
				(xy 37.7444 -163.449) (xy 37.5412 -163.449) (xy 37.5412 -163.6522) (xy 37.7444 -163.6522)
			)
		)
		(polygon
			(pts
				(xy 37.9222 -162.052) (xy 37.719 -162.052) (xy 37.719 -162.2552) (xy 37.9222 -162.2552)
			)
		)
		(polygon
			(pts
				(xy 37.3634 -162.052) (xy 37.1602 -162.052) (xy 37.1602 -162.2552) (xy 37.3634 -162.2552)
			)
		)
	)
	(zone
		(net "GND")
		(layer "F.Cu")
		(hatch none 0.5)
		(connect_pads
			(clearance 0.5)
		)
		(min_thickness 0.25)
		(fill yes
			(thermal_gap 0.5)
			(thermal_bridge_width 0.5)
			(island_removal_mode 0)
		)
		(polygon
			(pts
				(xy 204.1398 -125.336554) (xy 204.1398 -125.984) (xy 203.9747 -126.1491) (xy 202.5142 -126.1491)
				(xy 202.4507 -126.2126) (xy 201.3712 -126.2126) (xy 201.3712 -128.3716) (xy 201.5744 -128.5748)
				(xy 202.2602 -128.5748) (xy 202.3872 -128.4478) (xy 202.3872 -127.9906) (xy 202.6158 -127.762) (xy 204.1652 -127.762)
				(xy 204.1906 -127.7874) (xy 204.1906 -128.6002) (xy 207.4164 -128.6002) (xy 207.4164 -127.8382)
				(xy 207.4672 -127.7874) (xy 213.5378 -127.7874) (xy 213.7918 -127.5334) (xy 213.7918 -125.7046)
				(xy 213.5759 -125.4887) (xy 209.8167 -125.4887) (xy 209.169 -126.1364) (xy 207.4418 -126.1364) (xy 207.4418 -125.3744)
				(xy 207.403954 -125.336554)
			)
		)
		(polygon
			(pts
				(xy 202.2094 -127.508) (xy 202.0062 -127.508) (xy 202.0062 -127.7112) (xy 202.2094 -127.7112)
			)
		)
		(polygon
			(pts
				(xy 210.282536 -127.0762) (xy 210.079336 -127.0762) (xy 210.079336 -127.2794) (xy 210.282536 -127.2794)
			)
		)
		(polygon
			(pts
				(xy 209.672936 -127.0762) (xy 209.469736 -127.0762) (xy 209.469736 -127.2794) (xy 209.672936 -127.2794)
			)
		)
	)
	(zone
		(layer "F.Cu")
		(hatch none 0.5)
		(connect_pads
			(clearance 0)
		)
		(min_thickness 0.25)
		(keepout
			(tracks allowed)
			(vias allowed)
			(pads allowed)
			(copperpour allowed)
			(footprints allowed)
		)
		(placement
			(enabled no)
			(sheetname "")
		)
		(fill
			(thermal_gap 0.5)
			(thermal_bridge_width 0.5)
			(island_removal_mode 0)
		)
		(polygon
			(pts
				(xy 116.830094 -13.062458) (xy 116.830094 -11.208258) (xy 121.0818 -11.208258) (xy 121.0818 -13.062458)
			)
		)
	)
	(zone
		(net "GND")
		(layer "F.Cu")
		(hatch none 0.5)
		(connect_pads
			(clearance 0.5)
		)
		(min_thickness 0.25)
		(fill yes
			(thermal_gap 0.5)
			(thermal_bridge_width 0.5)
			(island_removal_mode 0)
		)
		(polygon
			(pts
				(xy 18.90522 -14.605) (xy 18.17624 -15.33398) (xy 17.20088 -15.33398) (xy 17.12722 -15.40764) (xy 17.12722 -17.20342)
				(xy 17.40408 -17.48028) (xy 20.12696 -17.48028) (xy 20.5486 -17.05864) (xy 20.5486 -14.605)
			)
		)
		(polygon
			(pts
				(xy 20.03298 -15.02664) (xy 19.82978 -15.02664) (xy 19.82978 -15.22984) (xy 20.03298 -15.22984)
			)
		)
	)
	(zone
		(layer "F.Cu")
		(hatch none 0.5)
		(connect_pads
			(clearance 0)
		)
		(min_thickness 0.25)
		(keepout
			(tracks allowed)
			(vias allowed)
			(pads allowed)
			(copperpour allowed)
			(footprints allowed)
		)
		(placement
			(enabled no)
			(sheetname "")
		)
		(fill
			(thermal_gap 0.5)
			(thermal_bridge_width 0.5)
			(island_removal_mode 0)
		)
		(polygon
			(pts
				(xy 91.694 -172.7962) (xy 93.0402 -172.7962) (xy 93.0402 -174.6504) (xy 91.694 -174.6504) (xy 91.3384 -174.6504)
				(xy 91.186 -174.498) (xy 91.186 -173.101) (xy 91.4908 -172.7962)
			)
		)
	)
	(zone
		(layer "F.Cu")
		(hatch none 0.5)
		(connect_pads
			(clearance 0)
		)
		(min_thickness 0.25)
		(keepout
			(tracks not_allowed)
			(vias allowed)
			(pads allowed)
			(copperpour not_allowed)
			(footprints allowed)
		)
		(placement
			(enabled no)
			(sheetname "")
		)
		(fill
			(thermal_gap 0.5)
			(thermal_bridge_width 0.5)
			(island_removal_mode 0)
		)
		(polygon
			(pts
				(arc
					(start 78.505558 -89.710768)
					(mid 78.122018 -89.327228)
					(end 77.738478 -89.710768)
				)
				(xy 77.738478 -89.911936) (xy 77.83068 -89.911936)
				(arc
					(start 77.835252 -89.911682)
					(mid 77.881305 -89.90634)
					(end 77.924914 -89.8906)
				)
				(arc
					(start 77.924914 -89.8906)
					(mid 78.240729 -89.472154)
					(end 78.096618 -89.976198)
				)
				(arc
					(start 78.096618 -89.976198)
					(mid 77.993621 -90.048071)
					(end 77.87259 -90.081608)
				)
				(xy 77.870812 -90.083132) (xy 77.844904 -90.083132) (xy 77.835252 -90.083386) (xy 77.83068 -90.083132)
				(xy 77.738478 -90.083132) (xy 77.738478 -90.222832) (xy 77.826362 -90.222832) (xy 77.830934 -90.222832)
				(xy 77.84084 -90.222832) (xy 77.866494 -90.222832)
				(arc
					(start 77.868272 -90.22461)
					(mid 77.99287 -90.259306)
					(end 78.098396 -90.334084)
				)
				(arc
					(start 78.098396 -90.334084)
					(mid 78.23929 -90.839337)
					(end 77.926692 -90.418158)
				)
				(arc
					(start 77.926692 -90.418158)
					(mid 77.880251 -90.400529)
					(end 77.830934 -90.394536)
				)
				(xy 77.826362 -90.394536) (xy 77.738478 -90.394536)
				(arc
					(start 77.738478 -90.599514)
					(mid 78.121891 -90.983308)
					(end 78.505558 -90.599768)
				)
			)
		)
	)
	(zone
		(layer "F.Cu")
		(hatch none 0.5)
		(connect_pads
			(clearance 0)
		)
		(min_thickness 0.25)
		(keepout
			(tracks allowed)
			(vias allowed)
			(pads allowed)
			(copperpour allowed)
			(footprints allowed)
		)
		(placement
			(enabled no)
			(sheetname "")
		)
		(fill
			(thermal_gap 0.5)
			(thermal_bridge_width 0.5)
			(island_removal_mode 0)
		)
		(polygon
			(pts
				(xy 68.2498 -139.192) (xy 70.104 -139.192) (xy 70.104 -139.9794) (xy 68.2498 -139.9794)
			)
		)
	)
	(zone
		(net "GND")
		(layer "F.Cu")
		(hatch none 0.5)
		(connect_pads
			(clearance 0.5)
		)
		(min_thickness 0.25)
		(fill yes
			(thermal_gap 0.5)
			(thermal_bridge_width 0.5)
			(island_removal_mode 0)
		)
		(polygon
			(pts
				(xy 175.26 -145.015966) (xy 175.1584 -145.117566) (xy 175.1584 -145.3896) (xy 175.133 -145.415)
				(xy 174.879 -145.415) (xy 174.8536 -145.4404) (xy 174.8536 -145.542) (xy 174.2694 -146.1262) (xy 173.1264 -146.1262)
				(xy 172.974 -146.2786) (xy 172.974 -147.9804) (xy 173.3042 -148.3106) (xy 173.7868 -148.3106) (xy 173.792896 -148.304504)
				(xy 174.783496 -148.304504) (xy 174.796704 -148.317966) (xy 181.908704 -148.317966) (xy 182.416704 -147.809966)
				(xy 182.416704 -145.523966) (xy 181.908704 -145.015966)
			)
		)
	)
	(zone
		(net "AGND_P5V")
		(layer "F.Cu")
		(hatch none 0.5)
		(connect_pads
			(clearance 0.5)
		)
		(min_thickness 0.25)
		(fill yes
			(thermal_gap 0.5)
			(thermal_bridge_width 0.5)
			(island_removal_mode 0)
		)
		(polygon
			(pts
				(xy 183.710834 -140.697966) (xy 183.515 -140.8938) (xy 183.515 -143.8148) (xy 183.3372 -143.9926)
				(xy 183.2356 -143.9926) (xy 183.0832 -144.145) (xy 183.0832 -144.8308) (xy 183.1594 -144.907) (xy 183.178704 -144.907)
				(xy 183.178704 -147.555966) (xy 183.305704 -147.682966) (xy 185.591704 -147.682966) (xy 185.718704 -147.555966)
				(xy 185.718704 -140.824966) (xy 185.591704 -140.697966)
			)
		)
		(polygon
			(pts
				(xy 185.293 -147.0025) (xy 185.0898 -147.0025) (xy 185.0898 -147.2057) (xy 185.293 -147.2057)
			)
		)
		(polygon
			(pts
				(xy 184.7342 -147.0025) (xy 184.531 -147.0025) (xy 184.531 -147.2057) (xy 184.7342 -147.2057)
			)
		)
		(polygon
			(pts
				(xy 183.769 -144.7292) (xy 183.5658 -144.7292) (xy 183.5658 -144.9324) (xy 183.769 -144.9324)
			)
		)
		(polygon
			(pts
				(xy 183.769 -144.1704) (xy 183.5658 -144.1704) (xy 183.5658 -144.3736) (xy 183.769 -144.3736)
			)
		)
		(polygon
			(pts
				(xy 184.1754 -143.5862) (xy 183.9722 -143.5862) (xy 183.9722 -143.7894) (xy 184.1754 -143.7894)
			)
		)
		(polygon
			(pts
				(xy 184.1754 -143.0274) (xy 183.9722 -143.0274) (xy 183.9722 -143.2306) (xy 184.1754 -143.2306)
			)
		)
		(polygon
			(pts
				(xy 184.1754 -142.5702) (xy 183.9722 -142.5702) (xy 183.9722 -142.7734) (xy 184.1754 -142.7734)
			)
		)
		(polygon
			(pts
				(xy 184.1754 -142.0114) (xy 183.9722 -142.0114) (xy 183.9722 -142.2146) (xy 184.1754 -142.2146)
			)
		)
	)
	(zone
		(net "MB0_P12V_MAIN_R")
		(layer "F.Cu")
		(hatch none 0.5)
		(connect_pads
			(clearance 0.5)
		)
		(min_thickness 0.25)
		(fill yes
			(thermal_gap 0.5)
			(thermal_bridge_width 0.5)
			(island_removal_mode 0)
		)
		(polygon
			(pts
				(xy 135.503666 -5.632196) (xy 135.503666 -10.68705) (xy 135.553196 -10.73658) (xy 136.27354 -10.73658)
				(xy 136.632696 -11.095736) (xy 136.632696 -12.396724) (xy 136.626854 -12.402566) (xy 136.626854 -12.846558)
				(xy 136.682988 -12.902692) (xy 140.558012 -12.902692) (xy 141.226032 -12.234672) (xy 141.226032 -5.713476)
				(xy 141.144752 -5.632196)
			)
		)
	)
	(zone
		(layer "F.Cu")
		(hatch none 0.5)
		(connect_pads
			(clearance 0)
		)
		(min_thickness 0.25)
		(keepout
			(tracks allowed)
			(vias allowed)
			(pads allowed)
			(copperpour allowed)
			(footprints allowed)
		)
		(placement
			(enabled no)
			(sheetname "")
		)
		(fill
			(thermal_gap 0.5)
			(thermal_bridge_width 0.5)
			(island_removal_mode 0)
		)
		(polygon
			(pts
				(xy 74.067416 -96.962468) (xy 74.067416 -66.2178) (xy 81.528666 -66.2178) (xy 81.528666 -96.962468)
			)
		)
	)
	(zone
		(layer "F.Cu")
		(hatch none 0.5)
		(connect_pads
			(clearance 0)
		)
		(min_thickness 0.25)
		(keepout
			(tracks not_allowed)
			(vias allowed)
			(pads allowed)
			(copperpour not_allowed)
			(footprints allowed)
		)
		(placement
			(enabled no)
			(sheetname "")
		)
		(fill
			(thermal_gap 0.5)
			(thermal_bridge_width 0.5)
			(island_removal_mode 0)
		)
		(polygon
			(pts
				(arc
					(start 216.192354 -73.652126)
					(mid 216.192354 -73.113646)
					(end 215.653874 -73.113646)
				)
				(xy 215.65362 -73.113392) (xy 215.44661 -73.320402)
				(arc
					(start 215.589104 -73.462896)
					(mid 215.630894 -73.48856)
					(end 215.679782 -73.49236)
				)
				(arc
					(start 215.679782 -73.49236)
					(mid 216.121861 -73.205077)
					(end 215.786208 -73.61174)
				)
				(arc
					(start 215.786208 -73.61174)
					(mid 215.644031 -73.642825)
					(end 215.508078 -73.590912)
				)
				(xy 215.50503 -73.590912) (xy 215.340438 -73.426574) (xy 215.260174 -73.506838) (xy 215.159082 -73.60793)
				(xy 215.323674 -73.772522)
				(arc
					(start 215.323674 -73.77557)
					(mid 215.375644 -73.91198)
					(end 215.343994 -74.054462)
				)
				(arc
					(start 215.343994 -74.054462)
					(mid 214.937198 -74.39009)
					(end 215.224868 -73.948036)
				)
				(arc
					(start 215.224868 -73.948036)
					(mid 215.221402 -73.898757)
					(end 215.195658 -73.856596)
				)
				(xy 215.053164 -73.713848) (xy 214.845392 -73.92162)
				(arc
					(start 214.845646 -73.921874)
					(mid 214.845646 -74.460354)
					(end 215.384126 -74.460354)
				)
				(xy 215.38438 -74.460608) (xy 216.192354 -73.65238)
			)
		)
	)
	(zone
		(layer "F.Cu")
		(hatch none 0.5)
		(connect_pads
			(clearance 0)
		)
		(min_thickness 0.25)
		(keepout
			(tracks not_allowed)
			(vias allowed)
			(pads allowed)
			(copperpour not_allowed)
			(footprints allowed)
		)
		(placement
			(enabled no)
			(sheetname "")
		)
		(fill
			(thermal_gap 0.5)
			(thermal_bridge_width 0.5)
			(island_removal_mode 0)
		)
		(polygon
			(pts
				(arc
					(start 207.941672 -65.9384)
					(mid 207.960368 -65.960802)
					(end 207.967072 -65.9892)
				)
				(arc
					(start 207.967072 -66.1924)
					(mid 207.960368 -66.220798)
					(end 207.941672 -66.2432)
				)
				(arc
					(start 208.170272 -66.2432)
					(mid 208.151576 -66.220798)
					(end 208.144872 -66.1924)
				)
				(arc
					(start 208.144872 -65.9892)
					(mid 208.151576 -65.960802)
					(end 208.170272 -65.9384)
				)
			)
		)
	)
	(zone
		(layer "F.Cu")
		(hatch none 0.5)
		(connect_pads
			(clearance 0)
		)
		(min_thickness 0.25)
		(keepout
			(tracks not_allowed)
			(vias allowed)
			(pads allowed)
			(copperpour not_allowed)
			(footprints allowed)
		)
		(placement
			(enabled no)
			(sheetname "")
		)
		(fill
			(thermal_gap 0.5)
			(thermal_bridge_width 0.5)
			(island_removal_mode 0)
		)
		(polygon
			(pts
				(arc
					(start 207.941672 -74.8792)
					(mid 207.960368 -74.901602)
					(end 207.967072 -74.93)
				)
				(arc
					(start 207.967072 -75.1332)
					(mid 207.960368 -75.161598)
					(end 207.941672 -75.184)
				)
				(arc
					(start 208.170272 -75.184)
					(mid 208.151576 -75.161598)
					(end 208.144872 -75.1332)
				)
				(arc
					(start 208.144872 -74.93)
					(mid 208.151576 -74.901602)
					(end 208.170272 -74.8792)
				)
			)
		)
	)
	(zone
		(layer "F.Cu")
		(hatch none 0.5)
		(connect_pads
			(clearance 0)
		)
		(min_thickness 0.25)
		(keepout
			(tracks allowed)
			(vias allowed)
			(pads allowed)
			(copperpour allowed)
			(footprints not_allowed)
		)
		(placement
			(enabled no)
			(sheetname "")
		)
		(fill
			(thermal_gap 0.5)
			(thermal_bridge_width 0.5)
			(island_removal_mode 0)
		)
		(polygon
			(pts
				(xy 4.99999 0)
				(arc
					(start 29.53004 0)
					(mid 30.237145 -0.292893)
					(end 30.530038 -0.999998)
				)
				(xy 30.530038 -31.999936) (xy 29.500068 -31.999936) (xy 5.500116 -31.999936) (xy 5.500116 -43.999912)
				(xy 29.500068 -43.999912) (xy 29.500068 -32.100012) (xy 30.530038 -32.100012) (xy 30.530038 -48.600106)
				(xy 6.700012 -48.600106) (xy 6.700012 -55.79999) (xy 8.64997 -55.79999) (xy 8.64997 -65.300098)
				(xy 6.700012 -65.300098) (xy 6.700012 -103.799894) (xy 11.8999 -103.799894) (xy 11.8999 -109.799882)
				(xy 6.700012 -109.799882) (xy 6.700012 -113.050066) (xy 85.700108 -113.050066) (xy 85.700108 -109.799882)
				(xy 92.700094 -109.799882) (xy 92.700094 -100.300028) (xy 85.700108 -100.300028) (xy 85.700108 -44.800012)
				(xy 89.499948 -44.800012) (xy 89.499948 -35.299904) (xy 85.700108 -35.299904) (xy 85.700108 -29.200094)
				(xy 82.300064 -29.200094) (xy 82.300064 0) (xy 230.000048 0)
				(arc
					(start 230.000048 -193.786252)
					(mid 229.70903 -193.945107)
					(end 229.382066 -194.00012)
				)
				(arc
					(start 149.917912 -194.00012)
					(mid 149.392231 -193.850645)
					(end 149.023578 -193.447162)
				)
				(arc
					(start 144.405604 -184.211214)
					(mid 144.326748 -183.993717)
					(end 144.29994 -183.76392)
				)
				(arc
					(start 144.29994 -47.999904)
					(mid 143.800068 -47.500032)
					(end 143.299942 -47.999904)
				)
				(arc
					(start 104.70007 -47.999904)
					(mid 104.200198 -47.500032)
					(end 103.700072 -47.999904)
				)
				(xy 103.700072 -129.420112) (xy 73.429876 -129.420112) (xy 73.429876 -113.199926) (xy 24.5999 -113.199926)
				(xy 24.5999 -129.519934) (xy 73.429876 -129.519934) (xy 103.700072 -129.519934)
				(arc
					(start 103.700072 -183.76392)
					(mid 103.673308 -183.993728)
					(end 103.594408 -184.211214)
				)
				(arc
					(start 98.976434 -193.447162)
					(mid 98.607709 -193.850769)
					(end 98.081846 -194.00012)
				)
				(arc
					(start 5.617972 -194.00012)
					(mid 5.290993 -193.945151)
					(end 4.99999 -193.786252)
				)
			)
		)
	)
	(zone
		(layer "F.Cu")
		(hatch none 0.5)
		(connect_pads
			(clearance 0)
		)
		(min_thickness 0.25)
		(keepout
			(tracks not_allowed)
			(vias allowed)
			(pads allowed)
			(copperpour not_allowed)
			(footprints allowed)
		)
		(placement
			(enabled no)
			(sheetname "")
		)
		(fill
			(thermal_gap 0.5)
			(thermal_bridge_width 0.5)
			(island_removal_mode 0)
		)
		(polygon
			(pts
				(arc
					(start 160.250124 -110.000034)
					(mid 155.50007 -114.750088)
					(end 150.750016 -110.000034)
				)
				(arc
					(start 150.750016 -110.000034)
					(mid 155.50007 -105.24998)
					(end 160.250124 -110.000034)
				)
			)
		)
	)
	(zone
		(layer "F.Cu")
		(hatch none 0.5)
		(connect_pads
			(clearance 0)
		)
		(min_thickness 0.25)
		(keepout
			(tracks not_allowed)
			(vias allowed)
			(pads allowed)
			(copperpour not_allowed)
			(footprints allowed)
		)
		(placement
			(enabled no)
			(sheetname "")
		)
		(fill
			(thermal_gap 0.5)
			(thermal_bridge_width 0.5)
			(island_removal_mode 0)
		)
		(polygon
			(pts
				(arc
					(start 22.750018 -24.99995)
					(mid 17.999964 -29.750004)
					(end 13.24991 -24.99995)
				)
				(arc
					(start 13.24991 -24.99995)
					(mid 17.999964 -20.249896)
					(end 22.750018 -24.99995)
				)
			)
		)
	)
	(zone
		(layer "F.Cu")
		(hatch none 0.5)
		(connect_pads
			(clearance 0)
		)
		(min_thickness 0.25)
		(keepout
			(tracks not_allowed)
			(vias allowed)
			(pads allowed)
			(copperpour not_allowed)
			(footprints allowed)
		)
		(placement
			(enabled no)
			(sheetname "")
		)
		(fill
			(thermal_gap 0.5)
			(thermal_bridge_width 0.5)
			(island_removal_mode 0)
		)
		(polygon
			(pts
				(arc
					(start 207.941672 -67.6148)
					(mid 207.960368 -67.637202)
					(end 207.967072 -67.6656)
				)
				(arc
					(start 207.967072 -67.8688)
					(mid 207.960368 -67.897198)
					(end 207.941672 -67.9196)
				)
				(arc
					(start 208.170272 -67.9196)
					(mid 208.151576 -67.897198)
					(end 208.144872 -67.8688)
				)
				(arc
					(start 208.144872 -67.6656)
					(mid 208.151576 -67.637202)
					(end 208.170272 -67.6148)
				)
			)
		)
	)
	(zone
		(net "P12V_IOM")
		(layer "F.Cu")
		(hatch none 0.5)
		(connect_pads
			(clearance 0.5)
		)
		(min_thickness 0.25)
		(fill yes
			(thermal_gap 0.5)
			(thermal_bridge_width 0.5)
			(island_removal_mode 0)
		)
		(polygon
			(pts
				(xy 136.760458 -13.202158) (xy 136.612122 -13.350494) (xy 136.612122 -14.79169) (xy 136.501886 -14.901926)
				(xy 134.979664 -14.901926) (xy 134.314438 -15.567152) (xy 129.96291 -15.567152) (xy 129.21488 -16.315182)
				(xy 129.21488 -17.402556) (xy 127.34417 -19.273266) (xy 127.34417 -20.25523) (xy 127.72771 -20.63877)
				(xy 129.28219 -20.63877) (xy 130.220212 -19.700748) (xy 130.220212 -19.007328) (xy 130.6957 -18.53184)
				(xy 134.2136 -18.53184) (xy 135.11784 -17.6276) (xy 137.57275 -17.6276) (xy 137.991596 -17.209008)
				(xy 137.991596 -16.432784) (xy 139.03452 -15.38986) (xy 139.03452 -13.301218) (xy 138.93546 -13.202158)
			)
		)
		(polygon
			(pts
				(xy 137.1219 -16.99006) (xy 136.9187 -16.99006) (xy 136.9187 -17.19326) (xy 137.1219 -17.19326)
			)
		)
		(polygon
			(pts
				(xy 136.5123 -16.99006) (xy 136.3091 -16.99006) (xy 136.3091 -17.19326) (xy 136.5123 -17.19326)
			)
		)
		(polygon
			(pts
				(xy 136.15416 -16.63954) (xy 135.95096 -16.63954) (xy 135.95096 -16.84274) (xy 136.15416 -16.84274)
			)
		)
		(polygon
			(pts
				(xy 135.29056 -16.63954) (xy 135.08736 -16.63954) (xy 135.08736 -16.84274) (xy 135.29056 -16.84274)
			)
		)
	)
	(zone
		(net "GND")
		(layer "F.Cu")
		(hatch none 0.5)
		(connect_pads
			(clearance 0.5)
		)
		(min_thickness 0.25)
		(fill yes
			(thermal_gap 0.5)
			(thermal_bridge_width 0.5)
			(island_removal_mode 0)
		)
		(polygon
			(pts
				(arc
					(start 0.999998 -0.763016)
					(mid 0.832426 -0.832426)
					(end 0.763016 -0.999998)
				)
				(arc
					(start 0.763016 -183.76392)
					(mid 0.769411 -183.818347)
					(end 0.788162 -183.869838)
				)
				(arc
					(start 5.406136 -193.10604)
					(mid 5.493436 -193.201687)
					(end 5.617972 -193.237104)
				)
				(arc
					(start 98.0821 -193.237104)
					(mid 98.206591 -193.201614)
					(end 98.293936 -193.10604)
				)
				(arc
					(start 102.91191 -183.869838)
					(mid 102.930633 -183.818341)
					(end 102.937056 -183.76392)
				)
				(xy 102.937056 -183.403748) (xy 100.874322 -183.403748) (xy 96.97339 -191.20612) (xy 6.726682 -191.20612)
				(xy 2.82575 -183.403748) (xy 2.767584 -183.403748) (xy 2.7305 -183.366664) (xy 2.7305 -183.313832)
				(xy 2.767584 -183.276748) (xy 2.794 -183.276748) (xy 2.794 -2.794) (xy 6.474968 -2.794) (xy 6.474968 -0.763016)
			)
		)
	)
	(zone
		(layer "F.Cu")
		(hatch none 0.5)
		(connect_pads
			(clearance 0)
		)
		(min_thickness 0.25)
		(keepout
			(tracks allowed)
			(vias allowed)
			(pads allowed)
			(copperpour allowed)
			(footprints allowed)
		)
		(placement
			(enabled no)
			(sheetname "")
		)
		(fill
			(thermal_gap 0.5)
			(thermal_bridge_width 0.5)
			(island_removal_mode 0)
		)
		(polygon
			(pts
				(xy 155.4734 -92.5068) (xy 155.4734 -90.2716) (xy 157.0736 -90.2716) (xy 157.0736 -92.5068)
			)
		)
	)
	(zone
		(layer "F.Cu")
		(hatch none 0.5)
		(connect_pads
			(clearance 0)
		)
		(min_thickness 0.25)
		(keepout
			(tracks allowed)
			(vias allowed)
			(pads allowed)
			(copperpour allowed)
			(footprints allowed)
		)
		(placement
			(enabled no)
			(sheetname "")
		)
		(fill
			(thermal_gap 0.5)
			(thermal_bridge_width 0.5)
			(island_removal_mode 0)
		)
		(polygon
			(pts
				(xy 90.2716 -154.94) (xy 90.2716 -156.2862) (xy 90.2716 -157.5816) (xy 90.0684 -157.7848) (xy 88.392 -157.7848)
				(xy 88.3793 -157.7721) (xy 87.6681 -157.7721) (xy 87.4014 -157.5054) (xy 87.4014 -155.1432) (xy 87.4014 -154.2034)
				(xy 87.4776 -154.1272) (xy 88.4174 -154.1272) (xy 88.4174 -153.924) (xy 88.9508 -153.3906) (xy 90.3224 -153.3906)
				(xy 90.3732 -153.4414) (xy 90.3732 -154.2542) (xy 90.2716 -154.3558)
			)
		)
	)
	(zone
		(layer "F.Cu")
		(hatch none 0.5)
		(connect_pads
			(clearance 0)
		)
		(min_thickness 0.25)
		(keepout
			(tracks not_allowed)
			(vias allowed)
			(pads allowed)
			(copperpour not_allowed)
			(footprints allowed)
		)
		(placement
			(enabled no)
			(sheetname "")
		)
		(fill
			(thermal_gap 0.5)
			(thermal_bridge_width 0.5)
			(island_removal_mode 0)
		)
		(polygon
			(pts
				(arc
					(start 85.367368 -91.306396)
					(mid 84.983828 -90.922856)
					(end 84.600288 -91.306396)
				)
				(xy 84.600288 -91.50858) (xy 84.699856 -91.50858)
				(arc
					(start 84.704428 -91.50858)
					(mid 84.747959 -91.503628)
					(end 84.789264 -91.489022)
				)
				(arc
					(start 84.789264 -91.489022)
					(mid 85.098451 -91.065747)
					(end 84.963762 -91.572334)
				)
				(arc
					(start 84.963762 -91.572334)
					(mid 84.861956 -91.644565)
					(end 84.741766 -91.678252)
				)
				(xy 84.739988 -91.680284) (xy 84.71408 -91.680284) (xy 84.704428 -91.680284) (xy 84.699856 -91.680284)
				(xy 84.600288 -91.680284) (xy 84.600288 -91.819984) (xy 84.699856 -91.819984) (xy 84.704428 -91.81973)
				(xy 84.71408 -91.819984) (xy 84.739988 -91.819984)
				(arc
					(start 84.741766 -91.821762)
					(mid 84.862947 -91.856052)
					(end 84.965286 -91.929458)
				)
				(arc
					(start 84.965286 -91.929458)
					(mid 85.09745 -92.436553)
					(end 84.790534 -92.011754)
				)
				(arc
					(start 84.790534 -92.011754)
					(mid 84.748658 -91.996602)
					(end 84.704428 -91.991434)
				)
				(xy 84.699856 -91.99118) (xy 84.600288 -91.99118)
				(arc
					(start 84.600288 -92.195142)
					(mid 84.983701 -92.578936)
					(end 85.367368 -92.195396)
				)
			)
		)
	)
	(zone
		(layer "F.Cu")
		(hatch none 0.5)
		(connect_pads
			(clearance 0)
		)
		(min_thickness 0.25)
		(keepout
			(tracks not_allowed)
			(vias allowed)
			(pads allowed)
			(copperpour not_allowed)
			(footprints allowed)
		)
		(placement
			(enabled no)
			(sheetname "")
		)
		(fill
			(thermal_gap 0.5)
			(thermal_bridge_width 0.5)
			(island_removal_mode 0)
		)
		(polygon
			(pts
				(arc
					(start 190.448692 -84.156296)
					(mid 190.448692 -83.617308)
					(end 189.909704 -83.617308)
				)
				(xy 189.766194 -83.760818) (xy 189.879986 -83.87461)
				(arc
					(start 189.883288 -83.877912)
					(mid 189.897237 -83.890003)
					(end 189.912752 -83.90001)
				)
				(arc
					(start 189.912752 -83.90001)
					(mid 190.41971 -83.771381)
					(end 190.00216 -84.086446)
				)
				(arc
					(start 190.00216 -84.086446)
					(mid 189.890329 -84.075445)
					(end 189.790324 -84.024216)
				)
				(xy 189.787022 -84.024216) (xy 189.768226 -84.00542) (xy 189.761876 -83.999324) (xy 189.758574 -83.996022)
				(xy 189.645036 -83.88223) (xy 189.545976 -83.981036) (xy 189.659768 -84.094574) (xy 189.66307 -84.097876)
				(xy 189.669166 -84.104226) (xy 189.687962 -84.123022)
				(arc
					(start 189.687962 -84.126324)
					(mid 189.73915 -84.226341)
					(end 189.750192 -84.33816)
				)
				(arc
					(start 189.750192 -84.33816)
					(mid 189.435101 -84.755764)
					(end 189.563756 -84.248752)
				)
				(arc
					(start 189.563756 -84.248752)
					(mid 189.553743 -84.233244)
					(end 189.541658 -84.219288)
				)
				(xy 189.538356 -84.215986) (xy 189.424818 -84.102448)
				(arc
					(start 189.286134 -84.241132)
					(mid 189.279055 -84.782246)
					(end 189.820296 -84.784692)
				)
			)
		)
	)
	(zone
		(layer "F.Cu")
		(hatch none 0.5)
		(connect_pads
			(clearance 0)
		)
		(min_thickness 0.25)
		(keepout
			(tracks not_allowed)
			(vias allowed)
			(pads allowed)
			(copperpour not_allowed)
			(footprints allowed)
		)
		(placement
			(enabled no)
			(sheetname "")
		)
		(fill
			(thermal_gap 0.5)
			(thermal_bridge_width 0.5)
			(island_removal_mode 0)
		)
		(polygon
			(pts
				(arc
					(start 75.25004 -120.000014)
					(mid 80.000094 -115.24996)
					(end 84.749894 -120.000014)
				)
				(arc
					(start 84.749894 -120.000014)
					(mid 80.000094 -124.749814)
					(end 75.25004 -120.000014)
				)
			)
		)
	)
	(zone
		(layer "F.Cu")
		(hatch none 0.5)
		(connect_pads
			(clearance 0)
		)
		(min_thickness 0.25)
		(keepout
			(tracks allowed)
			(vias allowed)
			(pads allowed)
			(copperpour allowed)
			(footprints allowed)
		)
		(placement
			(enabled no)
			(sheetname "")
		)
		(fill
			(thermal_gap 0.5)
			(thermal_bridge_width 0.5)
			(island_removal_mode 0)
		)
		(polygon
			(pts
				(xy 178.308 -144.526) (xy 178.308 -142.6464) (xy 180.3908 -142.6464) (xy 180.3908 -144.526)
			)
		)
	)
	(zone
		(net "P12V_STBY")
		(layer "F.Cu")
		(hatch none 0.5)
		(connect_pads
			(clearance 0.5)
		)
		(min_thickness 0.25)
		(fill yes
			(thermal_gap 0.5)
			(thermal_bridge_width 0.5)
			(island_removal_mode 0)
		)
		(polygon
			(pts
				(xy 166.7002 -138.7348) (xy 166.285164 -139.149836) (xy 166.285164 -142.729458) (xy 166.445946 -142.89024)
				(xy 168.681146 -142.89024) (xy 168.815766 -142.75562) (xy 168.815766 -139.081256) (xy 168.46931 -138.7348)
			)
		)
	)
	(zone
		(layer "F.Cu")
		(hatch none 0.5)
		(connect_pads
			(clearance 0)
		)
		(min_thickness 0.25)
		(keepout
			(tracks allowed)
			(vias allowed)
			(pads allowed)
			(copperpour allowed)
			(footprints not_allowed)
		)
		(placement
			(enabled no)
			(sheetname "")
		)
		(fill
			(thermal_gap 0.5)
			(thermal_bridge_width 0.5)
			(island_removal_mode 0)
		)
		(polygon
			(pts
				(arc
					(start 150.750016 -187.999878)
					(mid 155.50007 -183.249824)
					(end 160.250124 -187.999878)
				)
				(arc
					(start 160.250124 -187.999878)
					(mid 155.50007 -192.749932)
					(end 150.750016 -187.999878)
				)
			)
		)
	)
	(zone
		(net "P5V_STBY")
		(layer "F.Cu")
		(hatch none 0.5)
		(connect_pads
			(clearance 0.5)
		)
		(min_thickness 0.25)
		(fill yes
			(thermal_gap 0.5)
			(thermal_bridge_width 0.5)
			(island_removal_mode 0)
		)
		(polygon
			(pts
				(xy 150.060152 -6.912102) (xy 148.6154 -8.356854) (xy 148.6154 -22.831044) (xy 144.2212 -27.225244)
				(xy 144.2212 -44.934632) (xy 145.725896 -46.439328) (xy 145.725896 -93.735906) (xy 146.260058 -94.270068)
				(xy 149.596856 -94.270068) (xy 150.759668 -93.107256) (xy 150.759668 -41.412668) (xy 148.463 -39.116)
				(xy 148.463 -36.3982) (xy 148.8059 -36.0553) (xy 148.8059 -29.066236) (xy 153.096976 -24.77516)
				(xy 153.096976 -7.227824) (xy 152.781 -6.912102)
			)
		)
	)
	(zone
		(net "P1V8_STBY")
		(layer "F.Cu")
		(hatch none 0.5)
		(connect_pads
			(clearance 0.5)
		)
		(min_thickness 0.25)
		(fill yes
			(thermal_gap 0.5)
			(thermal_bridge_width 0.5)
			(island_removal_mode 0)
		)
		(polygon
			(pts
				(xy 207.7466 -128.0922) (xy 207.6196 -128.2192) (xy 207.6196 -128.6383) (xy 207.3402 -128.9177)
				(xy 205.613 -128.9177) (xy 205.613 -132.5626) (xy 205.8162 -132.7658) (xy 211.5312 -132.7658) (xy 211.836 -132.461)
				(xy 211.836 -129.7432) (xy 210.185 -128.0922)
			)
		)
		(polygon
			(pts
				(xy 210.282536 -128.6002) (xy 210.079336 -128.6002) (xy 210.079336 -128.8034) (xy 210.282536 -128.8034)
			)
		)
		(polygon
			(pts
				(xy 209.672936 -128.6002) (xy 209.469736 -128.6002) (xy 209.469736 -128.8034) (xy 209.672936 -128.8034)
			)
		)
	)
	(zone
		(net "P3V3")
		(layer "F.Cu")
		(hatch none 0.5)
		(connect_pads
			(clearance 0.5)
		)
		(min_thickness 0.25)
		(fill yes
			(thermal_gap 0.5)
			(thermal_bridge_width 0.5)
			(island_removal_mode 0)
		)
		(polygon
			(pts
				(xy 85.314028 -47.592996) (xy 84.171028 -48.735996) (xy 84.171028 -52.418996) (xy 84.450428 -52.698396)
				(xy 88.717628 -52.698396) (xy 89.759028 -51.656996) (xy 89.759028 -49.959768) (xy 90.361008 -49.357788)
				(xy 90.361008 -48.571404) (xy 90.2589 -48.469296) (xy 89.543128 -48.469296) (xy 89.4334 -48.579024)
				(xy 89.4334 -49.421796) (xy 88.91397 -49.941226) (xy 87.580978 -49.941226) (xy 87.193628 -49.553876)
				(xy 87.193628 -47.664624) (xy 87.122 -47.592996)
			)
		)
		(polygon
			(pts
				(xy 86.748366 -49.372012) (xy 86.545166 -49.372012) (xy 86.545166 -49.575212) (xy 86.748366 -49.575212)
			)
		)
		(polygon
			(pts
				(xy 86.748366 -48.813212) (xy 86.545166 -48.813212) (xy 86.545166 -49.016412) (xy 86.748366 -49.016412)
			)
		)
		(polygon
			(pts
				(xy 86.6902 -48.431196) (xy 86.487 -48.431196) (xy 86.487 -48.634396) (xy 86.6902 -48.634396)
			)
		)
		(polygon
			(pts
				(xy 86.6902 -47.821596) (xy 86.487 -47.821596) (xy 86.487 -48.024796) (xy 86.6902 -48.024796)
			)
		)
	)
	(zone
		(layer "F.Cu")
		(hatch none 0.5)
		(connect_pads
			(clearance 0)
		)
		(min_thickness 0.25)
		(keepout
			(tracks allowed)
			(vias allowed)
			(pads allowed)
			(copperpour allowed)
			(footprints allowed)
		)
		(placement
			(enabled no)
			(sheetname "")
		)
		(fill
			(thermal_gap 0.5)
			(thermal_bridge_width 0.5)
			(island_removal_mode 0)
		)
		(polygon
			(pts
				(xy 95.4024 -154.94) (xy 97.2566 -154.94) (xy 97.2566 -156.2862) (xy 95.4024 -156.2862)
			)
		)
	)
	(zone
		(layer "F.Cu")
		(hatch none 0.5)
		(connect_pads
			(clearance 0)
		)
		(min_thickness 0.25)
		(keepout
			(tracks allowed)
			(vias allowed)
			(pads allowed)
			(copperpour allowed)
			(footprints allowed)
		)
		(placement
			(enabled no)
			(sheetname "")
		)
		(fill
			(thermal_gap 0.5)
			(thermal_bridge_width 0.5)
			(island_removal_mode 0)
		)
		(polygon
			(pts
				(xy 186.0042 -123.5202) (xy 187.2234 -123.5202) (xy 187.579 -123.1646) (xy 187.579 -122.428) (xy 189.484 -122.428)
				(xy 190.5508 -123.4948) (xy 191.4398 -123.4948) (xy 191.5033 -123.4313) (xy 193.3067 -123.4313)
				(xy 193.421 -123.317) (xy 193.802 -122.936) (xy 193.802 -121.4882) (xy 193.4464 -121.1326) (xy 193.294 -120.9802)
				(xy 191.7446 -120.9802) (xy 191.5668 -120.8024) (xy 191.5668 -119.888) (xy 185.8518 -119.888) (xy 185.7756 -119.9642)
				(xy 185.7756 -121.9962) (xy 185.3946 -122.3772) (xy 183.1848 -122.3772) (xy 182.372 -123.19) (xy 182.372 -124.206)
				(xy 182.3974 -124.2314) (xy 184.5056 -124.2314) (xy 185.4454 -123.2916) (xy 185.7756 -123.2916)
			)
		)
	)
	(zone
		(layer "F.Cu")
		(hatch none 0.5)
		(connect_pads
			(clearance 0)
		)
		(min_thickness 0.25)
		(keepout
			(tracks allowed)
			(vias allowed)
			(pads allowed)
			(copperpour allowed)
			(footprints allowed)
		)
		(placement
			(enabled no)
			(sheetname "")
		)
		(fill
			(thermal_gap 0.5)
			(thermal_bridge_width 0.5)
			(island_removal_mode 0)
		)
		(polygon
			(pts
				(xy 93.5228 -124.333) (xy 94.6658 -124.333) (xy 94.7674 -124.2314) (xy 94.7674 -123.0376) (xy 94.488 -122.7582)
				(xy 93.7514 -122.7582) (xy 93.472 -123.0376) (xy 93.472 -124.2822)
			)
		)
	)
	(zone
		(layer "F.Cu")
		(hatch none 0.5)
		(connect_pads
			(clearance 0)
		)
		(min_thickness 0.25)
		(keepout
			(tracks allowed)
			(vias allowed)
			(pads allowed)
			(copperpour allowed)
			(footprints allowed)
		)
		(placement
			(enabled no)
			(sheetname "")
		)
		(fill
			(thermal_gap 0.5)
			(thermal_bridge_width 0.5)
			(island_removal_mode 0)
		)
		(polygon
			(pts
				(xy 63.6016 -148.1836) (xy 65.4558 -148.1836) (xy 65.4558 -148.971) (xy 63.6016 -148.971)
			)
		)
	)
	(zone
		(layer "F.Cu")
		(hatch none 0.5)
		(connect_pads
			(clearance 0)
		)
		(min_thickness 0.25)
		(keepout
			(tracks allowed)
			(vias allowed)
			(pads allowed)
			(copperpour allowed)
			(footprints allowed)
		)
		(placement
			(enabled no)
			(sheetname "")
		)
		(fill
			(thermal_gap 0.5)
			(thermal_bridge_width 0.5)
			(island_removal_mode 0)
		)
		(polygon
			(pts
				(xy 181.2798 -90.551) (xy 181.2798 -88.3158) (xy 181.991 -88.3158) (xy 181.991 -90.551)
			)
		)
	)
	(zone
		(layer "F.Cu")
		(hatch none 0.5)
		(connect_pads
			(clearance 0)
		)
		(min_thickness 0.25)
		(keepout
			(tracks allowed)
			(vias allowed)
			(pads allowed)
			(copperpour allowed)
			(footprints allowed)
		)
		(placement
			(enabled no)
			(sheetname "")
		)
		(fill
			(thermal_gap 0.5)
			(thermal_bridge_width 0.5)
			(island_removal_mode 0)
		)
		(polygon
			(pts
				(xy 178.2572 -150.2664) (xy 178.2572 -148.3868) (xy 180.34 -148.3868) (xy 180.4924 -148.3868) (xy 180.7972 -148.6916)
				(xy 180.7972 -150.1902) (xy 180.7972 -150.5458) (xy 180.5559 -150.7871) (xy 179.6415 -150.7871)
				(xy 178.689 -151.7396) (xy 178.3842 -151.7396) (xy 178.2572 -151.6126)
			)
		)
	)
	(zone
		(net "TPS74801_P2V5_STBY_OUT")
		(layer "F.Cu")
		(hatch none 0.5)
		(connect_pads
			(clearance 0.5)
		)
		(min_thickness 0.25)
		(fill yes
			(thermal_gap 0.5)
			(thermal_bridge_width 0.5)
			(island_removal_mode 0)
		)
		(polygon
			(pts
				(xy 75.07732 -172.85208) (xy 74.5744 -173.355) (xy 74.5744 -175.0822) (xy 74.6506 -175.1584) (xy 75.29068 -175.1584)
				(xy 75.49388 -175.3616) (xy 75.49388 -176.75352) (xy 74.88428 -177.36312) (xy 74.88428 -178.38928)
				(xy 74.90968 -178.41468) (xy 76.96708 -178.41468) (xy 77.01788 -178.46548) (xy 77.01788 -179.22748)
				(xy 78.21168 -179.22748) (xy 78.31328 -179.12588) (xy 78.31328 -178.82108) (xy 78.656688 -178.477672)
				(xy 82.111088 -178.477672) (xy 82.37728 -178.21148) (xy 82.37728 -173.10608) (xy 82.12328 -172.85208)
			)
		)
		(polygon
			(pts
				(xy 75.286616 -174.37608) (xy 75.083416 -174.37608) (xy 75.083416 -174.57928) (xy 75.286616 -174.57928)
			)
		)
		(polygon
			(pts
				(xy 75.239372 -173.952662) (xy 75.036172 -173.952662) (xy 75.036172 -174.155862) (xy 75.239372 -174.155862)
			)
		)
		(polygon
			(pts
				(xy 80.39608 -173.56328) (xy 80.19288 -173.56328) (xy 80.19288 -173.76648) (xy 80.39608 -173.76648)
			)
		)
		(polygon
			(pts
				(xy 79.78648 -173.56328) (xy 79.58328 -173.56328) (xy 79.58328 -173.76648) (xy 79.78648 -173.76648)
			)
		)
		(polygon
			(pts
				(xy 75.239372 -173.393862) (xy 75.036172 -173.393862) (xy 75.036172 -173.597062) (xy 75.239372 -173.597062)
			)
		)
	)
	(zone
		(layer "F.Cu")
		(hatch none 0.5)
		(connect_pads
			(clearance 0)
		)
		(min_thickness 0.25)
		(keepout
			(tracks not_allowed)
			(vias allowed)
			(pads allowed)
			(copperpour not_allowed)
			(footprints allowed)
		)
		(placement
			(enabled no)
			(sheetname "")
		)
		(fill
			(thermal_gap 0.5)
			(thermal_bridge_width 0.5)
			(island_removal_mode 0)
		)
		(polygon
			(pts
				(arc
					(start 85.367368 -84.904834)
					(mid 84.983828 -84.521294)
					(end 84.600288 -84.904834)
				)
				(xy 84.600288 -85.108796) (xy 84.776056 -85.108796)
				(arc
					(start 84.780628 -85.108542)
					(mid 84.794441 -85.107696)
					(end 84.80806 -85.10524)
				)
				(arc
					(start 84.80806 -85.10524)
					(mid 85.067098 -84.651349)
					(end 85.00745 -85.170518)
				)
				(arc
					(start 85.00745 -85.170518)
					(mid 84.923416 -85.242539)
					(end 84.818474 -85.277706)
				)
				(xy 84.816188 -85.279992) (xy 84.789264 -85.279992) (xy 84.780628 -85.280246) (xy 84.776056 -85.279992)
				(xy 84.600288 -85.279992) (xy 84.600288 -85.419692) (xy 84.776056 -85.419692) (xy 84.780628 -85.419692)
				(xy 84.789264 -85.419692) (xy 84.816188 -85.419692)
				(arc
					(start 84.818474 -85.422232)
					(mid 84.92259 -85.457014)
					(end 85.00618 -85.52815)
				)
				(arc
					(start 85.00618 -85.52815)
					(mid 85.067971 -86.046831)
					(end 84.80679 -85.594444)
				)
				(arc
					(start 84.80679 -85.594444)
					(mid 84.793795 -85.592173)
					(end 84.780628 -85.591396)
				)
				(xy 84.776056 -85.591396) (xy 84.600288 -85.591396)
				(arc
					(start 84.600288 -85.79358)
					(mid 84.983701 -86.177374)
					(end 85.367368 -85.793834)
				)
			)
		)
	)
	(zone
		(layer "F.Cu")
		(hatch none 0.5)
		(connect_pads
			(clearance 0)
		)
		(min_thickness 0.25)
		(keepout
			(tracks allowed)
			(vias allowed)
			(pads allowed)
			(copperpour allowed)
			(footprints allowed)
		)
		(placement
			(enabled no)
			(sheetname "")
		)
		(fill
			(thermal_gap 0.5)
			(thermal_bridge_width 0.5)
			(island_removal_mode 0)
		)
		(polygon
			(pts
				(xy 122.573542 -6.619494) (xy 122.573542 -10.11428) (xy 122.8979 -10.438638) (xy 122.8979 -10.94994)
				(xy 122.73026 -11.11758) (xy 122.20194 -11.11758) (xy 122.11304 -11.20648) (xy 122.11304 -12.34694)
				(xy 121.9454 -12.51458) (xy 121.10212 -12.51458) (xy 120.719342 -12.131802) (xy 120.719342 -10.8712)
				(xy 120.719342 -7.2136) (xy 120.08358 -7.2136) (xy 119.94134 -7.07136) (xy 119.94134 -5.842) (xy 120.03786 -5.74548)
				(xy 122.12574 -5.74548) (xy 122.573542 -6.193282)
			)
		)
	)
	(zone
		(layer "F.Cu")
		(hatch none 0.5)
		(connect_pads
			(clearance 0)
		)
		(min_thickness 0.25)
		(keepout
			(tracks not_allowed)
			(vias allowed)
			(pads allowed)
			(copperpour not_allowed)
			(footprints allowed)
		)
		(placement
			(enabled no)
			(sheetname "")
		)
		(fill
			(thermal_gap 0.5)
			(thermal_bridge_width 0.5)
			(island_removal_mode 0)
		)
		(polygon
			(pts
				(arc
					(start 207.941672 -64.8208)
					(mid 207.960368 -64.843202)
					(end 207.967072 -64.8716)
				)
				(arc
					(start 207.967072 -65.0748)
					(mid 207.960368 -65.103198)
					(end 207.941672 -65.1256)
				)
				(arc
					(start 208.170272 -65.1256)
					(mid 208.151576 -65.103198)
					(end 208.144872 -65.0748)
				)
				(arc
					(start 208.144872 -64.8716)
					(mid 208.151576 -64.843202)
					(end 208.170272 -64.8208)
				)
			)
		)
	)
	(zone
		(layer "F.Cu")
		(hatch none 0.5)
		(connect_pads
			(clearance 0)
		)
		(min_thickness 0.25)
		(keepout
			(tracks not_allowed)
			(vias allowed)
			(pads allowed)
			(copperpour not_allowed)
			(footprints allowed)
		)
		(placement
			(enabled no)
			(sheetname "")
		)
		(fill
			(thermal_gap 0.5)
			(thermal_bridge_width 0.5)
			(island_removal_mode 0)
		)
		(polygon
			(pts
				(arc
					(start 150.750016 -187.999878)
					(mid 155.50007 -183.249824)
					(end 160.250124 -187.999878)
				)
				(arc
					(start 160.250124 -187.999878)
					(mid 155.50007 -192.749932)
					(end 150.750016 -187.999878)
				)
			)
		)
	)
	(zone
		(layer "F.Cu")
		(hatch none 0.5)
		(connect_pads
			(clearance 0)
		)
		(min_thickness 0.25)
		(keepout
			(tracks not_allowed)
			(vias allowed)
			(pads allowed)
			(copperpour not_allowed)
			(footprints allowed)
		)
		(placement
			(enabled no)
			(sheetname "")
		)
		(fill
			(thermal_gap 0.5)
			(thermal_bridge_width 0.5)
			(island_removal_mode 0)
		)
		(polygon
			(pts
				(arc
					(start 207.941672 -75.9968)
					(mid 207.960368 -76.019202)
					(end 207.967072 -76.0476)
				)
				(arc
					(start 207.967072 -76.2508)
					(mid 207.960368 -76.279198)
					(end 207.941672 -76.3016)
				)
				(arc
					(start 208.170272 -76.3016)
					(mid 208.151576 -76.279198)
					(end 208.144872 -76.2508)
				)
				(arc
					(start 208.144872 -76.0476)
					(mid 208.151576 -76.019202)
					(end 208.170272 -75.9968)
				)
			)
		)
	)
	(zone
		(net "GND")
		(layer "F.Cu")
		(hatch none 0.5)
		(connect_pads
			(clearance 0.5)
		)
		(min_thickness 0.25)
		(fill yes
			(thermal_gap 0.5)
			(thermal_bridge_width 0.5)
			(island_removal_mode 0)
		)
		(polygon
			(pts
				(xy 14.31798 -13.01496) (xy 13.2207 -14.11224) (xy 12.00912 -14.11224) (xy 11.79322 -14.32814) (xy 11.79322 -16.1036)
				(xy 11.94308 -16.25346) (xy 12.02182 -16.25346) (xy 12.25296 -16.4846) (xy 14.80312 -16.4846) (xy 15.22222 -16.0655)
				(xy 15.22222 -13.03528) (xy 15.2019 -13.01496)
			)
		)
		(polygon
			(pts
				(xy 15.11554 -13.51534) (xy 14.91234 -13.51534) (xy 14.91234 -13.71854) (xy 15.11554 -13.71854)
			)
		)
		(polygon
			(pts
				(xy 14.55674 -13.51534) (xy 14.35354 -13.51534) (xy 14.35354 -13.71854) (xy 14.55674 -13.71854)
			)
		)
	)
	(zone
		(net "P3V3_STBY")
		(layer "F.Cu")
		(hatch none 0.5)
		(connect_pads
			(clearance 0.5)
		)
		(min_thickness 0.25)
		(fill yes
			(thermal_gap 0.5)
			(thermal_bridge_width 0.5)
			(island_removal_mode 0)
		)
		(polygon
			(pts
				(xy 61.044328 -181.678072) (xy 60.7187 -182.0037) (xy 60.7187 -188.595) (xy 60.96635 -188.84265)
				(xy 63.63335 -188.84265) (xy 63.9826 -188.4934) (xy 63.9826 -182.2704) (xy 63.390272 -181.678072)
			)
		)
	)
	(zone
		(net "P0V975")
		(layer "F.Cu")
		(hatch none 0.5)
		(connect_pads
			(clearance 0.5)
		)
		(min_thickness 0.25)
		(fill yes
			(thermal_gap 0.5)
			(thermal_bridge_width 0.5)
			(island_removal_mode 0)
		)
		(polygon
			(pts
				(xy 223.158812 -98.720402) (xy 223.150938 -98.728276) (xy 223.150938 -101.92385) (xy 223.56826 -102.341172)
				(xy 227.670868 -102.341172) (xy 227.718874 -102.293166) (xy 227.718874 -99.82835) (xy 227.678742 -99.788218)
				(xy 225.222054 -99.788218) (xy 224.154238 -98.720402)
			)
		)
		(polygon
			(pts
				(xy 224.110042 -99.496118) (xy 223.906842 -99.496118) (xy 223.906842 -99.699318) (xy 224.110042 -99.699318)
			)
		)
	)
	(zone
		(layer "F.Cu")
		(hatch none 0.5)
		(connect_pads
			(clearance 0)
		)
		(min_thickness 0.25)
		(keepout
			(tracks allowed)
			(vias allowed)
			(pads allowed)
			(copperpour allowed)
			(footprints not_allowed)
		)
		(placement
			(enabled no)
			(sheetname "")
		)
		(fill
			(thermal_gap 0.5)
			(thermal_bridge_width 0.5)
			(island_removal_mode 0)
		)
		(polygon
			(pts
				(arc
					(start 150.750016 -110.000034)
					(mid 155.50007 -105.24998)
					(end 160.250124 -110.000034)
				)
				(arc
					(start 160.250124 -110.000034)
					(mid 155.50007 -114.750088)
					(end 150.750016 -110.000034)
				)
			)
		)
	)
	(zone
		(layer "F.Cu")
		(hatch none 0.5)
		(connect_pads
			(clearance 0)
		)
		(min_thickness 0.25)
		(keepout
			(tracks not_allowed)
			(vias allowed)
			(pads allowed)
			(copperpour not_allowed)
			(footprints allowed)
		)
		(placement
			(enabled no)
			(sheetname "")
		)
		(fill
			(thermal_gap 0.5)
			(thermal_bridge_width 0.5)
			(island_removal_mode 0)
		)
		(polygon
			(pts
				(arc
					(start 83.741768 -88.105488)
					(mid 83.358355 -87.721694)
					(end 82.974688 -88.105234)
				)
				(xy 82.974688 -88.308688) (xy 83.112356 -88.308688)
				(arc
					(start 83.116928 -88.308434)
					(mid 83.145747 -88.305744)
					(end 83.17357 -88.297766)
				)
				(arc
					(start 83.17357 -88.297766)
					(mid 83.456914 -87.857387)
					(end 83.360006 -88.371934)
				)
				(arc
					(start 83.360006 -88.371934)
					(mid 83.266929 -88.443636)
					(end 83.15452 -88.477852)
				)
				(xy 83.152488 -88.479884) (xy 83.126072 -88.479884) (xy 83.116928 -88.480138) (xy 83.112356 -88.479884)
				(xy 82.974688 -88.479884) (xy 82.974688 -88.619584) (xy 83.112356 -88.619584) (xy 83.116928 -88.619584)
				(xy 83.126072 -88.619584) (xy 83.152488 -88.619584)
				(arc
					(start 83.15452 -88.62187)
					(mid 83.266738 -88.656033)
					(end 83.359752 -88.727534)
				)
				(arc
					(start 83.359752 -88.727534)
					(mid 83.457174 -89.241905)
					(end 83.173316 -88.801956)
				)
				(arc
					(start 83.173316 -88.801956)
					(mid 83.145619 -88.793989)
					(end 83.116928 -88.791288)
				)
				(xy 83.112356 -88.791288) (xy 82.974688 -88.791288)
				(arc
					(start 82.974688 -88.994234)
					(mid 83.358228 -89.377774)
					(end 83.741768 -88.994234)
				)
			)
		)
	)
	(zone
		(layer "F.Cu")
		(hatch none 0.5)
		(connect_pads
			(clearance 0)
		)
		(min_thickness 0.25)
		(keepout
			(tracks allowed)
			(vias allowed)
			(pads allowed)
			(copperpour allowed)
			(footprints not_allowed)
		)
		(placement
			(enabled no)
			(sheetname "")
		)
		(fill
			(thermal_gap 0.5)
			(thermal_bridge_width 0.5)
			(island_removal_mode 0)
		)
		(polygon
			(pts
				(arc
					(start 7.750048 -187.999878)
					(mid 12.500102 -183.249824)
					(end 17.249902 -187.999878)
				)
				(arc
					(start 17.249902 -187.999878)
					(mid 12.500102 -192.749678)
					(end 7.750048 -187.999878)
				)
			)
		)
	)
	(zone
		(net "VT235_VX")
		(layer "F.Cu")
		(hatch none 0.5)
		(connect_pads
			(clearance 0.5)
		)
		(min_thickness 0.25)
		(fill yes
			(thermal_gap 0.5)
			(thermal_bridge_width 0.5)
			(island_removal_mode 0)
		)
		(polygon
			(pts
				(xy 190.2206 -115.3414) (xy 189.9412 -115.6208) (xy 189.9412 -116.8146) (xy 189.5348 -117.221) (xy 187.9092 -117.221)
				(xy 187.8076 -117.3226) (xy 187.8076 -118.7958) (xy 189.0268 -120.015) (xy 189.0268 -121.412) (xy 189.0649 -121.4501)
				(xy 191.4525 -121.4501) (xy 191.4906 -121.412) (xy 191.4906 -121.0818) (xy 191.77 -120.8024) (xy 194.818 -120.8024)
				(xy 195.0974 -120.523) (xy 195.0974 -115.824) (xy 194.6148 -115.3414)
			)
		)
		(polygon
			(pts
				(xy 194.183 -119.634) (xy 193.9798 -119.634) (xy 193.9798 -119.8372) (xy 194.183 -119.8372)
			)
		)
		(polygon
			(pts
				(xy 193.3194 -119.634) (xy 193.1162 -119.634) (xy 193.1162 -119.8372) (xy 193.3194 -119.8372)
			)
		)
	)
	(zone
		(net "TPS74801_P1V2_STBY_FB")
		(layer "F.Cu")
		(hatch none 0.5)
		(connect_pads
			(clearance 0.5)
		)
		(min_thickness 0.25)
		(fill yes
			(thermal_gap 0.5)
			(thermal_bridge_width 0.5)
			(island_removal_mode 0)
		)
		(polygon
			(pts
				(xy 14.151356 -161.798) (xy 13.824204 -162.125152) (xy 13.824204 -166.920164) (xy 14.08684 -167.1828)
				(xy 15.494 -167.1828) (xy 15.5448 -167.132) (xy 15.5448 -165.7096) (xy 15.8623 -165.3921) (xy 15.8623 -161.8615)
				(xy 15.7988 -161.798)
			)
		)
		(polygon
			(pts
				(xy 15.404084 -164.7317) (xy 15.200884 -164.7317) (xy 15.200884 -164.9349) (xy 15.404084 -164.9349)
			)
		)
		(polygon
			(pts
				(xy 15.404084 -164.1729) (xy 15.200884 -164.1729) (xy 15.200884 -164.3761) (xy 15.404084 -164.3761)
			)
		)
		(polygon
			(pts
				(xy 15.362936 -163.7538) (xy 15.159736 -163.7538) (xy 15.159736 -163.957) (xy 15.362936 -163.957)
			)
		)
		(polygon
			(pts
				(xy 15.362936 -163.1442) (xy 15.159736 -163.1442) (xy 15.159736 -163.3474) (xy 15.362936 -163.3474)
			)
		)
		(polygon
			(pts
				(xy 15.431516 -162.7251) (xy 15.228316 -162.7251) (xy 15.228316 -162.9283) (xy 15.431516 -162.9283)
			)
		)
		(polygon
			(pts
				(xy 15.431516 -162.1663) (xy 15.228316 -162.1663) (xy 15.228316 -162.3695) (xy 15.431516 -162.3695)
			)
		)
	)
	(zone
		(net "GND")
		(layer "F.Cu")
		(hatch none 0.5)
		(connect_pads
			(clearance 0.5)
		)
		(min_thickness 0.25)
		(fill yes
			(thermal_gap 0.5)
			(thermal_bridge_width 0.5)
			(island_removal_mode 0)
		)
		(polygon
			(pts
				(xy 213.36 -120.396) (xy 213.36 -123.1392) (xy 216.0016 -123.1392) (xy 216.2556 -122.8852) (xy 216.2556 -120.7516)
				(xy 215.9 -120.396)
			)
		)
		(polygon
			(pts
				(xy 214.0712 -120.9802) (xy 213.868 -120.9802) (xy 213.868 -121.1834) (xy 214.0712 -121.1834)
			)
		)
	)
	(zone
		(layer "F.Cu")
		(hatch none 0.5)
		(connect_pads
			(clearance 0)
		)
		(min_thickness 0.25)
		(keepout
			(tracks allowed)
			(vias allowed)
			(pads allowed)
			(copperpour allowed)
			(footprints allowed)
		)
		(placement
			(enabled no)
			(sheetname "")
		)
		(fill
			(thermal_gap 0.5)
			(thermal_bridge_width 0.5)
			(island_removal_mode 0)
		)
		(polygon
			(pts
				(xy 80.1624 -133.7183) (xy 80.1624 -133.477) (xy 80.3275 -133.3119) (xy 81.9785 -133.3119) (xy 82.042 -133.3754)
				(xy 82.042 -133.8326) (xy 81.9277 -133.9469) (xy 81.6864 -133.9469) (xy 80.391 -133.9469)
			)
		)
	)
	(zone
		(net "GND")
		(layer "F.Cu")
		(hatch none 0.5)
		(connect_pads
			(clearance 0.5)
		)
		(min_thickness 0.25)
		(fill yes
			(thermal_gap 0.5)
			(thermal_bridge_width 0.5)
			(island_removal_mode 0)
		)
		(polygon
			(pts
				(xy 76.145644 -160.5788) (xy 76.145644 -161.2265) (xy 75.980544 -161.3916) (xy 73.516744 -161.3916)
				(xy 73.377044 -161.5313) (xy 73.377044 -162.8013) (xy 73.580244 -163.0045) (xy 76.171044 -163.0045)
				(xy 76.196444 -163.0299) (xy 76.196444 -163.8427) (xy 79.422244 -163.8427) (xy 79.422244 -163.0807)
				(xy 79.473044 -163.0299) (xy 81.1784 -163.0299) (xy 81.4451 -163.2966) (xy 85.0773 -163.2966) (xy 85.4964 -162.8775)
				(xy 85.4964 -161.036) (xy 85.1916 -160.7312) (xy 81.822544 -160.7312) (xy 81.174844 -161.3789) (xy 79.447644 -161.3789)
				(xy 79.447644 -160.6169) (xy 79.409544 -160.5788)
			)
		)
		(polygon
			(pts
				(xy 82.2198 -162.5854) (xy 82.0166 -162.5854) (xy 82.0166 -162.7886) (xy 82.2198 -162.7886)
			)
		)
		(polygon
			(pts
				(xy 81.6102 -162.5854) (xy 81.407 -162.5854) (xy 81.407 -162.7886) (xy 81.6102 -162.7886)
			)
		)
	)
	(zone
		(net "P0V975")
		(layer "F.Cu")
		(hatch none 0.5)
		(connect_pads
			(clearance 0.5)
		)
		(min_thickness 0.25)
		(fill yes
			(thermal_gap 0.5)
			(thermal_bridge_width 0.5)
			(island_removal_mode 0)
		)
		(polygon
			(pts
				(xy 189.9666 -106.3244) (xy 189.611 -106.68) (xy 189.611 -113.0046) (xy 189.89675 -113.29035) (xy 201.58075 -113.29035)
				(xy 201.9173 -112.9538) (xy 202.1078 -112.9538) (xy 211.201 -112.9538) (xy 213.1314 -111.0234) (xy 213.1314 -107.1372)
				(xy 212.3186 -106.3244)
			)
		)
		(polygon
			(pts
				(xy 199.2884 -107.2134) (xy 199.0852 -107.2134) (xy 199.0852 -107.4166) (xy 199.2884 -107.4166)
			)
		)
		(polygon
			(pts
				(xy 198.4248 -107.2134) (xy 198.2216 -107.2134) (xy 198.2216 -107.4166) (xy 198.4248 -107.4166)
			)
		)
		(polygon
			(pts
				(xy 200.2028 -106.8324) (xy 199.9996 -106.8324) (xy 199.9996 -107.0356) (xy 200.2028 -107.0356)
			)
		)
		(polygon
			(pts
				(xy 199.5932 -106.8324) (xy 199.39 -106.8324) (xy 199.39 -107.0356) (xy 199.5932 -107.0356)
			)
		)
		(polygon
			(pts
				(xy 201.1426 -106.807) (xy 200.9394 -106.807) (xy 200.9394 -107.0102) (xy 201.1426 -107.0102)
			)
		)
		(polygon
			(pts
				(xy 200.5838 -106.807) (xy 200.3806 -106.807) (xy 200.3806 -107.0102) (xy 200.5838 -107.0102)
			)
		)
	)
	(zone
		(layer "F.Cu")
		(hatch none 0.5)
		(connect_pads
			(clearance 0)
		)
		(min_thickness 0.25)
		(keepout
			(tracks not_allowed)
			(vias allowed)
			(pads allowed)
			(copperpour not_allowed)
			(footprints allowed)
		)
		(placement
			(enabled no)
			(sheetname "")
		)
		(fill
			(thermal_gap 0.5)
			(thermal_bridge_width 0.5)
			(island_removal_mode 0)
		)
		(polygon
			(pts
				(arc
					(start 197.793864 -85.604096)
					(mid 197.793864 -85.065108)
					(end 197.254876 -85.065108)
				)
				(xy 197.111366 -85.208618) (xy 197.173342 -85.270594)
				(arc
					(start 197.176644 -85.273896)
					(mid 197.214308 -85.303652)
					(end 197.257924 -85.32368)
				)
				(arc
					(start 197.257924 -85.32368)
					(mid 197.777074 -85.249655)
					(end 197.319138 -85.505036)
				)
				(arc
					(start 197.319138 -85.505036)
					(mid 197.193723 -85.482969)
					(end 197.082918 -85.4202)
				)
				(xy 197.080378 -85.4202) (xy 197.062344 -85.402166) (xy 197.055232 -85.395308) (xy 197.05193 -85.392006)
				(xy 196.990208 -85.33003) (xy 196.891148 -85.428836) (xy 196.953378 -85.490812) (xy 196.95668 -85.494114)
				(xy 196.963538 -85.501226) (xy 196.981572 -85.51926)
				(arc
					(start 196.981572 -85.5218)
					(mid 197.044302 -85.632474)
					(end 197.066408 -85.757766)
				)
				(arc
					(start 197.066408 -85.757766)
					(mid 196.810651 -86.215758)
					(end 196.884798 -85.696552)
				)
				(arc
					(start 196.884798 -85.696552)
					(mid 196.864842 -85.6531)
					(end 196.835268 -85.615526)
				)
				(xy 196.831966 -85.612224) (xy 196.76999 -85.550248)
				(arc
					(start 196.631306 -85.688932)
					(mid 196.624227 -86.230046)
					(end 197.165468 -86.232492)
				)
			)
		)
	)
	(zone
		(layer "F.Cu")
		(hatch none 0.5)
		(connect_pads
			(clearance 0)
		)
		(min_thickness 0.25)
		(keepout
			(tracks allowed)
			(vias allowed)
			(pads allowed)
			(copperpour allowed)
			(footprints allowed)
		)
		(placement
			(enabled no)
			(sheetname "")
		)
		(fill
			(thermal_gap 0.5)
			(thermal_bridge_width 0.5)
			(island_removal_mode 0)
		)
		(polygon
			(pts
				(xy 91.2368 -160.02) (xy 91.2368 -158.369) (xy 94.615 -158.369) (xy 94.615 -159.1056) (xy 95.123 -159.6136)
				(xy 95.5294 -160.02) (xy 95.5294 -160.2994) (xy 95.1992 -160.6296) (xy 94.615 -160.6296) (xy 93.5228 -160.6296)
				(xy 92.2528 -161.8996) (xy 92.0496 -161.8996) (xy 91.5924 -161.4424) (xy 91.5924 -160.3756)
			)
		)
	)
	(zone
		(layer "F.Cu")
		(hatch none 0.5)
		(connect_pads
			(clearance 0)
		)
		(min_thickness 0.25)
		(keepout
			(tracks allowed)
			(vias allowed)
			(pads allowed)
			(copperpour allowed)
			(footprints allowed)
		)
		(placement
			(enabled no)
			(sheetname "")
		)
		(fill
			(thermal_gap 0.5)
			(thermal_bridge_width 0.5)
			(island_removal_mode 0)
		)
		(polygon
			(pts
				(xy 207.4164 -66.929) (xy 207.4164 -65.8114) (xy 208.7118 -65.8114) (xy 208.7118 -66.929)
			)
		)
	)
	(zone
		(net "P12V_STBY_VIN_PU1")
		(layer "F.Cu")
		(hatch none 0.5)
		(connect_pads
			(clearance 0.5)
		)
		(min_thickness 0.25)
		(fill yes
			(thermal_gap 0.5)
			(thermal_bridge_width 0.5)
			(island_removal_mode 0)
		)
		(polygon
			(pts
				(xy 173.355 -135.4582) (xy 173.272704 -135.540496) (xy 173.272704 -143.033496) (xy 172.8724 -143.4338)
				(xy 172.8724 -144.8054) (xy 172.9486 -144.8816) (xy 174.505366 -144.8816) (xy 174.625 -144.761966)
				(xy 177.717704 -144.761966) (xy 177.971704 -144.507966) (xy 177.971704 -136.595104) (xy 176.8348 -135.4582)
			)
		)
		(polygon
			(pts
				(xy 176.5681 -136.8933) (xy 176.3649 -136.8933) (xy 176.3649 -137.0965) (xy 176.5681 -137.0965)
			)
		)
		(polygon
			(pts
				(xy 175.1711 -136.8933) (xy 174.9679 -136.8933) (xy 174.9679 -137.0965) (xy 175.1711 -137.0965)
			)
		)
		(polygon
			(pts
				(xy 176.5681 -135.7503) (xy 176.3649 -135.7503) (xy 176.3649 -135.9535) (xy 176.5681 -135.9535)
			)
		)
		(polygon
			(pts
				(xy 175.1711 -135.7503) (xy 174.9679 -135.7503) (xy 174.9679 -135.9535) (xy 175.1711 -135.9535)
			)
		)
	)
	(zone
		(layer "F.Cu")
		(hatch none 0.5)
		(connect_pads
			(clearance 0)
		)
		(min_thickness 0.25)
		(keepout
			(tracks allowed)
			(vias allowed)
			(pads allowed)
			(copperpour allowed)
			(footprints not_allowed)
		)
		(placement
			(enabled no)
			(sheetname "")
		)
		(fill
			(thermal_gap 0.5)
			(thermal_bridge_width 0.5)
			(island_removal_mode 0)
		)
		(polygon
			(pts
				(arc
					(start 160.250124 -110.000034)
					(mid 155.50007 -114.750088)
					(end 150.750016 -110.000034)
				)
				(arc
					(start 150.750016 -110.000034)
					(mid 155.50007 -105.24998)
					(end 160.250124 -110.000034)
				)
			)
		)
	)
	(zone
		(net "P1V15_STBY")
		(layer "F.Cu")
		(hatch none 0.5)
		(connect_pads
			(clearance 0.5)
		)
		(min_thickness 0.25)
		(fill yes
			(thermal_gap 0.5)
			(thermal_bridge_width 0.5)
			(island_removal_mode 0)
		)
		(polygon
			(pts
				(xy 76.772008 -151.9428) (xy 76.49464 -152.220168) (xy 76.49464 -153.312876) (xy 76.673964 -153.4922)
				(xy 79.87792 -153.4922) (xy 79.88046 -153.49474) (xy 79.982568 -153.392632) (xy 79.982568 -152.042368)
				(xy 79.883 -151.9428)
			)
		)
	)
	(zone
		(layer "F.Cu")
		(hatch none 0.5)
		(connect_pads
			(clearance 0)
		)
		(min_thickness 0.25)
		(keepout
			(tracks not_allowed)
			(vias allowed)
			(pads allowed)
			(copperpour not_allowed)
			(footprints allowed)
		)
		(placement
			(enabled no)
			(sheetname "")
		)
		(fill
			(thermal_gap 0.5)
			(thermal_bridge_width 0.5)
			(island_removal_mode 0)
		)
		(polygon
			(pts
				(arc
					(start 78.505558 -70.508368)
					(mid 78.122018 -70.124828)
					(end 77.738478 -70.508368)
				)
				(xy 77.738478 -70.712584) (xy 77.827632 -70.712584)
				(arc
					(start 77.832204 -70.71233)
					(mid 77.880577 -70.706573)
					(end 77.926184 -70.68947)
				)
				(arc
					(start 77.926184 -70.68947)
					(mid 78.239842 -70.269064)
					(end 78.097888 -70.774052)
				)
				(arc
					(start 78.097888 -70.774052)
					(mid 77.993082 -70.847918)
					(end 77.869542 -70.882256)
				)
				(xy 77.867764 -70.88378) (xy 77.841856 -70.88378) (xy 77.832204 -70.884034) (xy 77.827632 -70.88378)
				(xy 77.738478 -70.88378) (xy 77.738478 -71.02348) (xy 77.82941 -71.02348) (xy 77.833982 -71.02348)
				(xy 77.843634 -71.02348) (xy 77.869542 -71.02348)
				(arc
					(start 77.87132 -71.025258)
					(mid 77.993394 -71.059184)
					(end 78.097126 -71.131938)
				)
				(arc
					(start 78.097126 -71.131938)
					(mid 78.240157 -71.636205)
					(end 77.925422 -71.217028)
				)
				(arc
					(start 77.925422 -71.217028)
					(mid 77.88099 -71.200711)
					(end 77.833982 -71.195184)
				)
				(xy 77.82941 -71.195184) (xy 77.738478 -71.195184)
				(arc
					(start 77.738478 -71.397114)
					(mid 78.121891 -71.780908)
					(end 78.505558 -71.397368)
				)
			)
		)
	)
	(zone
		(net "P1V8_STBY_SW")
		(layer "F.Cu")
		(hatch none 0.5)
		(connect_pads
			(clearance 0.5)
		)
		(min_thickness 0.25)
		(fill yes
			(thermal_gap 0.5)
			(thermal_bridge_width 0.5)
			(island_removal_mode 0)
		)
		(polygon
			(pts
				(xy 156.151834 -128.382522) (xy 155.99664 -128.537716) (xy 155.99664 -130.48996) (xy 155.575 -130.9116)
				(xy 155.575 -132.685282) (xy 157.13964 -134.249922) (xy 157.8864 -134.249922) (xy 158.3436 -134.707122)
				(xy 158.3436 -135.5344) (xy 158.4706 -135.6614) (xy 159.6898 -135.6614) (xy 159.6898 -134.5184)
				(xy 159.7152 -134.493) (xy 159.7152 -134.468362) (xy 160.44164 -133.741922) (xy 160.44164 -131.963922)
				(xy 161.049208 -131.356608) (xy 161.8488 -130.557016) (xy 161.8488 -128.546606) (xy 161.684716 -128.382522)
			)
		)
		(polygon
			(pts
				(xy 159.65424 -132.802122) (xy 159.45104 -132.802122) (xy 159.45104 -133.005322) (xy 159.65424 -133.005322)
			)
		)
		(polygon
			(pts
				(xy 156.28874 -132.675122) (xy 156.08554 -132.675122) (xy 156.08554 -132.878322) (xy 156.28874 -132.878322)
			)
		)
		(polygon
			(pts
				(xy 156.28874 -132.065522) (xy 156.08554 -132.065522) (xy 156.08554 -132.268722) (xy 156.28874 -132.268722)
			)
		)
		(polygon
			(pts
				(xy 159.65424 -131.938522) (xy 159.45104 -131.938522) (xy 159.45104 -132.141722) (xy 159.65424 -132.141722)
			)
		)
	)
	(zone
		(layer "F.Cu")
		(hatch none 0.5)
		(connect_pads
			(clearance 0)
		)
		(min_thickness 0.25)
		(keepout
			(tracks allowed)
			(vias allowed)
			(pads allowed)
			(copperpour allowed)
			(footprints not_allowed)
		)
		(placement
			(enabled no)
			(sheetname "")
		)
		(fill
			(thermal_gap 0.5)
			(thermal_bridge_width 0.5)
			(island_removal_mode 0)
		)
		(polygon
			(pts
				(arc
					(start 168.800018 -45.72)
					(mid 165.800024 -48.719994)
					(end 162.80003 -45.72)
				)
				(arc
					(start 162.80003 -45.72)
					(mid 165.800024 -42.720006)
					(end 168.800018 -45.72)
				)
			)
		)
	)
	(zone
		(layer "F.Cu")
		(hatch none 0.5)
		(connect_pads
			(clearance 0)
		)
		(min_thickness 0.25)
		(keepout
			(tracks not_allowed)
			(vias allowed)
			(pads allowed)
			(copperpour not_allowed)
			(footprints allowed)
		)
		(placement
			(enabled no)
			(sheetname "")
		)
		(fill
			(thermal_gap 0.5)
			(thermal_bridge_width 0.5)
			(island_removal_mode 0)
		)
		(polygon
			(pts
				(arc
					(start 78.505558 -83.335368)
					(mid 78.122018 -82.951828)
					(end 77.738478 -83.335368)
				)
				(xy 77.738478 -83.537044) (xy 77.841856 -83.537044)
				(arc
					(start 77.846428 -83.537044)
					(mid 77.888361 -83.532352)
					(end 77.928216 -83.518502)
				)
				(arc
					(start 77.928216 -83.518502)
					(mid 78.235989 -83.094312)
					(end 78.103476 -83.601306)
				)
				(arc
					(start 78.103476 -83.601306)
					(mid 78.002778 -83.673104)
					(end 77.883766 -83.706716)
				)
				(xy 77.881988 -83.708748) (xy 77.85608 -83.708748) (xy 77.846428 -83.708748) (xy 77.841856 -83.708748)
				(xy 77.738478 -83.708748) (xy 77.738478 -83.848448) (xy 77.841856 -83.848448) (xy 77.846428 -83.848194)
				(xy 77.85608 -83.848448) (xy 77.881988 -83.848448)
				(arc
					(start 77.883766 -83.850226)
					(mid 78.004383 -83.884644)
					(end 78.106016 -83.958176)
				)
				(arc
					(start 78.106016 -83.958176)
					(mid 78.233625 -84.466563)
					(end 77.929994 -84.039202)
				)
				(arc
					(start 77.929994 -84.039202)
					(mid 77.889314 -84.024782)
					(end 77.846428 -84.019898)
				)
				(xy 77.841856 -84.019644) (xy 77.738478 -84.019644)
				(arc
					(start 77.738478 -84.224114)
					(mid 78.121891 -84.607908)
					(end 78.505558 -84.224368)
				)
			)
		)
	)
	(zone
		(layer "F.Cu")
		(hatch none 0.5)
		(connect_pads
			(clearance 0)
		)
		(min_thickness 0.25)
		(keepout
			(tracks not_allowed)
			(vias allowed)
			(pads allowed)
			(copperpour not_allowed)
			(footprints allowed)
		)
		(placement
			(enabled no)
			(sheetname "")
		)
		(fill
			(thermal_gap 0.5)
			(thermal_bridge_width 0.5)
			(island_removal_mode 0)
		)
		(polygon
			(pts
				(arc
					(start 217.716354 -75.176126)
					(mid 217.716354 -74.637646)
					(end 217.177874 -74.637646)
				)
				(xy 217.17762 -74.637392) (xy 216.97061 -74.844402)
				(arc
					(start 217.113104 -74.986896)
					(mid 217.154894 -75.01256)
					(end 217.203782 -75.01636)
				)
				(arc
					(start 217.203782 -75.01636)
					(mid 217.645861 -74.729077)
					(end 217.310208 -75.13574)
				)
				(arc
					(start 217.310208 -75.13574)
					(mid 217.168031 -75.166825)
					(end 217.032078 -75.114912)
				)
				(xy 217.02903 -75.114912) (xy 216.864438 -74.950574) (xy 216.858342 -74.95667) (xy 216.683082 -75.13193)
				(xy 216.84742 -75.296268)
				(arc
					(start 216.84742 -75.299316)
					(mid 216.899294 -75.435838)
					(end 216.86774 -75.578462)
				)
				(arc
					(start 216.86774 -75.578462)
					(mid 216.46091 -75.913631)
					(end 216.748614 -75.472036)
				)
				(arc
					(start 216.748614 -75.472036)
					(mid 216.745132 -75.42265)
					(end 216.719404 -75.380342)
				)
				(xy 216.577164 -75.237848) (xy 216.369392 -75.44562)
				(arc
					(start 216.369646 -75.445874)
					(mid 216.369646 -75.984354)
					(end 216.908126 -75.984354)
				)
				(xy 216.90838 -75.984608) (xy 217.716354 -75.17638)
			)
		)
	)
	(zone
		(net "GND")
		(layer "F.Cu")
		(hatch none 0.5)
		(connect_pads
			(clearance 0.5)
		)
		(min_thickness 0.25)
		(fill yes
			(thermal_gap 0.5)
			(thermal_bridge_width 0.5)
			(island_removal_mode 0)
		)
		(polygon
			(pts
				(xy 170.561 -135.0264) (xy 169.843704 -135.743696) (xy 169.843704 -144.554702) (xy 170.16984 -144.880838)
				(xy 172.143674 -144.880838) (xy 172.208444 -144.816068) (xy 172.212 -144.816068) (xy 172.212 -143.256)
				(xy 172.5422 -142.9258) (xy 172.5422 -135.3058) (xy 172.2628 -135.0264)
			)
		)
	)
	(zone
		(layer "F.Cu")
		(hatch none 0.5)
		(connect_pads
			(clearance 0)
		)
		(min_thickness 0.25)
		(keepout
			(tracks allowed)
			(vias allowed)
			(pads allowed)
			(copperpour allowed)
			(footprints allowed)
		)
		(placement
			(enabled no)
			(sheetname "")
		)
		(fill
			(thermal_gap 0.5)
			(thermal_bridge_width 0.5)
			(island_removal_mode 0)
		)
		(polygon
			(pts
				(xy 63.3222 -141.0208) (xy 65.1764 -141.0208) (xy 65.1764 -141.8082) (xy 63.3222 -141.8082)
			)
		)
	)
	(zone
		(net "VT235_VDDH")
		(layer "F.Cu")
		(hatch none 0.5)
		(connect_pads
			(clearance 0.5)
		)
		(min_thickness 0.25)
		(fill yes
			(thermal_gap 0.5)
			(thermal_bridge_width 0.5)
			(island_removal_mode 0)
		)
		(polygon
			(pts
				(xy 182.1053 -106.335322) (xy 181.864 -106.576622) (xy 181.864 -112.0394) (xy 180.975 -112.9284)
				(xy 180.975 -120.16867) (xy 182.72633 -121.92) (xy 185.0136 -121.92) (xy 185.0644 -121.9708) (xy 190.0682 -121.9708)
				(xy 190.119 -121.92) (xy 190.119 -121.5644) (xy 186.069732 -121.5644) (xy 185.541666 -121.036334)
				(xy 184.14365 -121.036334) (xy 183.433466 -120.32615) (xy 183.433466 -119.475758) (xy 183.858662 -119.050562)
				(xy 184.052464 -119.050562) (xy 184.161176 -118.942104) (xy 184.161176 -106.536744) (xy 183.959754 -106.335322)
			)
		)
		(polygon
			(pts
				(xy 185.460386 -121.589292) (xy 185.257186 -121.589292) (xy 185.257186 -121.792492) (xy 185.460386 -121.792492)
			)
		)
		(polygon
			(pts
				(xy 184.850786 -121.589292) (xy 184.647586 -121.589292) (xy 184.647586 -121.792492) (xy 184.850786 -121.792492)
			)
		)
	)
	(zone
		(layer "F.Cu")
		(hatch none 0.5)
		(connect_pads
			(clearance 0)
		)
		(min_thickness 0.25)
		(keepout
			(tracks not_allowed)
			(vias allowed)
			(pads allowed)
			(copperpour not_allowed)
			(footprints allowed)
		)
		(placement
			(enabled no)
			(sheetname "")
		)
		(fill
			(thermal_gap 0.5)
			(thermal_bridge_width 0.5)
			(island_removal_mode 0)
		)
		(polygon
			(pts
				(arc
					(start 37.69995 -169.999914)
					(mid 41.450006 -166.249858)
					(end 45.200062 -169.999914)
				)
				(arc
					(start 45.200062 -169.999914)
					(mid 41.450006 -173.74997)
					(end 37.69995 -169.999914)
				)
			)
		)
	)
	(zone
		(net "PWR_BTN_GND")
		(layer "F.Cu")
		(hatch none 0.5)
		(connect_pads
			(clearance 0.5)
		)
		(min_thickness 0.25)
		(fill yes
			(thermal_gap 0.5)
			(thermal_bridge_width 0.5)
			(island_removal_mode 0)
		)
		(polygon
			(pts
				(xy 17.4625 -2.96164) (xy 17.0815 -3.34264) (xy 17.0815 -13.93952) (xy 17.1831 -14.04112) (xy 19.15668 -14.04112)
				(xy 19.42338 -14.30782) (xy 20.3454 -14.30782) (xy 21.24964 -13.40358) (xy 21.24964 -10.05586) (xy 20.81784 -9.62406)
				(xy 20.81784 -7.16026) (xy 27.12466 -7.16026) (xy 27.1653 -7.2009) (xy 27.1653 -10.13714) (xy 26.58872 -10.71372)
				(xy 26.58872 -12.60094) (xy 27.08402 -13.09624) (xy 28.8036 -13.09624) (xy 28.97632 -12.92352) (xy 28.97632 -3.2258)
				(xy 28.71216 -2.96164)
			)
		)
		(polygon
			(pts
				(xy 20.59178 -13.60424) (xy 20.38858 -13.60424) (xy 20.38858 -13.80744) (xy 20.59178 -13.80744)
			)
		)
		(polygon
			(pts
				(xy 20.03298 -13.60424) (xy 19.82978 -13.60424) (xy 19.82978 -13.80744) (xy 20.03298 -13.80744)
			)
		)
	)
	(zone
		(layer "F.Cu")
		(hatch none 0.5)
		(connect_pads
			(clearance 0)
		)
		(min_thickness 0.25)
		(keepout
			(tracks allowed)
			(vias allowed)
			(pads allowed)
			(copperpour allowed)
			(footprints allowed)
		)
		(placement
			(enabled no)
			(sheetname "")
		)
		(fill
			(thermal_gap 0.5)
			(thermal_bridge_width 0.5)
			(island_removal_mode 0)
		)
		(polygon
			(pts
				(xy 207.4164 -71.9582) (xy 207.4164 -70.8406) (xy 208.7118 -70.8406) (xy 208.7118 -71.9582)
			)
		)
	)
	(zone
		(layer "F.Cu")
		(hatch none 0.5)
		(connect_pads
			(clearance 0)
		)
		(min_thickness 0.25)
		(keepout
			(tracks allowed)
			(vias allowed)
			(pads allowed)
			(copperpour allowed)
			(footprints allowed)
		)
		(placement
			(enabled no)
			(sheetname "")
		)
		(fill
			(thermal_gap 0.5)
			(thermal_bridge_width 0.5)
			(island_removal_mode 0)
		)
		(polygon
			(pts
				(xy 95.123 -176.7078) (xy 96.0374 -176.7078) (xy 96.2406 -176.5046) (xy 96.2406 -175.514) (xy 96.0374 -175.3108)
				(xy 95.0722 -175.3108) (xy 94.9452 -175.4378) (xy 94.9452 -176.5046) (xy 95.123 -176.6824)
			)
		)
	)
	(zone
		(net "GND")
		(layer "F.Cu")
		(hatch none 0.5)
		(connect_pads
			(clearance 0.5)
		)
		(min_thickness 0.25)
		(fill yes
			(thermal_gap 0.5)
			(thermal_bridge_width 0.5)
			(island_removal_mode 0)
		)
		(polygon
			(pts
				(xy 83.2104 -154.3558) (xy 83.0834 -154.4828) (xy 83.0834 -158.1658) (xy 83.2866 -158.369) (xy 85.4202 -158.369)
				(xy 85.6234 -158.1658) (xy 85.6234 -154.686) (xy 85.2932 -154.3558)
			)
		)
	)
	(zone
		(layer "F.Cu")
		(hatch none 0.5)
		(connect_pads
			(clearance 0)
		)
		(min_thickness 0.25)
		(keepout
			(tracks allowed)
			(vias allowed)
			(pads allowed)
			(copperpour allowed)
			(footprints allowed)
		)
		(placement
			(enabled no)
			(sheetname "")
		)
		(fill
			(thermal_gap 0.5)
			(thermal_bridge_width 0.5)
			(island_removal_mode 0)
		)
		(polygon
			(pts
				(xy 67.3608 -139.8016) (xy 67.3608 -141.6558) (xy 66.5734 -141.6558) (xy 66.5734 -139.8016)
			)
		)
	)
	(zone
		(net "P5V_USB")
		(layer "F.Cu")
		(hatch none 0.5)
		(connect_pads
			(clearance 0.5)
		)
		(min_thickness 0.25)
		(fill yes
			(thermal_gap 0.5)
			(thermal_bridge_width 0.5)
			(island_removal_mode 0)
		)
		(polygon
			(pts
				(xy 90.792808 -25.955498) (xy 90.541094 -26.207212) (xy 90.541094 -28.898596) (xy 90.768678 -29.12618)
				(xy 91.761056 -29.12618) (xy 91.770454 -29.116782) (xy 92.554044 -29.116782) (xy 92.72016 -29.282898)
				(xy 92.72016 -31.439612) (xy 91.463622 -32.69615) (xy 91.463622 -35.484308) (xy 91.774518 -35.795204)
				(xy 95.903796 -35.795204) (xy 96.103694 -35.595306) (xy 96.103694 -31.828486) (xy 95.892366 -31.617158)
				(xy 94.831154 -31.617158) (xy 94.40037 -31.186374) (xy 94.40037 -27.22753) (xy 93.128338 -25.955498)
			)
		)
		(polygon
			(pts
				(xy 93.4466 -31.0642) (xy 93.2434 -31.0642) (xy 93.2434 -31.2674) (xy 93.4466 -31.2674)
			)
		)
		(polygon
			(pts
				(xy 93.4466 -30.2006) (xy 93.2434 -30.2006) (xy 93.2434 -30.4038) (xy 93.4466 -30.4038)
			)
		)
		(polygon
			(pts
				(xy 93.4466 -29.7942) (xy 93.2434 -29.7942) (xy 93.2434 -29.9974) (xy 93.4466 -29.9974)
			)
		)
		(polygon
			(pts
				(xy 93.4466 -28.9306) (xy 93.2434 -28.9306) (xy 93.2434 -29.1338) (xy 93.4466 -29.1338)
			)
		)
		(polygon
			(pts
				(xy 93.4466 -28.5242) (xy 93.2434 -28.5242) (xy 93.2434 -28.7274) (xy 93.4466 -28.7274)
			)
		)
		(polygon
			(pts
				(xy 93.4466 -27.6606) (xy 93.2434 -27.6606) (xy 93.2434 -27.8638) (xy 93.4466 -27.8638)
			)
		)
		(polygon
			(pts
				(xy 92.0623 -27.4447) (xy 91.8591 -27.4447) (xy 91.8591 -27.6479) (xy 92.0623 -27.6479)
			)
		)
		(polygon
			(pts
				(xy 90.9193 -27.4447) (xy 90.7161 -27.4447) (xy 90.7161 -27.6479) (xy 90.9193 -27.6479)
			)
		)
	)
	(zone
		(layer "F.Cu")
		(hatch none 0.5)
		(connect_pads
			(clearance 0)
		)
		(min_thickness 0.25)
		(keepout
			(tracks allowed)
			(vias allowed)
			(pads allowed)
			(copperpour allowed)
			(footprints not_allowed)
		)
		(placement
			(enabled no)
			(sheetname "")
		)
		(fill
			(thermal_gap 0.5)
			(thermal_bridge_width 0.5)
			(island_removal_mode 0)
		)
		(polygon
			(pts
				(arc
					(start 107.750102 -9.99998)
					(mid 103.000048 -14.750034)
					(end 98.249994 -9.99998)
				)
				(arc
					(start 98.249994 -9.99998)
					(mid 103.000048 -5.249926)
					(end 107.750102 -9.99998)
				)
			)
		)
	)
	(zone
		(layer "F.Cu")
		(hatch none 0.5)
		(connect_pads
			(clearance 0)
		)
		(min_thickness 0.25)
		(keepout
			(tracks not_allowed)
			(vias allowed)
			(pads allowed)
			(copperpour not_allowed)
			(footprints allowed)
		)
		(placement
			(enabled no)
			(sheetname "")
		)
		(fill
			(thermal_gap 0.5)
			(thermal_bridge_width 0.5)
			(island_removal_mode 0)
		)
		(polygon
			(pts
				(arc
					(start 217.749882 -187.999878)
					(mid 222.499936 -183.249824)
					(end 227.24999 -187.999878)
				)
				(arc
					(start 227.24999 -187.999878)
					(mid 222.499936 -192.749932)
					(end 217.749882 -187.999878)
				)
			)
		)
	)
	(zone
		(layer "F.Cu")
		(hatch none 0.5)
		(connect_pads
			(clearance 0)
		)
		(min_thickness 0.25)
		(keepout
			(tracks not_allowed)
			(vias allowed)
			(pads allowed)
			(copperpour not_allowed)
			(footprints allowed)
		)
		(placement
			(enabled no)
			(sheetname "")
		)
		(fill
			(thermal_gap 0.5)
			(thermal_bridge_width 0.5)
			(island_removal_mode 0)
		)
		(polygon
			(pts
				(arc
					(start 13.24991 -120.000014)
					(mid 17.999964 -115.24996)
					(end 22.750018 -120.000014)
				)
				(arc
					(start 22.750018 -120.000014)
					(mid 17.999964 -124.750068)
					(end 13.24991 -120.000014)
				)
			)
		)
	)
	(zone
		(net "GND")
		(layer "F.Cu")
		(hatch none 0.5)
		(connect_pads
			(clearance 0.5)
		)
		(min_thickness 0.25)
		(fill yes
			(thermal_gap 0.5)
			(thermal_bridge_width 0.5)
			(island_removal_mode 0)
		)
		(polygon
			(pts
				(xy 127.39116 -4.0259) (xy 127.16002 -4.25704) (xy 127.16002 -5.969) (xy 127.35052 -6.1595) (xy 129.20218 -6.1595)
				(xy 129.34696 -6.01472) (xy 129.34696 -4.23672) (xy 129.29362 -4.23672) (xy 129.0828 -4.0259)
			)
		)
		(polygon
			(pts
				(xy 128.529588 -5.154422) (xy 128.326388 -5.154422) (xy 128.326388 -5.357622) (xy 128.529588 -5.357622)
			)
		)
		(polygon
			(pts
				(xy 128.199388 -5.154422) (xy 127.996188 -5.154422) (xy 127.996188 -5.357622) (xy 128.199388 -5.357622)
			)
		)
	)
	(zone
		(net "GND")
		(layer "F.Cu")
		(hatch none 0.5)
		(connect_pads
			(clearance 0.5)
		)
		(min_thickness 0.25)
		(fill yes
			(thermal_gap 0.5)
			(thermal_bridge_width 0.5)
			(island_removal_mode 0)
		)
		(polygon
			(pts
				(xy 218.9099 -99.0219) (xy 218.7575 -99.1743) (xy 218.7575 -100.7491) (xy 219.456 -101.4476) (xy 222.5929 -101.4476)
				(xy 222.794068 -101.246432) (xy 222.794068 -99.146868) (xy 222.6691 -99.0219)
			)
		)
	)
	(zone
		(layer "F.Cu")
		(hatch none 0.5)
		(connect_pads
			(clearance 0)
		)
		(min_thickness 0.25)
		(keepout
			(tracks allowed)
			(vias allowed)
			(pads allowed)
			(copperpour allowed)
			(footprints allowed)
		)
		(placement
			(enabled no)
			(sheetname "")
		)
		(fill
			(thermal_gap 0.5)
			(thermal_bridge_width 0.5)
			(island_removal_mode 0)
		)
		(polygon
			(pts
				(xy 207.4164 -73.6346) (xy 207.4164 -72.517) (xy 208.7118 -72.517) (xy 208.7118 -73.6346)
			)
		)
	)
	(zone
		(layer "F.Cu")
		(hatch none 0.5)
		(connect_pads
			(clearance 0)
		)
		(min_thickness 0.25)
		(keepout
			(tracks allowed)
			(vias allowed)
			(pads allowed)
			(copperpour allowed)
			(footprints not_allowed)
		)
		(placement
			(enabled no)
			(sheetname "")
		)
		(fill
			(thermal_gap 0.5)
			(thermal_bridge_width 0.5)
			(island_removal_mode 0)
		)
		(polygon
			(pts
				(arc
					(start 217.749882 -14.99997)
					(mid 222.499936 -10.249916)
					(end 227.24999 -14.99997)
				)
				(arc
					(start 227.24999 -14.99997)
					(mid 222.499936 -19.750024)
					(end 217.749882 -14.99997)
				)
			)
		)
	)
	(zone
		(layer "F.Cu")
		(hatch none 0.5)
		(connect_pads
			(clearance 0)
		)
		(min_thickness 0.25)
		(keepout
			(tracks allowed)
			(vias allowed)
			(pads allowed)
			(copperpour allowed)
			(footprints not_allowed)
		)
		(placement
			(enabled no)
			(sheetname "")
		)
		(fill
			(thermal_gap 0.5)
			(thermal_bridge_width 0.5)
			(island_removal_mode 0)
		)
		(polygon
			(pts
				(arc
					(start 84.749894 -120.000014)
					(mid 80.000094 -124.749814)
					(end 75.25004 -120.000014)
				)
				(arc
					(start 75.25004 -120.000014)
					(mid 80.000094 -115.24996)
					(end 84.749894 -120.000014)
				)
			)
		)
	)
	(zone
		(layer "F.Cu")
		(hatch none 0.5)
		(connect_pads
			(clearance 0)
		)
		(min_thickness 0.25)
		(keepout
			(tracks allowed)
			(vias allowed)
			(pads allowed)
			(copperpour allowed)
			(footprints not_allowed)
		)
		(placement
			(enabled no)
			(sheetname "")
		)
		(fill
			(thermal_gap 0.5)
			(thermal_bridge_width 0.5)
			(island_removal_mode 0)
		)
		(polygon
			(pts
				(arc
					(start 216.799922 -84.479892)
					(mid 219.799916 -81.479898)
					(end 222.79991 -84.479892)
				)
				(arc
					(start 222.79991 -84.479892)
					(mid 219.799916 -87.479886)
					(end 216.799922 -84.479892)
				)
			)
		)
	)
	(zone
		(net "TPS74801_P1V15_STBY_FB")
		(layer "F.Cu")
		(hatch none 0.5)
		(connect_pads
			(clearance 0.5)
		)
		(min_thickness 0.25)
		(fill yes
			(thermal_gap 0.5)
			(thermal_bridge_width 0.5)
			(island_removal_mode 0)
		)
		(polygon
			(pts
				(xy 76.5048 -153.9748) (xy 75.937872 -154.541728) (xy 75.937872 -154.9908) (xy 75.946 -154.998928)
				(xy 75.946 -158.829756) (xy 76.3016 -159.185356) (xy 76.3016 -160.2359) (xy 76.327 -160.2613) (xy 76.602844 -160.2613)
				(xy 76.653644 -160.2105) (xy 76.653644 -158.7881) (xy 76.971144 -158.4706) (xy 76.971144 -154.829256)
				(xy 77.0128 -154.7876) (xy 77.0128 -154.1526) (xy 76.835 -153.9748)
			)
		)
		(polygon
			(pts
				(xy 76.542392 -157.778958) (xy 76.339192 -157.778958) (xy 76.339192 -157.982158) (xy 76.542392 -157.982158)
			)
		)
		(polygon
			(pts
				(xy 76.542392 -157.220158) (xy 76.339192 -157.220158) (xy 76.339192 -157.423358) (xy 76.542392 -157.423358)
			)
		)
		(polygon
			(pts
				(xy 76.5302 -156.739336) (xy 76.327 -156.739336) (xy 76.327 -156.942536) (xy 76.5302 -156.942536)
			)
		)
		(polygon
			(pts
				(xy 76.5302 -156.180536) (xy 76.327 -156.180536) (xy 76.327 -156.383736) (xy 76.5302 -156.383736)
			)
		)
		(polygon
			(pts
				(xy 76.52258 -155.7401) (xy 76.31938 -155.7401) (xy 76.31938 -155.9433) (xy 76.52258 -155.9433)
			)
		)
		(polygon
			(pts
				(xy 76.52258 -155.1305) (xy 76.31938 -155.1305) (xy 76.31938 -155.3337) (xy 76.52258 -155.3337)
			)
		)
	)
	(zone
		(layer "F.Cu")
		(hatch none 0.5)
		(connect_pads
			(clearance 0)
		)
		(min_thickness 0.25)
		(keepout
			(tracks not_allowed)
			(vias allowed)
			(pads allowed)
			(copperpour not_allowed)
			(footprints allowed)
		)
		(placement
			(enabled no)
			(sheetname "")
		)
		(fill
			(thermal_gap 0.5)
			(thermal_bridge_width 0.5)
			(island_removal_mode 0)
		)
		(polygon
			(pts
				(arc
					(start 227.24999 -110.000034)
					(mid 222.499936 -114.750088)
					(end 217.749882 -110.000034)
				)
				(arc
					(start 217.749882 -110.000034)
					(mid 222.499936 -105.24998)
					(end 227.24999 -110.000034)
				)
			)
		)
	)
	(zone
		(layer "F.Cu")
		(hatch none 0.5)
		(connect_pads
			(clearance 0)
		)
		(min_thickness 0.25)
		(keepout
			(tracks allowed)
			(vias allowed)
			(pads allowed)
			(copperpour allowed)
			(footprints not_allowed)
		)
		(placement
			(enabled no)
			(sheetname "")
		)
		(fill
			(thermal_gap 0.5)
			(thermal_bridge_width 0.5)
			(island_removal_mode 0)
		)
		(polygon
			(pts
				(arc
					(start 13.24991 -120.000014)
					(mid 17.999964 -115.24996)
					(end 22.750018 -120.000014)
				)
				(arc
					(start 22.750018 -120.000014)
					(mid 17.999964 -124.750068)
					(end 13.24991 -120.000014)
				)
			)
		)
	)
	(zone
		(layer "F.Cu")
		(hatch none 0.5)
		(connect_pads
			(clearance 0)
		)
		(min_thickness 0.25)
		(keepout
			(tracks allowed)
			(vias allowed)
			(pads allowed)
			(copperpour allowed)
			(footprints allowed)
		)
		(placement
			(enabled no)
			(sheetname "")
		)
		(fill
			(thermal_gap 0.5)
			(thermal_bridge_width 0.5)
			(island_removal_mode 0)
		)
		(polygon
			(pts
				(xy 30.1498 -181.1782) (xy 30.1498 -179.2478) (xy 32.131 -179.2478) (xy 32.131 -181.1782)
			)
		)
	)
	(zone
		(layer "F.Cu")
		(hatch none 0.5)
		(connect_pads
			(clearance 0)
		)
		(min_thickness 0.25)
		(keepout
			(tracks allowed)
			(vias allowed)
			(pads allowed)
			(copperpour allowed)
			(footprints not_allowed)
		)
		(placement
			(enabled no)
			(sheetname "")
		)
		(fill
			(thermal_gap 0.5)
			(thermal_bridge_width 0.5)
			(island_removal_mode 0)
		)
		(polygon
			(pts
				(arc
					(start 78.49997 -44.800012)
					(mid 73.749916 -40.049958)
					(end 78.49997 -35.299904)
				)
				(xy 89.499948 -35.299904) (xy 89.499948 -44.800012)
			)
		)
	)
	(zone
		(layer "F.Cu")
		(hatch none 0.5)
		(connect_pads
			(clearance 0)
		)
		(min_thickness 0.25)
		(keepout
			(tracks allowed)
			(vias allowed)
			(pads allowed)
			(copperpour allowed)
			(footprints allowed)
		)
		(placement
			(enabled no)
			(sheetname "")
		)
		(fill
			(thermal_gap 0.5)
			(thermal_bridge_width 0.5)
			(island_removal_mode 0)
		)
		(polygon
			(pts
				(xy 186.9186 -125.3998) (xy 186.9186 -123.6726) (xy 191.0334 -123.6726) (xy 191.0334 -125.3998)
				(xy 189.8904 -125.3998) (xy 189.71514 -125.57506) (xy 189.71514 -126.56312) (xy 189.64656 -126.6317)
				(xy 189.10046 -126.6317) (xy 188.63564 -126.16688) (xy 188.63564 -125.3998)
			)
		)
	)
	(zone
		(layer "F.Cu")
		(hatch none 0.5)
		(connect_pads
			(clearance 0)
		)
		(min_thickness 0.25)
		(keepout
			(tracks allowed)
			(vias allowed)
			(pads allowed)
			(copperpour allowed)
			(footprints allowed)
		)
		(placement
			(enabled no)
			(sheetname "")
		)
		(fill
			(thermal_gap 0.5)
			(thermal_bridge_width 0.5)
			(island_removal_mode 0)
		)
		(polygon
			(pts
				(xy 207.4164 -75.311) (xy 207.4164 -74.1934) (xy 208.7118 -74.1934) (xy 208.7118 -75.311)
			)
		)
	)
	(zone
		(net "AGND_P3V3_STBY")
		(layer "F.Cu")
		(hatch none 0.5)
		(connect_pads
			(clearance 0.5)
		)
		(min_thickness 0.25)
		(fill yes
			(thermal_gap 0.5)
			(thermal_bridge_width 0.5)
			(island_removal_mode 0)
		)
		(polygon
			(pts
				(xy 29.6926 -173.79061) (xy 28.282646 -175.200564) (xy 28.282646 -176.20361) (xy 28.528518 -176.449482)
				(xy 35.021774 -176.449482) (xy 35.267646 -176.20361) (xy 35.267646 -173.91761) (xy 35.140646 -173.79061)
			)
		)
		(polygon
			(pts
				(xy 30.213046 -175.805338) (xy 30.009846 -175.805338) (xy 30.009846 -176.008538) (xy 30.213046 -176.008538)
			)
		)
		(polygon
			(pts
				(xy 29.654246 -175.805338) (xy 29.451046 -175.805338) (xy 29.451046 -176.008538) (xy 29.654246 -176.008538)
			)
		)
		(polygon
			(pts
				(xy 29.171646 -175.805338) (xy 28.968446 -175.805338) (xy 28.968446 -176.008538) (xy 29.171646 -176.008538)
			)
		)
		(polygon
			(pts
				(xy 28.612846 -175.805338) (xy 28.409646 -175.805338) (xy 28.409646 -176.008538) (xy 28.612846 -176.008538)
			)
		)
		(polygon
			(pts
				(xy 31.254446 -175.221138) (xy 31.051246 -175.221138) (xy 31.051246 -175.424338) (xy 31.254446 -175.424338)
			)
		)
		(polygon
			(pts
				(xy 30.695646 -175.221138) (xy 30.492446 -175.221138) (xy 30.492446 -175.424338) (xy 30.695646 -175.424338)
			)
		)
		(polygon
			(pts
				(xy 34.785046 -174.85741) (xy 34.581846 -174.85741) (xy 34.581846 -175.06061) (xy 34.785046 -175.06061)
			)
		)
		(polygon
			(pts
				(xy 34.785046 -174.29861) (xy 34.581846 -174.29861) (xy 34.581846 -174.50181) (xy 34.785046 -174.50181)
			)
		)
	)
	(zone
		(net "P1V8")
		(layer "F.Cu")
		(hatch none 0.5)
		(connect_pads
			(clearance 0.5)
		)
		(min_thickness 0.25)
		(fill yes
			(thermal_gap 0.5)
			(thermal_bridge_width 0.5)
			(island_removal_mode 0)
		)
		(polygon
			(pts
				(xy 183.0832 -88.5698) (xy 182.9816 -88.6714) (xy 182.9816 -92.0242) (xy 183.0578 -92.1004) (xy 183.0578 -92.5322)
				(xy 182.753 -92.837) (xy 181.8386 -92.837) (xy 181.5846 -92.583) (xy 181.5846 -91.0844) (xy 170.9166 -91.0844)
				(xy 170.8404 -91.0082) (xy 169.635932 -91.0082) (xy 168.752266 -91.891866) (xy 168.752266 -109.606588)
				(xy 168.8846 -109.738922) (xy 168.8846 -112.2172) (xy 168.7576 -112.3442) (xy 168.7576 -116.84)
				(xy 168.9354 -117.0178) (xy 169.9768 -117.0178) (xy 170.0784 -117.1194) (xy 171.9072 -117.1194)
				(xy 172.085 -116.9416) (xy 173.0502 -116.9416) (xy 173.6344 -116.3574) (xy 176.1236 -116.3574) (xy 176.197514 -116.431314)
				(xy 177.4317 -116.431314) (xy 177.509678 -116.353336) (xy 177.509678 -115.7732) (xy 177.1904 -115.453922)
				(xy 177.1904 -110.363) (xy 176.2506 -109.4232) (xy 176.2506 -105.156) (xy 178.2699 -103.1367) (xy 183.4515 -103.1367)
				(xy 187.8711 -98.7171) (xy 187.8711 -93.8403) (xy 188.6204 -93.091) (xy 188.6204 -91.7448) (xy 187.8838 -91.0082)
				(xy 187.2996 -91.0082) (xy 187.2234 -91.0844) (xy 187.2234 -92.3798) (xy 186.944 -92.6592) (xy 185.1914 -92.6592)
				(xy 185.0136 -92.4814) (xy 185.0136 -91.15298) (xy 184.89422 -91.0336) (xy 184.1246 -91.0336) (xy 183.896 -90.805)
				(xy 183.896 -90.551) (xy 183.89219 -90.54719) (xy 183.89219 -88.64219) (xy 183.8198 -88.5698)
			)
		)
		(polygon
			(pts
				(xy 172.9232 -116.2304) (xy 172.72 -116.2304) (xy 172.72 -116.4336) (xy 172.9232 -116.4336)
			)
		)
		(polygon
			(pts
				(xy 172.027596 -116.123466) (xy 171.824396 -116.123466) (xy 171.824396 -116.326666) (xy 172.027596 -116.326666)
				(xy 172.1104 -116.4336) (xy 172.3136 -116.4336) (xy 172.3136 -116.2304) (xy 172.1104 -116.2304)
			)
		)
		(polygon
			(pts
				(xy 171.163996 -116.123466) (xy 170.960796 -116.123466) (xy 170.960796 -116.326666) (xy 171.163996 -116.326666)
			)
		)
		(polygon
			(pts
				(xy 177.298858 -115.774724) (xy 177.095658 -115.774724) (xy 177.095658 -115.977924) (xy 177.298858 -115.977924)
			)
		)
		(polygon
			(pts
				(xy 176.740058 -115.774724) (xy 176.536858 -115.774724) (xy 176.536858 -115.977924) (xy 176.740058 -115.977924)
			)
		)
		(polygon
			(pts
				(xy 169.4434 -112.7506) (xy 169.2402 -112.7506) (xy 169.2402 -112.9538) (xy 169.4434 -112.9538)
			)
		)
		(polygon
			(pts
				(xy 169.4434 -112.1918) (xy 169.2402 -112.1918) (xy 169.2402 -112.395) (xy 169.4434 -112.395)
			)
		)
		(polygon
			(pts
				(xy 169.4942 -109.4486) (xy 169.291 -109.4486) (xy 169.291 -109.6518) (xy 169.4942 -109.6518)
			)
		)
		(polygon
			(pts
				(xy 169.4942 -108.7374) (xy 169.291 -108.7374) (xy 169.291 -108.9406) (xy 169.4942 -108.9406)
			)
		)
		(polygon
			(pts
				(xy 169.4942 -108.4072) (xy 169.291 -108.4072) (xy 169.291 -108.6104) (xy 169.4942 -108.6104)
			)
		)
		(polygon
			(pts
				(xy 169.4942 -107.696) (xy 169.291 -107.696) (xy 169.291 -107.8992) (xy 169.4942 -107.8992)
			)
		)
		(polygon
			(pts
				(xy 169.4942 -107.3658) (xy 169.291 -107.3658) (xy 169.291 -107.569) (xy 169.4942 -107.569)
			)
		)
		(polygon
			(pts
				(xy 169.4942 -106.6546) (xy 169.291 -106.6546) (xy 169.291 -106.8578) (xy 169.4942 -106.8578)
			)
		)
		(polygon
			(pts
				(xy 169.4942 -106.3244) (xy 169.291 -106.3244) (xy 169.291 -106.5276) (xy 169.4942 -106.5276)
			)
		)
		(polygon
			(pts
				(xy 169.4942 -105.6132) (xy 169.291 -105.6132) (xy 169.291 -105.8164) (xy 169.4942 -105.8164)
			)
		)
		(polygon
			(pts
				(xy 169.4942 -105.283) (xy 169.291 -105.283) (xy 169.291 -105.4862) (xy 169.4942 -105.4862)
			)
		)
		(polygon
			(pts
				(xy 169.4942 -104.5718) (xy 169.291 -104.5718) (xy 169.291 -104.775) (xy 169.4942 -104.775)
			)
		)
		(polygon
			(pts
				(xy 169.4942 -104.2416) (xy 169.291 -104.2416) (xy 169.291 -104.4448) (xy 169.4942 -104.4448)
			)
		)
		(polygon
			(pts
				(xy 169.4942 -103.5304) (xy 169.291 -103.5304) (xy 169.291 -103.7336) (xy 169.4942 -103.7336)
			)
		)
		(polygon
			(pts
				(xy 181.0512 -91.5162) (xy 180.848 -91.5162) (xy 180.848 -91.7194) (xy 181.0512 -91.7194)
			)
		)
		(polygon
			(pts
				(xy 184.531 -91.4908) (xy 184.3278 -91.4908) (xy 184.3278 -91.694) (xy 184.531 -91.694)
			)
		)
		(polygon
			(pts
				(xy 187.92571 -91.47429) (xy 187.72251 -91.47429) (xy 187.72251 -91.67749) (xy 187.92571 -91.67749)
			)
		)
		(polygon
			(pts
				(xy 183.3372 -89.0016) (xy 183.134 -89.0016) (xy 183.134 -89.2048) (xy 183.3372 -89.2048)
			)
		)
	)
	(zone
		(net "P5V_STBY")
		(layer "F.Cu")
		(hatch none 0.5)
		(connect_pads
			(clearance 0.5)
		)
		(min_thickness 0.25)
		(fill yes
			(thermal_gap 0.5)
			(thermal_bridge_width 0.5)
			(island_removal_mode 0)
		)
		(polygon
			(pts
				(xy 170.688 -159.4866) (xy 169.378376 -160.796224) (xy 169.378376 -171.222162) (xy 169.371518 -171.22902)
				(xy 169.371518 -179.731416) (xy 169.650918 -180.010816) (xy 174.193454 -180.010816) (xy 177.288952 -176.915318)
				(xy 177.288952 -160.833816) (xy 175.941736 -159.4866)
			)
		)
	)
	(zone
		(layer "F.Cu")
		(hatch none 0.5)
		(connect_pads
			(clearance 0)
		)
		(min_thickness 0.25)
		(keepout
			(tracks allowed)
			(vias allowed)
			(pads allowed)
			(copperpour allowed)
			(footprints allowed)
		)
		(placement
			(enabled no)
			(sheetname "")
		)
		(fill
			(thermal_gap 0.5)
			(thermal_bridge_width 0.5)
			(island_removal_mode 0)
		)
		(polygon
			(pts
				(xy 207.4164 -76.9874) (xy 207.4164 -75.8698) (xy 208.7118 -75.8698) (xy 208.7118 -76.9874)
			)
		)
	)
	(zone
		(layer "F.Cu")
		(hatch none 0.5)
		(connect_pads
			(clearance 0)
		)
		(min_thickness 0.25)
		(keepout
			(tracks allowed)
			(vias allowed)
			(pads allowed)
			(copperpour allowed)
			(footprints not_allowed)
		)
		(placement
			(enabled no)
			(sheetname "")
		)
		(fill
			(thermal_gap 0.5)
			(thermal_bridge_width 0.5)
			(island_removal_mode 0)
		)
		(polygon
			(pts
				(arc
					(start 227.24999 -14.99997)
					(mid 222.499936 -19.750024)
					(end 217.749882 -14.99997)
				)
				(arc
					(start 217.749882 -14.99997)
					(mid 222.499936 -10.249916)
					(end 227.24999 -14.99997)
				)
			)
		)
	)
	(zone
		(layer "F.Cu")
		(hatch none 0.5)
		(connect_pads
			(clearance 0)
		)
		(min_thickness 0.25)
		(keepout
			(tracks not_allowed)
			(vias allowed)
			(pads allowed)
			(copperpour not_allowed)
			(footprints allowed)
		)
		(placement
			(enabled no)
			(sheetname "")
		)
		(fill
			(thermal_gap 0.5)
			(thermal_bridge_width 0.5)
			(island_removal_mode 0)
		)
		(polygon
			(pts
				(arc
					(start 78.505558 -76.909168)
					(mid 78.122018 -76.525628)
					(end 77.738478 -76.909168)
				)
				(xy 77.738478 -77.117448) (xy 77.833474 -77.117448)
				(arc
					(start 77.838046 -77.117194)
					(mid 77.885532 -77.111356)
					(end 77.930248 -77.094334)
				)
				(arc
					(start 77.930248 -77.094334)
					(mid 78.234605 -76.667215)
					(end 78.104746 -77.17536)
				)
				(arc
					(start 78.104746 -77.17536)
					(mid 77.999998 -77.251614)
					(end 77.875384 -77.28712)
				)
				(xy 77.873606 -77.288644) (xy 77.847698 -77.288644) (xy 77.838046 -77.288898) (xy 77.833474 -77.288644)
				(xy 77.738478 -77.288644) (xy 77.738478 -77.428344) (xy 77.833474 -77.428344) (xy 77.838046 -77.428344)
				(xy 77.847698 -77.428344) (xy 77.873606 -77.428344)
				(arc
					(start 77.875384 -77.430122)
					(mid 77.994183 -77.462798)
					(end 78.095602 -77.532738)
				)
				(arc
					(start 78.095602 -77.532738)
					(mid 78.242401 -78.036199)
					(end 77.923898 -77.619606)
				)
				(arc
					(start 77.923898 -77.619606)
					(mid 77.882073 -77.604993)
					(end 77.838046 -77.600048)
				)
				(xy 77.833474 -77.600048) (xy 77.738478 -77.600048)
				(arc
					(start 77.738478 -77.797914)
					(mid 78.121891 -78.181708)
					(end 78.505558 -77.798168)
				)
			)
		)
	)
	(zone
		(net "GND")
		(layer "F.Cu")
		(hatch none 0.5)
		(connect_pads
			(clearance 0.5)
		)
		(min_thickness 0.25)
		(fill yes
			(thermal_gap 0.5)
			(thermal_bridge_width 0.5)
			(island_removal_mode 0)
		)
		(polygon
			(pts
				(xy 200.5584 -113.6142) (xy 196.5198 -113.6142) (xy 196.3928 -113.7412) (xy 196.3928 -116.9416)
				(xy 197.0278 -117.5766) (xy 212.2932 -117.5766) (xy 212.979 -116.8908) (xy 212.979 -113.6142) (xy 212.8266 -113.4618)
				(xy 212.7504 -113.3856) (xy 212.0646 -113.3856) (xy 202.0062 -113.3856) (xy 201.7776 -113.6142)
			)
		)
	)
	(zone
		(layer "F.Cu")
		(hatch none 0.5)
		(connect_pads
			(clearance 0)
		)
		(min_thickness 0.25)
		(keepout
			(tracks allowed)
			(vias allowed)
			(pads allowed)
			(copperpour allowed)
			(footprints not_allowed)
		)
		(placement
			(enabled no)
			(sheetname "")
		)
		(fill
			(thermal_gap 0.5)
			(thermal_bridge_width 0.5)
			(island_removal_mode 0)
		)
		(polygon
			(pts
				(xy 230.000048 0)
				(arc
					(start 234.00004 0)
					(mid 234.707145 -0.292893)
					(end 235.000038 -0.999998)
				)
				(arc
					(start 235.000038 -183.76392)
					(mid 234.973274 -183.993728)
					(end 234.894374 -184.211214)
				)
				(arc
					(start 230.2764 -193.447162)
					(mid 230.156976 -193.631987)
					(end 230.000048 -193.786252)
				)
			)
		)
	)
	(zone
		(net "TPS74801_P2V5_STBY_FB")
		(layer "F.Cu")
		(hatch none 0.5)
		(connect_pads
			(clearance 0.5)
		)
		(min_thickness 0.25)
		(fill yes
			(thermal_gap 0.5)
			(thermal_bridge_width 0.5)
			(island_removal_mode 0)
		)
		(polygon
			(pts
				(xy 72.648572 -173.02988) (xy 72.39 -173.288452) (xy 72.39 -178.194208) (xy 72.610472 -178.41468)
				(xy 73.89368 -178.41468) (xy 73.9648 -178.34356) (xy 73.9648 -176.8602) (xy 74.26198 -176.56302)
				(xy 74.26198 -173.19498) (xy 74.09688 -173.02988)
			)
		)
		(polygon
			(pts
				(xy 73.833228 -175.932338) (xy 73.630028 -175.932338) (xy 73.630028 -176.135538) (xy 73.833228 -176.135538)
			)
		)
		(polygon
			(pts
				(xy 73.833228 -175.373538) (xy 73.630028 -175.373538) (xy 73.630028 -175.576738) (xy 73.833228 -175.576738)
			)
		)
		(polygon
			(pts
				(xy 73.762616 -174.98568) (xy 73.559416 -174.98568) (xy 73.559416 -175.18888) (xy 73.762616 -175.18888)
			)
		)
		(polygon
			(pts
				(xy 73.762616 -174.37608) (xy 73.559416 -174.37608) (xy 73.559416 -174.57928) (xy 73.762616 -174.57928)
			)
		)
		(polygon
			(pts
				(xy 73.816972 -173.952662) (xy 73.613772 -173.952662) (xy 73.613772 -174.155862) (xy 73.816972 -174.155862)
			)
		)
		(polygon
			(pts
				(xy 73.816972 -173.393862) (xy 73.613772 -173.393862) (xy 73.613772 -173.597062) (xy 73.816972 -173.597062)
			)
		)
	)
	(zone
		(net "GND")
		(layer "F.Cu")
		(hatch none 0.5)
		(connect_pads
			(clearance 0.5)
		)
		(min_thickness 0.25)
		(fill yes
			(thermal_gap 0.5)
			(thermal_bridge_width 0.5)
			(island_removal_mode 0)
		)
		(polygon
			(pts
				(xy 154.47264 -133.487922) (xy 154.21864 -133.741922) (xy 154.21864 -136.027922) (xy 154.614118 -136.4234)
				(xy 156.899864 -136.4234) (xy 156.910532 -136.434068) (xy 157.053026 -136.576308) (xy 158.096966 -136.576308)
				(xy 158.155132 -136.517634) (xy 158.155132 -135.711692) (xy 155.931362 -133.487922)
			)
		)
		(polygon
			(pts
				(xy 156.1084 -135.3566) (xy 155.9052 -135.3566) (xy 155.9052 -135.5598) (xy 156.1084 -135.5598)
			)
		)
		(polygon
			(pts
				(xy 155.2448 -135.3566) (xy 155.0416 -135.3566) (xy 155.0416 -135.5598) (xy 155.2448 -135.5598)
			)
		)
	)
	(zone
		(layer "F.Cu")
		(hatch none 0.5)
		(connect_pads
			(clearance 0)
		)
		(min_thickness 0.25)
		(keepout
			(tracks not_allowed)
			(vias allowed)
			(pads allowed)
			(copperpour not_allowed)
			(footprints allowed)
		)
		(placement
			(enabled no)
			(sheetname "")
		)
		(fill
			(thermal_gap 0.5)
			(thermal_bridge_width 0.5)
			(island_removal_mode 0)
		)
		(polygon
			(pts
				(arc
					(start 85.367368 -78.504796)
					(mid 84.983828 -78.121256)
					(end 84.600288 -78.504796)
				)
				(xy 84.600288 -78.708504) (xy 84.737956 -78.708504)
				(arc
					(start 84.742528 -78.708504)
					(mid 84.771623 -78.705757)
					(end 84.799678 -78.697582)
				)
				(arc
					(start 84.799678 -78.697582)
					(mid 85.082486 -78.256828)
					(end 84.986114 -78.771496)
				)
				(arc
					(start 84.986114 -78.771496)
					(mid 84.892865 -78.843575)
					(end 84.78012 -78.877922)
				)
				(xy 84.778088 -78.880208) (xy 84.751672 -78.880208) (xy 84.742528 -78.880208) (xy 84.737956 -78.880208)
				(xy 84.600288 -78.880208) (xy 84.600288 -79.019908) (xy 84.737956 -79.019908) (xy 84.742528 -79.019654)
				(xy 84.751672 -79.019908) (xy 84.778088 -79.019908)
				(arc
					(start 84.78012 -79.02194)
					(mid 84.892019 -79.055939)
					(end 84.984844 -79.127096)
				)
				(arc
					(start 84.984844 -79.127096)
					(mid 85.083175 -79.641304)
					(end 84.798662 -79.201772)
				)
				(arc
					(start 84.798662 -79.201772)
					(mid 84.771076 -79.193976)
					(end 84.742528 -79.191358)
				)
				(xy 84.737956 -79.191104) (xy 84.600288 -79.191104)
				(arc
					(start 84.600288 -79.393542)
					(mid 84.983701 -79.777336)
					(end 85.367368 -79.393796)
				)
			)
		)
	)
	(zone
		(layer "F.Cu")
		(hatch none 0.5)
		(connect_pads
			(clearance 0)
		)
		(min_thickness 0.25)
		(keepout
			(tracks allowed)
			(vias allowed)
			(pads allowed)
			(copperpour allowed)
			(footprints allowed)
		)
		(placement
			(enabled no)
			(sheetname "")
		)
		(fill
			(thermal_gap 0.5)
			(thermal_bridge_width 0.5)
			(island_removal_mode 0)
		)
		(polygon
			(pts
				(xy 63.2968 -142.4686) (xy 65.151 -142.4686) (xy 65.151 -143.256) (xy 63.2968 -143.256)
			)
		)
	)
	(zone
		(layer "F.Cu")
		(hatch none 0.5)
		(connect_pads
			(clearance 0)
		)
		(min_thickness 0.25)
		(keepout
			(tracks not_allowed)
			(vias allowed)
			(pads allowed)
			(copperpour not_allowed)
			(footprints allowed)
		)
		(placement
			(enabled no)
			(sheetname "")
		)
		(fill
			(thermal_gap 0.5)
			(thermal_bridge_width 0.5)
			(island_removal_mode 0)
		)
		(polygon
			(pts
				(arc
					(start 207.941672 -69.2912)
					(mid 207.960368 -69.313602)
					(end 207.967072 -69.342)
				)
				(arc
					(start 207.967072 -69.5452)
					(mid 207.960368 -69.573598)
					(end 207.941672 -69.596)
				)
				(arc
					(start 208.170272 -69.596)
					(mid 208.151576 -69.573598)
					(end 208.144872 -69.5452)
				)
				(arc
					(start 208.144872 -69.342)
					(mid 208.151576 -69.313602)
					(end 208.170272 -69.2912)
				)
			)
		)
	)
	(zone
		(net "GND")
		(layer "F.Cu")
		(hatch none 0.5)
		(connect_pads
			(clearance 0.5)
		)
		(min_thickness 0.25)
		(fill yes
			(thermal_gap 0.5)
			(thermal_bridge_width 0.5)
			(island_removal_mode 0)
		)
		(polygon
			(pts
				(xy 23.51405 -170.571414) (xy 23.47595 -170.609514) (xy 23.47595 -174.038768) (xy 23.57755 -174.140368)
				(xy 25.4254 -174.140368) (xy 25.818084 -173.747684) (xy 25.818084 -170.942) (xy 25.447498 -170.571414)
			)
		)
	)
	(zone
		(net "GND")
		(layer "F.Cu")
		(hatch none 0.5)
		(connect_pads
			(clearance 0.5)
		)
		(min_thickness 0.25)
		(fill yes
			(thermal_gap 0.5)
			(thermal_bridge_width 0.5)
			(island_removal_mode 0)
		)
		(polygon
			(pts
				(xy 24.892 -161.036) (xy 24.384 -161.544) (xy 24.384 -167.2463) (xy 23.9776 -167.6527) (xy 20.7137 -167.6527)
				(xy 20.066 -168.3004) (xy 18.3388 -168.3004) (xy 18.3388 -167.5384) (xy 18.301208 -167.500808) (xy 15.0368 -167.500808)
				(xy 15.0368 -168.148) (xy 14.8717 -168.3131) (xy 12.7254 -168.3131) (xy 12.5476 -168.4909) (xy 12.5476 -169.4434)
				(xy 12.319 -169.672) (xy 12.319 -170.7896) (xy 12.3698 -170.8404) (xy 13.081 -170.8404) (xy 13.4112 -170.5102)
				(xy 13.4112 -170.053) (xy 13.5382 -169.926) (xy 15.0622 -169.926) (xy 15.0876 -169.9514) (xy 15.0876 -170.7642)
				(xy 18.3134 -170.7642) (xy 18.3134 -170.0022) (xy 18.3642 -169.9514) (xy 26.0604 -169.9514) (xy 27.10561 -168.90619)
				(xy 27.10561 -161.44621) (xy 26.6954 -161.036)
			)
		)
		(polygon
			(pts
				(xy 13.081 -170.125136) (xy 12.8778 -170.125136) (xy 12.8778 -170.328336) (xy 13.081 -170.328336)
			)
		)
		(polygon
			(pts
				(xy 21.179536 -169.2402) (xy 20.976336 -169.2402) (xy 20.976336 -169.4434) (xy 21.179536 -169.4434)
			)
		)
		(polygon
			(pts
				(xy 20.569936 -169.2402) (xy 20.366736 -169.2402) (xy 20.366736 -169.4434) (xy 20.569936 -169.4434)
			)
		)
	)
	(zone
		(net "P12V_STBY")
		(layer "F.Cu")
		(hatch none 0.5)
		(connect_pads
			(clearance 0.5)
		)
		(min_thickness 0.25)
		(fill yes
			(thermal_gap 0.5)
			(thermal_bridge_width 0.5)
			(island_removal_mode 0)
		)
		(polygon
			(pts
				(xy 133.587744 -7.128764) (xy 133.55574 -7.160768) (xy 133.55574 -7.403338) (xy 133.461506 -7.497572)
				(xy 130.942588 -7.497572) (xy 130.756152 -7.684008) (xy 130.756152 -11.351514) (xy 130.9751 -11.570462)
				(xy 134.654544 -11.570462) (xy 134.965694 -11.259312) (xy 135.14832 -11.07694) (xy 135.14832 -7.1628)
				(xy 135.114284 -7.128764)
			)
		)
	)
	(zone
		(layer "F.Cu")
		(hatch none 0.5)
		(connect_pads
			(clearance 0)
		)
		(min_thickness 0.25)
		(keepout
			(tracks not_allowed)
			(vias allowed)
			(pads allowed)
			(copperpour not_allowed)
			(footprints allowed)
		)
		(placement
			(enabled no)
			(sheetname "")
		)
		(fill
			(thermal_gap 0.5)
			(thermal_bridge_width 0.5)
			(island_removal_mode 0)
		)
		(polygon
			(pts
				(arc
					(start 207.941672 -66.4972)
					(mid 207.960368 -66.519602)
					(end 207.967072 -66.548)
				)
				(arc
					(start 207.967072 -66.7512)
					(mid 207.960368 -66.779598)
					(end 207.941672 -66.802)
				)
				(arc
					(start 208.170272 -66.802)
					(mid 208.151576 -66.779598)
					(end 208.144872 -66.7512)
				)
				(arc
					(start 208.144872 -66.548)
					(mid 208.151576 -66.519602)
					(end 208.170272 -66.4972)
				)
			)
		)
	)
	(zone
		(layer "F.Cu")
		(hatch none 0.5)
		(connect_pads
			(clearance 0)
		)
		(min_thickness 0.25)
		(keepout
			(tracks allowed)
			(vias allowed)
			(pads allowed)
			(copperpour allowed)
			(footprints allowed)
		)
		(placement
			(enabled no)
			(sheetname "")
		)
		(fill
			(thermal_gap 0.5)
			(thermal_bridge_width 0.5)
			(island_removal_mode 0)
		)
		(polygon
			(pts
				(xy 158.3436 -139.5476) (xy 158.3436 -137.668) (xy 160.4264 -137.668) (xy 160.4264 -139.5476)
			)
		)
	)
	(zone
		(net "GND")
		(layer "F.Cu")
		(hatch none 0.5)
		(connect_pads
			(clearance 0.5)
		)
		(min_thickness 0.25)
		(fill yes
			(thermal_gap 0.5)
			(thermal_bridge_width 0.5)
			(island_removal_mode 0)
		)
		(polygon
			(pts
				(xy 188.317886 -0.763016) (xy 188.317886 -2.794) (xy 232.206038 -2.794) (xy 232.206038 -183.340248)
				(xy 228.273356 -191.20612) (xy 151.026622 -191.20612) (xy 147.09394 -183.340248) (xy 147.09394 -97.673668)
				(xy 145.062956 -97.673668)
				(arc
					(start 145.062956 -183.76392)
					(mid 145.069351 -183.818347)
					(end 145.088102 -183.869838)
				)
				(arc
					(start 149.706076 -193.10604)
					(mid 149.793376 -193.201687)
					(end 149.917912 -193.237104)
				)
				(arc
					(start 229.382066 -193.237104)
					(mid 229.506557 -193.201614)
					(end 229.593902 -193.10604)
				)
				(arc
					(start 234.211876 -183.869838)
					(mid 234.230599 -183.818341)
					(end 234.237022 -183.76392)
				)
				(arc
					(start 234.237022 -0.999998)
					(mid 234.167612 -0.832426)
					(end 234.00004 -0.763016)
				)
			)
		)
	)
	(zone
		(net "P3V3_STBY")
		(layer "F.Cu")
		(hatch none 0.5)
		(connect_pads
			(clearance 0.5)
		)
		(min_thickness 0.25)
		(fill yes
			(thermal_gap 0.5)
			(thermal_bridge_width 0.5)
			(island_removal_mode 0)
		)
		(polygon
			(pts
				(xy 39.3446 -130.1242) (xy 39.116 -130.3528) (xy 39.116 -130.6576) (xy 39.3446 -130.8862) (xy 39.3446 -131.3942)
				(xy 39.5224 -131.572) (xy 40.9448 -131.572) (xy 40.9702 -131.5466) (xy 40.9702 -130.1242)
			)
		)
		(polygon
			(pts
				(xy 40.646858 -130.891788) (xy 40.443658 -130.891788) (xy 40.443658 -131.094988) (xy 40.646858 -131.094988)
			)
		)
		(polygon
			(pts
				(xy 40.188134 -130.884168) (xy 39.984934 -130.884168) (xy 39.984934 -131.087368) (xy 40.188134 -131.087368)
			)
		)
	)
	(zone
		(net "GND")
		(layer "F.Cu")
		(hatch none 0.5)
		(connect_pads
			(clearance 0.5)
		)
		(min_thickness 0.25)
		(fill yes
			(thermal_gap 0.5)
			(thermal_bridge_width 0.5)
			(island_removal_mode 0)
		)
		(polygon
			(pts
				(xy 11.864594 -127.1778) (xy 6.341364 -132.70103) (xy 6.341364 -145.125186) (xy 7.09168 -145.875502)
				(xy 10.923524 -145.875502) (xy 11.3284 -145.470626) (xy 11.3284 -142.779242) (xy 10.651744 -142.102586)
				(xy 9.125966 -142.102586) (xy 8.729472 -141.706092) (xy 8.729472 -136.071864) (xy 8.733028 -136.068308)
				(xy 8.733028 -134.695438) (xy 14.447266 -128.9812) (xy 17.145 -128.9812) (xy 17.1958 -128.9304)
				(xy 21.7424 -128.9304) (xy 21.7551 -128.9431) (xy 22.4155 -128.9431) (xy 22.4536 -128.905) (xy 22.4536 -127.3302)
				(xy 22.3012 -127.1778)
			)
		)
		(polygon
			(pts
				(xy 8.277098 -141.186662) (xy 8.073898 -141.186662) (xy 8.073898 -141.389862) (xy 8.277098 -141.389862)
			)
		)
		(polygon
			(pts
				(xy 8.277098 -140.627862) (xy 8.073898 -140.627862) (xy 8.073898 -140.831062) (xy 8.277098 -140.831062)
			)
		)
		(polygon
			(pts
				(xy 8.2296 -139.7508) (xy 8.0264 -139.7508) (xy 8.0264 -139.954) (xy 8.2296 -139.954)
			)
		)
		(polygon
			(pts
				(xy 8.2296 -139.192) (xy 8.0264 -139.192) (xy 8.0264 -139.3952) (xy 8.2296 -139.3952)
			)
		)
		(polygon
			(pts
				(xy 8.295132 -138.323574) (xy 8.091932 -138.323574) (xy 8.091932 -138.526774) (xy 8.295132 -138.526774)
			)
		)
		(polygon
			(pts
				(xy 8.295132 -137.764774) (xy 8.091932 -137.764774) (xy 8.091932 -137.967974) (xy 8.295132 -137.967974)
			)
		)
		(polygon
			(pts
				(xy 8.269732 -136.894316) (xy 8.066532 -136.894316) (xy 8.066532 -137.097516) (xy 8.269732 -137.097516)
			)
		)
		(polygon
			(pts
				(xy 8.269732 -136.335516) (xy 8.066532 -136.335516) (xy 8.066532 -136.538716) (xy 8.269732 -136.538716)
			)
		)
		(polygon
			(pts
				(xy 8.27151 -135.467852) (xy 8.06831 -135.467852) (xy 8.06831 -135.671052) (xy 8.27151 -135.671052)
			)
		)
		(polygon
			(pts
				(xy 8.27151 -134.909052) (xy 8.06831 -134.909052) (xy 8.06831 -135.112252) (xy 8.27151 -135.112252)
			)
		)
		(polygon
			(pts
				(xy 21.837142 -128.2954) (xy 21.633942 -128.2954) (xy 21.633942 -128.4986) (xy 21.837142 -128.4986)
			)
		)
		(polygon
			(pts
				(xy 18.1356 -128.2954) (xy 17.9324 -128.2954) (xy 17.9324 -128.4986) (xy 18.1356 -128.4986)
			)
		)
		(polygon
			(pts
				(xy 17.5768 -128.2954) (xy 17.3736 -128.2954) (xy 17.3736 -128.4986) (xy 17.5768 -128.4986)
			)
		)
		(polygon
			(pts
				(xy 19.525742 -128.264666) (xy 19.322542 -128.264666) (xy 19.322542 -128.467866) (xy 19.525742 -128.467866)
			)
		)
		(polygon
			(pts
				(xy 18.966942 -128.264666) (xy 18.763742 -128.264666) (xy 18.763742 -128.467866) (xy 18.966942 -128.467866)
			)
		)
		(polygon
			(pts
				(xy 20.972272 -128.261364) (xy 20.769072 -128.261364) (xy 20.769072 -128.464564) (xy 20.972272 -128.464564)
			)
		)
		(polygon
			(pts
				(xy 20.413472 -128.261364) (xy 20.210272 -128.261364) (xy 20.210272 -128.464564) (xy 20.413472 -128.464564)
			)
		)
	)
	(zone
		(net "TPS74801_P1V15_STBY_OUT")
		(layer "F.Cu")
		(hatch none 0.5)
		(connect_pads
			(clearance 0.5)
		)
		(min_thickness 0.25)
		(fill yes
			(thermal_gap 0.5)
			(thermal_bridge_width 0.5)
			(island_removal_mode 0)
		)
		(polygon
			(pts
				(xy 78.5876 -154.1018) (xy 78.5114 -154.178) (xy 78.5114 -155.1178) (xy 78.4098 -155.2194) (xy 77.4192 -155.2194)
				(xy 77.3176 -155.321) (xy 77.314044 -155.321) (xy 77.314044 -156.6799) (xy 77.321664 -156.68752)
				(xy 77.321664 -156.91612) (xy 77.435964 -157.03042) (xy 78.025244 -157.03042) (xy 78.203044 -157.20822)
				(xy 78.203044 -158.6865) (xy 77.593444 -159.2961) (xy 77.593444 -160.2359) (xy 77.618844 -160.2613)
				(xy 79.676244 -160.2613) (xy 79.727044 -160.3121) (xy 79.727044 -161.0741) (xy 80.920844 -161.0741)
				(xy 81.022444 -160.9725) (xy 81.022444 -160.6677) (xy 81.276444 -160.4137) (xy 85.0519 -160.4137)
				(xy 85.1916 -160.274) (xy 85.1916 -158.8516) (xy 85.1408 -158.8008) (xy 82.804 -158.8008) (xy 82.5754 -158.5722)
				(xy 82.5754 -154.5844) (xy 81.2419 -154.5844) (xy 81.1276 -154.6987) (xy 80.0608 -154.6987) (xy 79.9846 -154.6225)
				(xy 79.9846 -154.178) (xy 79.9084 -154.1018)
			)
		)
		(polygon
			(pts
				(xy 77.9526 -156.180536) (xy 77.7494 -156.180536) (xy 77.7494 -156.383736) (xy 77.9526 -156.383736)
			)
		)
		(polygon
			(pts
				(xy 78.04658 -155.7401) (xy 77.84338 -155.7401) (xy 77.84338 -155.9433) (xy 78.04658 -155.9433)
			)
		)
		(polygon
			(pts
				(xy 81.0768 -155.2448) (xy 80.8736 -155.2448) (xy 80.8736 -155.448) (xy 81.0768 -155.448)
			)
		)
		(polygon
			(pts
				(xy 80.4672 -155.2448) (xy 80.264 -155.2448) (xy 80.264 -155.448) (xy 80.4672 -155.448)
			)
		)
	)
	(zone
		(net "MB0_CM_GATE")
		(layer "F.Cu")
		(hatch none 0.5)
		(connect_pads
			(clearance 0.5)
		)
		(min_thickness 0.25)
		(fill yes
			(thermal_gap 0.5)
			(thermal_bridge_width 0.5)
			(island_removal_mode 0)
		)
		(polygon
			(pts
				(xy 126.945898 -9.9314) (xy 126.685802 -10.191496) (xy 126.685802 -12.252198) (xy 125.997208 -12.940792)
				(xy 125.98781 -12.940792) (xy 125.87351 -13.055092) (xy 123.087892 -13.055092) (xy 122.7836 -12.7508)
				(xy 122.7836 -11.49858) (xy 121.87682 -10.5918) (xy 120.97258 -10.5918) (xy 120.96242 -10.60196)
				(xy 120.96242 -11.979656) (xy 121.601484 -12.61872) (xy 121.601484 -14.007084) (xy 121.9835 -14.3891)
				(xy 123.7869 -14.3891) (xy 124.0536 -14.6558) (xy 126.8222 -14.6558) (xy 128.5367 -12.9413) (xy 128.5367 -10.047986)
				(xy 128.420114 -9.9314)
			)
		)
	)
	(zone
		(net "GND")
		(layer "F.Cu")
		(hatch none 0.5)
		(connect_pads
			(clearance 0.5)
		)
		(min_thickness 0.25)
		(fill yes
			(thermal_gap 0.5)
			(thermal_bridge_width 0.5)
			(island_removal_mode 0)
		)
		(polygon
			(pts
				(xy 185.5216 -108.077) (xy 184.57037 -109.02823) (xy 184.57037 -119.04345) (xy 184.283604 -119.330216)
				(xy 183.887618 -119.330216) (xy 183.803544 -119.414544) (xy 183.803544 -120.479312) (xy 184.0992 -120.774968)
				(xy 185.617612 -120.774968) (xy 185.733944 -120.8913) (xy 186.31027 -120.8913) (xy 186.38647 -120.9675)
				(xy 188.8363 -120.9675) (xy 188.849 -120.9548) (xy 188.849 -120.3452) (xy 187.4012 -118.8974) (xy 187.4012 -115.3922)
				(xy 187.5028 -115.2906) (xy 188.2902 -115.2906) (xy 188.468 -115.2906) (xy 188.5188 -115.2398) (xy 188.5188 -108.5342)
				(xy 188.4807 -108.4961) (xy 188.0616 -108.077)
			)
		)
		(polygon
			(pts
				(xy 185.460386 -120.065292) (xy 185.257186 -120.065292) (xy 185.257186 -120.268492) (xy 185.460386 -120.268492)
			)
		)
		(polygon
			(pts
				(xy 184.850786 -120.065292) (xy 184.647586 -120.065292) (xy 184.647586 -120.268492) (xy 184.850786 -120.268492)
			)
		)
	)
	(zone
		(net "P12V_STBY_VIN_PU4")
		(layer "F.Cu")
		(hatch none 0.5)
		(connect_pads
			(clearance 0.5)
		)
		(min_thickness 0.25)
		(fill yes
			(thermal_gap 0.5)
			(thermal_bridge_width 0.5)
			(island_removal_mode 0)
		)
		(polygon
			(pts
				(xy 161.83864 -134.249922) (xy 160.528508 -135.560308) (xy 160.528508 -135.660892) (xy 160.3502 -135.8392)
				(xy 160.31464 -135.8392) (xy 160.31464 -136.271) (xy 160.543748 -136.500108) (xy 162.636708 -136.500108)
				(xy 162.865562 -136.271) (xy 166.2938 -136.271) (xy 166.5986 -136.5758) (xy 166.5986 -137.4902)
				(xy 167.041322 -137.932922) (xy 168.56964 -137.932922) (xy 168.82364 -137.678922) (xy 168.82364 -134.503922)
				(xy 168.56964 -134.249922)
			)
		)
		(polygon
			(pts
				(xy 164.3126 -134.7724) (xy 164.1094 -134.7724) (xy 164.1094 -134.9756) (xy 164.3126 -134.9756)
			)
		)
		(polygon
			(pts
				(xy 163.703 -134.7724) (xy 163.4998 -134.7724) (xy 163.4998 -134.9756) (xy 163.703 -134.9756)
			)
		)
	)
	(zone
		(layer "F.Cu")
		(hatch none 0.5)
		(connect_pads
			(clearance 0)
		)
		(min_thickness 0.25)
		(keepout
			(tracks not_allowed)
			(vias allowed)
			(pads allowed)
			(copperpour not_allowed)
			(footprints allowed)
		)
		(placement
			(enabled no)
			(sheetname "")
		)
		(fill
			(thermal_gap 0.5)
			(thermal_bridge_width 0.5)
			(island_removal_mode 0)
		)
		(polygon
			(pts
				(arc
					(start 78.550008 -100.300028)
					(mid 73.799954 -105.050082)
					(end 78.550008 -109.799882)
				)
				(xy 92.700094 -109.799882) (xy 92.700094 -100.300028)
			)
		)
	)
	(zone
		(layer "F.Cu")
		(hatch none 0.5)
		(connect_pads
			(clearance 0)
		)
		(min_thickness 0.25)
		(keepout
			(tracks allowed)
			(vias allowed)
			(pads allowed)
			(copperpour allowed)
			(footprints allowed)
		)
		(placement
			(enabled no)
			(sheetname "")
		)
		(fill
			(thermal_gap 0.5)
			(thermal_bridge_width 0.5)
			(island_removal_mode 0)
		)
		(polygon
			(pts
				(xy 175.4886 -60.2488) (xy 175.4886 -59.1312) (xy 176.784 -59.1312) (xy 176.784 -60.2488)
			)
		)
	)
	(zone
		(net "P1V8")
		(layer "F.Cu")
		(hatch none 0.5)
		(connect_pads
			(clearance 0.5)
		)
		(min_thickness 0.25)
		(fill yes
			(thermal_gap 0.5)
			(thermal_bridge_width 0.5)
			(island_removal_mode 0)
		)
		(polygon
			(pts
				(xy 204.8256 -43.1038) (xy 202.8698 -45.0596) (xy 199.898 -45.0596) (xy 199.1106 -45.847) (xy 199.1106 -47.9552)
				(xy 199.29602 -48.14062) (xy 206.24038 -48.14062) (xy 206.2988 -48.0822) (xy 206.2988 -44.7548)
				(xy 206.7306 -44.323) (xy 206.7306 -43.434) (xy 206.4004 -43.1038)
			)
		)
		(polygon
			(pts
				(xy 205.7146 -47.4726) (xy 205.5114 -47.4726) (xy 205.5114 -47.6758) (xy 205.7146 -47.6758)
			)
		)
		(polygon
			(pts
				(xy 205.0034 -47.4726) (xy 204.8002 -47.4726) (xy 204.8002 -47.6758) (xy 205.0034 -47.6758)
			)
		)
		(polygon
			(pts
				(xy 204.4446 -47.4726) (xy 204.2414 -47.4726) (xy 204.2414 -47.6758) (xy 204.4446 -47.6758)
			)
		)
		(polygon
			(pts
				(xy 203.7334 -47.4726) (xy 203.5302 -47.4726) (xy 203.5302 -47.6758) (xy 203.7334 -47.6758)
			)
		)
		(polygon
			(pts
				(xy 203.1746 -47.4726) (xy 202.9714 -47.4726) (xy 202.9714 -47.6758) (xy 203.1746 -47.6758)
			)
		)
		(polygon
			(pts
				(xy 202.4634 -47.4726) (xy 202.2602 -47.4726) (xy 202.2602 -47.6758) (xy 202.4634 -47.6758)
			)
		)
		(polygon
			(pts
				(xy 201.9046 -47.4726) (xy 201.7014 -47.4726) (xy 201.7014 -47.6758) (xy 201.9046 -47.6758)
			)
		)
		(polygon
			(pts
				(xy 201.1934 -47.4726) (xy 200.9902 -47.4726) (xy 200.9902 -47.6758) (xy 201.1934 -47.6758)
			)
		)
		(polygon
			(pts
				(xy 200.6346 -47.4726) (xy 200.4314 -47.4726) (xy 200.4314 -47.6758) (xy 200.6346 -47.6758)
			)
		)
		(polygon
			(pts
				(xy 199.9234 -47.4726) (xy 199.7202 -47.4726) (xy 199.7202 -47.6758) (xy 199.9234 -47.6758)
			)
		)
	)
	(zone
		(net "P1V8_STBY")
		(layer "F.Cu")
		(hatch none 0.5)
		(connect_pads
			(clearance 0.5)
		)
		(min_thickness 0.25)
		(fill yes
			(thermal_gap 0.5)
			(thermal_bridge_width 0.5)
			(island_removal_mode 0)
		)
		(polygon
			(pts
				(xy 18.6436 -170.2562) (xy 18.5166 -170.3832) (xy 18.5166 -170.8023) (xy 18.2372 -171.0817) (xy 16.51 -171.0817)
				(xy 16.51 -172.4914) (xy 17.0688 -173.0502) (xy 20.2692 -173.0502) (xy 21.3868 -174.1678) (xy 22.9616 -174.1678)
				(xy 23.0886 -174.0408) (xy 23.0886 -170.9166) (xy 22.4282 -170.2562)
			)
		)
		(polygon
			(pts
				(xy 21.179536 -170.7642) (xy 20.976336 -170.7642) (xy 20.976336 -170.9674) (xy 21.179536 -170.9674)
			)
		)
		(polygon
			(pts
				(xy 20.569936 -170.7642) (xy 20.366736 -170.7642) (xy 20.366736 -170.9674) (xy 20.569936 -170.9674)
			)
		)
	)
	(zone
		(layer "F.Cu")
		(hatch none 0.5)
		(connect_pads
			(clearance 0)
		)
		(min_thickness 0.25)
		(keepout
			(tracks allowed)
			(vias allowed)
			(pads allowed)
			(copperpour allowed)
			(footprints not_allowed)
		)
		(placement
			(enabled no)
			(sheetname "")
		)
		(fill
			(thermal_gap 0.5)
			(thermal_bridge_width 0.5)
			(island_removal_mode 0)
		)
		(polygon
			(pts
				(arc
					(start 22.750018 -24.99995)
					(mid 17.999964 -29.750004)
					(end 13.24991 -24.99995)
				)
				(arc
					(start 13.24991 -24.99995)
					(mid 17.999964 -20.249896)
					(end 22.750018 -24.99995)
				)
			)
		)
	)
	(zone
		(net "P1V2_STBY")
		(layer "F.Cu")
		(hatch none 0.5)
		(connect_pads
			(clearance 0.5)
		)
		(min_thickness 0.25)
		(fill yes
			(thermal_gap 0.5)
			(thermal_bridge_width 0.5)
			(island_removal_mode 0)
		)
		(polygon
			(pts
				(xy 18.892266 -158.452058) (xy 18.890234 -158.45409) (xy 18.84553 -158.45409) (xy 18.733262 -158.566358)
				(xy 18.733262 -160.471612) (xy 18.851372 -160.589722) (xy 20.436586 -160.589722) (xy 20.439634 -160.586674)
				(xy 20.730718 -160.586674) (xy 20.820634 -160.496758) (xy 20.820634 -158.622492) (xy 20.6502 -158.452058)
			)
		)
	)
	(zone
		(layer "F.Cu")
		(hatch none 0.5)
		(connect_pads
			(clearance 0)
		)
		(min_thickness 0.25)
		(keepout
			(tracks allowed)
			(vias allowed)
			(pads allowed)
			(copperpour allowed)
			(footprints allowed)
		)
		(placement
			(enabled no)
			(sheetname "")
		)
		(fill
			(thermal_gap 0.5)
			(thermal_bridge_width 0.5)
			(island_removal_mode 0)
		)
		(polygon
			(pts
				(xy 163.84778 -128.3462) (xy 165.26002 -128.3462) (xy 165.33368 -128.27254) (xy 165.33368 -127.82296)
				(xy 165.21938 -127.70866) (xy 163.8808 -127.70866) (xy 163.7411 -127.84836) (xy 163.7411 -128.23952)
			)
		)
	)
	(zone
		(layer "F.Cu")
		(hatch none 0.5)
		(connect_pads
			(clearance 0)
		)
		(min_thickness 0.25)
		(keepout
			(tracks allowed)
			(vias allowed)
			(pads allowed)
			(copperpour allowed)
			(footprints not_allowed)
		)
		(placement
			(enabled no)
			(sheetname "")
		)
		(fill
			(thermal_gap 0.5)
			(thermal_bridge_width 0.5)
			(island_removal_mode 0)
		)
		(polygon
			(pts
				(arc
					(start 162.80003 -45.72)
					(mid 165.800024 -42.720006)
					(end 168.800018 -45.72)
				)
				(arc
					(start 168.800018 -45.72)
					(mid 165.800024 -48.719994)
					(end 162.80003 -45.72)
				)
			)
		)
	)
	(zone
		(layer "F.Cu")
		(hatch none 0.5)
		(connect_pads
			(clearance 0)
		)
		(min_thickness 0.25)
		(keepout
			(tracks not_allowed)
			(vias allowed)
			(pads allowed)
			(copperpour not_allowed)
			(footprints allowed)
		)
		(placement
			(enabled no)
			(sheetname "")
		)
		(fill
			(thermal_gap 0.5)
			(thermal_bridge_width 0.5)
			(island_removal_mode 0)
		)
		(polygon
			(pts
				(arc
					(start 194.944492 -83.927696)
					(mid 194.944492 -83.388708)
					(end 194.405504 -83.388708)
				)
				(xy 194.261994 -83.532218) (xy 194.324986 -83.59521)
				(arc
					(start 194.328288 -83.598512)
					(mid 194.365503 -83.627902)
					(end 194.408552 -83.647788)
				)
				(arc
					(start 194.408552 -83.647788)
					(mid 194.927404 -83.572219)
					(end 194.470274 -83.829144)
				)
				(arc
					(start 194.470274 -83.829144)
					(mid 194.345128 -83.80735)
					(end 194.234562 -83.744816)
				)
				(xy 194.232022 -83.744816) (xy 194.213734 -83.726782) (xy 194.206876 -83.719924) (xy 194.203574 -83.716622)
				(xy 194.140836 -83.65363) (xy 194.041776 -83.752436) (xy 194.104768 -83.815174) (xy 194.10807 -83.818476)
				(xy 194.114928 -83.825334) (xy 194.132962 -83.843622)
				(arc
					(start 194.132962 -83.846162)
					(mid 194.195623 -83.956712)
					(end 194.217544 -84.081874)
				)
				(arc
					(start 194.217544 -84.081874)
					(mid 193.96072 -84.5391)
					(end 194.035934 -84.020152)
				)
				(arc
					(start 194.035934 -84.020152)
					(mid 194.016045 -83.977105)
					(end 193.986658 -83.939888)
				)
				(xy 193.983356 -83.936586) (xy 193.920618 -83.873848)
				(arc
					(start 193.781934 -84.012532)
					(mid 193.774855 -84.553646)
					(end 194.316096 -84.556092)
				)
			)
		)
	)
	(zone
		(layer "F.Cu")
		(hatch none 0.5)
		(connect_pads
			(clearance 0)
		)
		(min_thickness 0.25)
		(keepout
			(tracks allowed)
			(vias allowed)
			(pads allowed)
			(copperpour allowed)
			(footprints allowed)
		)
		(placement
			(enabled no)
			(sheetname "")
		)
		(fill
			(thermal_gap 0.5)
			(thermal_bridge_width 0.5)
			(island_removal_mode 0)
		)
		(polygon
			(pts
				(xy 93.98 -151.3332) (xy 93.98 -153.1874) (xy 92.6338 -153.1874) (xy 92.6338 -151.3332)
			)
		)
	)
	(zone
		(layer "F.Cu")
		(hatch none 0.5)
		(connect_pads
			(clearance 0)
		)
		(min_thickness 0.25)
		(keepout
			(tracks allowed)
			(vias allowed)
			(pads allowed)
			(copperpour allowed)
			(footprints allowed)
		)
		(placement
			(enabled no)
			(sheetname "")
		)
		(fill
			(thermal_gap 0.5)
			(thermal_bridge_width 0.5)
			(island_removal_mode 0)
		)
		(polygon
			(pts
				(xy 207.4164 -65.204086) (xy 207.4164 -64.086486) (xy 208.7118 -64.086486) (xy 208.7118 -65.204086)
			)
		)
	)
	(zone
		(layer "F.Cu")
		(hatch none 0.5)
		(connect_pads
			(clearance 0)
		)
		(min_thickness 0.25)
		(keepout
			(tracks allowed)
			(vias allowed)
			(pads allowed)
			(copperpour allowed)
			(footprints not_allowed)
		)
		(placement
			(enabled no)
			(sheetname "")
		)
		(fill
			(thermal_gap 0.5)
			(thermal_bridge_width 0.5)
			(island_removal_mode 0)
		)
		(polygon
			(pts
				(arc
					(start 13.24991 -24.99995)
					(mid 17.999964 -20.249896)
					(end 22.750018 -24.99995)
				)
				(arc
					(start 22.750018 -24.99995)
					(mid 17.999964 -29.750004)
					(end 13.24991 -24.99995)
				)
			)
		)
	)
	(zone
		(layer "F.Cu")
		(hatch none 0.5)
		(connect_pads
			(clearance 0)
		)
		(min_thickness 0.25)
		(keepout
			(tracks allowed)
			(vias allowed)
			(pads allowed)
			(copperpour allowed)
			(footprints not_allowed)
		)
		(placement
			(enabled no)
			(sheetname "")
		)
		(fill
			(thermal_gap 0.5)
			(thermal_bridge_width 0.5)
			(island_removal_mode 0)
		)
		(polygon
			(pts
				(arc
					(start 45.200062 -169.999914)
					(mid 41.450006 -173.74997)
					(end 37.69995 -169.999914)
				)
				(arc
					(start 37.69995 -169.999914)
					(mid 41.450006 -166.249858)
					(end 45.200062 -169.999914)
				)
			)
		)
	)
	(zone
		(layer "F.Cu")
		(hatch none 0.5)
		(connect_pads
			(clearance 0)
		)
		(min_thickness 0.25)
		(keepout
			(tracks not_allowed)
			(vias allowed)
			(pads allowed)
			(copperpour not_allowed)
			(footprints allowed)
		)
		(placement
			(enabled no)
			(sheetname "")
		)
		(fill
			(thermal_gap 0.5)
			(thermal_bridge_width 0.5)
			(island_removal_mode 0)
		)
		(polygon
			(pts
				(arc
					(start 83.741768 -81.705196)
					(mid 83.358228 -81.321656)
					(end 82.974688 -81.705196)
				)
				(xy 82.974688 -81.908396) (xy 83.099656 -81.908396)
				(arc
					(start 83.104228 -81.908396)
					(mid 83.138071 -81.904903)
					(end 83.170522 -81.89468)
				)
				(arc
					(start 83.170522 -81.89468)
					(mid 83.462176 -81.459569)
					(end 83.352894 -81.971896)
				)
				(arc
					(start 83.352894 -81.971896)
					(mid 83.256759 -82.043942)
					(end 83.141566 -82.078068)
				)
				(xy 83.139788 -82.0801) (xy 83.113626 -82.0801) (xy 83.104228 -82.0801) (xy 83.099656 -82.0801)
				(xy 82.974688 -82.0801) (xy 82.974688 -82.2198) (xy 83.099656 -82.2198) (xy 83.104228 -82.219546)
				(xy 83.113626 -82.2198) (xy 83.139788 -82.2198)
				(arc
					(start 83.141566 -82.221578)
					(mid 83.256612 -82.255596)
					(end 83.35264 -82.327496)
				)
				(arc
					(start 83.35264 -82.327496)
					(mid 83.462309 -82.839812)
					(end 83.170522 -82.404712)
				)
				(arc
					(start 83.170522 -82.404712)
					(mid 83.138061 -82.394591)
					(end 83.104228 -82.39125)
				)
				(xy 83.099656 -82.390996) (xy 82.974688 -82.390996)
				(arc
					(start 82.974688 -82.593942)
					(mid 83.358101 -82.977736)
					(end 83.741768 -82.594196)
				)
			)
		)
	)
	(zone
		(layer "F.Cu")
		(hatch none 0.5)
		(connect_pads
			(clearance 0)
		)
		(min_thickness 0.25)
		(keepout
			(tracks not_allowed)
			(vias allowed)
			(pads allowed)
			(copperpour not_allowed)
			(footprints allowed)
		)
		(placement
			(enabled no)
			(sheetname "")
		)
		(fill
			(thermal_gap 0.5)
			(thermal_bridge_width 0.5)
			(island_removal_mode 0)
		)
		(polygon
			(pts
				(arc
					(start 207.941672 -73.2028)
					(mid 207.960368 -73.225202)
					(end 207.967072 -73.2536)
				)
				(arc
					(start 207.967072 -73.4568)
					(mid 207.960368 -73.485198)
					(end 207.941672 -73.5076)
				)
				(arc
					(start 208.170272 -73.5076)
					(mid 208.151576 -73.485198)
					(end 208.144872 -73.4568)
				)
				(arc
					(start 208.144872 -73.2536)
					(mid 208.151576 -73.225202)
					(end 208.170272 -73.2028)
				)
			)
		)
	)
	(zone
		(layer "F.Cu")
		(hatch none 0.5)
		(connect_pads
			(clearance 0)
		)
		(min_thickness 0.25)
		(keepout
			(tracks allowed)
			(vias allowed)
			(pads allowed)
			(copperpour allowed)
			(footprints not_allowed)
		)
		(placement
			(enabled no)
			(sheetname "")
		)
		(fill
			(thermal_gap 0.5)
			(thermal_bridge_width 0.5)
			(island_removal_mode 0)
		)
		(polygon
			(pts
				(arc
					(start 160.250124 -187.999878)
					(mid 155.50007 -192.749932)
					(end 150.750016 -187.999878)
				)
				(arc
					(start 150.750016 -187.999878)
					(mid 155.50007 -183.249824)
					(end 160.250124 -187.999878)
				)
			)
		)
	)
	(zone
		(layer "F.Cu")
		(hatch none 0.5)
		(connect_pads
			(clearance 0)
		)
		(min_thickness 0.25)
		(keepout
			(tracks allowed)
			(vias allowed)
			(pads allowed)
			(copperpour allowed)
			(footprints not_allowed)
		)
		(placement
			(enabled no)
			(sheetname "")
		)
		(fill
			(thermal_gap 0.5)
			(thermal_bridge_width 0.5)
			(island_removal_mode 0)
		)
		(polygon
			(pts
				(xy 29.500068 -31.999936) (xy 5.500116 -31.999936) (xy 5.500116 -43.999912) (xy 29.500068 -43.999912)
			)
		)
	)
	(zone
		(layer "F.Cu")
		(hatch none 0.5)
		(connect_pads
			(clearance 0)
		)
		(min_thickness 0.25)
		(keepout
			(tracks not_allowed)
			(vias allowed)
			(pads allowed)
			(copperpour not_allowed)
			(footprints allowed)
		)
		(placement
			(enabled no)
			(sheetname "")
		)
		(fill
			(thermal_gap 0.5)
			(thermal_bridge_width 0.5)
			(island_removal_mode 0)
		)
		(polygon
			(pts
				(arc
					(start 216.573354 -79.113126)
					(mid 216.573354 -78.574646)
					(end 216.034874 -78.574646)
				)
				(xy 216.03462 -78.574392) (xy 215.827102 -78.78191)
				(arc
					(start 215.956896 -78.911704)
					(mid 216.003415 -78.940833)
					(end 216.057988 -78.946756)
				)
				(arc
					(start 216.057988 -78.946756)
					(mid 216.507385 -78.67114)
					(end 216.16289 -79.0702)
				)
				(arc
					(start 216.16289 -79.0702)
					(mid 216.014908 -79.096083)
					(end 215.875616 -79.03972)
				)
				(xy 215.872822 -79.03972) (xy 215.72093 -78.888082) (xy 215.539574 -79.069438) (xy 215.691212 -79.22133)
				(arc
					(start 215.691212 -79.224124)
					(mid 215.747527 -79.362982)
					(end 215.721946 -79.510636)
				)
				(arc
					(start 215.721946 -79.510636)
					(mid 215.323413 -79.855515)
					(end 215.598502 -79.405988)
				)
				(arc
					(start 215.598502 -79.405988)
					(mid 215.592353 -79.351656)
					(end 215.563196 -79.305404)
				)
				(xy 215.433402 -79.17561) (xy 215.226392 -79.38262)
				(arc
					(start 215.226646 -79.382874)
					(mid 215.226646 -79.921354)
					(end 215.765126 -79.921354)
				)
				(xy 215.76538 -79.921608) (xy 216.573354 -79.11338)
			)
		)
	)
	(zone
		(layer "F.Cu")
		(hatch none 0.5)
		(connect_pads
			(clearance 0)
		)
		(min_thickness 0.25)
		(keepout
			(tracks allowed)
			(vias allowed)
			(pads allowed)
			(copperpour allowed)
			(footprints allowed)
		)
		(placement
			(enabled no)
			(sheetname "")
		)
		(fill
			(thermal_gap 0.5)
			(thermal_bridge_width 0.5)
			(island_removal_mode 0)
		)
		(polygon
			(pts
				(xy 62.9412 -145.1356) (xy 64.7954 -145.1356) (xy 64.7954 -145.7452) (xy 62.9412 -145.7452)
			)
		)
	)
	(zone
		(layer "F.Cu")
		(hatch none 0.5)
		(connect_pads
			(clearance 0)
		)
		(min_thickness 0.25)
		(keepout
			(tracks not_allowed)
			(vias allowed)
			(pads allowed)
			(copperpour not_allowed)
			(footprints allowed)
		)
		(placement
			(enabled no)
			(sheetname "")
		)
		(fill
			(thermal_gap 0.5)
			(thermal_bridge_width 0.5)
			(island_removal_mode 0)
		)
		(polygon
			(pts
				(arc
					(start 83.741768 -75.305158)
					(mid 83.358228 -74.921618)
					(end 82.974688 -75.305158)
				)
				(xy 82.974688 -75.508612) (xy 83.086956 -75.508612)
				(arc
					(start 83.091528 -75.508358)
					(mid 83.130419 -75.504127)
					(end 83.167474 -75.491594)
				)
				(arc
					(start 83.167474 -75.491594)
					(mid 83.467303 -75.061749)
					(end 83.346036 -75.571604)
				)
				(arc
					(start 83.346036 -75.571604)
					(mid 83.246862 -75.644018)
					(end 83.128866 -75.67803)
				)
				(xy 83.127088 -75.679808) (xy 83.100926 -75.679808) (xy 83.091528 -75.680062) (xy 83.086956 -75.679808)
				(xy 82.974688 -75.679808) (xy 82.974688 -75.819508) (xy 83.086956 -75.819508) (xy 83.091528 -75.819508)
				(xy 83.100926 -75.819508) (xy 83.127088 -75.819508)
				(arc
					(start 83.128866 -75.82154)
					(mid 83.246709 -75.855457)
					(end 83.345782 -75.927712)
				)
				(arc
					(start 83.345782 -75.927712)
					(mid 83.46796 -76.437406)
					(end 83.167474 -76.007976)
				)
				(arc
					(start 83.167474 -76.007976)
					(mid 83.130411 -75.995483)
					(end 83.091528 -75.991212)
				)
				(xy 83.086956 -75.991212) (xy 82.974688 -75.991212)
				(arc
					(start 82.974688 -76.193904)
					(mid 83.358101 -76.577698)
					(end 83.741768 -76.194158)
				)
			)
		)
	)
	(zone
		(net "P3V3_STBY")
		(layer "F.Cu")
		(hatch none 0.5)
		(connect_pads
			(clearance 0.5)
		)
		(min_thickness 0.25)
		(fill yes
			(thermal_gap 0.5)
			(thermal_bridge_width 0.5)
			(island_removal_mode 0)
		)
		(polygon
			(pts
				(xy 82.348578 -53.034946) (xy 81.913476 -53.470048) (xy 78.863444 -53.470048) (xy 78.863444 -54.000146)
				(xy 78.895956 -54.032658) (xy 82.132424 -54.032658) (xy 82.605626 -54.50586) (xy 82.605626 -55.777638)
				(xy 83.818984 -56.990996) (xy 90.495628 -56.990996) (xy 90.813128 -56.673496) (xy 90.813128 -54.285896)
				(xy 89.562178 -53.034946)
			)
		)
	)
	(zone
		(net "P3V3_STBY_OUT")
		(layer "F.Cu")
		(hatch none 0.5)
		(connect_pads
			(clearance 0.5)
		)
		(min_thickness 0.25)
		(fill yes
			(thermal_gap 0.5)
			(thermal_bridge_width 0.5)
			(island_removal_mode 0)
		)
		(polygon
			(pts
				(xy 58.5724 -180.6956) (xy 58.3692 -180.8988) (xy 58.3692 -181.5084) (xy 58.1914 -181.6862) (xy 52.685696 -181.6862)
				(xy 51.796696 -182.5752) (xy 44.0436 -182.5752) (xy 43.894248 -182.724552) (xy 43.894248 -188.468)
				(xy 44.326048 -188.8998) (xy 59.4868 -188.8998) (xy 59.7916 -188.595) (xy 59.7916 -180.975) (xy 59.5122 -180.6956)
			)
		)
		(polygon
			(pts
				(xy 57.658 -182.2196) (xy 57.4548 -182.2196) (xy 57.4548 -182.4228) (xy 57.658 -182.4228)
			)
		)
		(polygon
			(pts
				(xy 57.0484 -182.2196) (xy 56.8452 -182.2196) (xy 56.8452 -182.4228) (xy 57.0484 -182.4228)
			)
		)
	)
	(zone
		(layer "F.Cu")
		(hatch none 0.5)
		(connect_pads
			(clearance 0)
		)
		(min_thickness 0.25)
		(keepout
			(tracks not_allowed)
			(vias allowed)
			(pads allowed)
			(copperpour not_allowed)
			(footprints allowed)
		)
		(placement
			(enabled no)
			(sheetname "")
		)
		(fill
			(thermal_gap 0.5)
			(thermal_bridge_width 0.5)
			(island_removal_mode 0)
		)
		(polygon
			(pts
				(arc
					(start 77.667358 -86.510368)
					(mid 77.283818 -86.126828)
					(end 76.900278 -86.510368)
				)
				(xy 76.900278 -86.712044) (xy 76.991972 -86.712044)
				(arc
					(start 76.996544 -86.71179)
					(mid 77.043007 -86.706418)
					(end 77.086968 -86.690454)
				)
				(arc
					(start 77.086968 -86.690454)
					(mid 77.402248 -86.271632)
					(end 77.258672 -86.775798)
				)
				(arc
					(start 77.258672 -86.775798)
					(mid 77.155348 -86.848004)
					(end 77.033882 -86.881716)
				)
				(xy 77.032104 -86.88324) (xy 77.006196 -86.88324) (xy 76.996544 -86.883494) (xy 76.991972 -86.88324)
				(xy 76.900278 -86.88324) (xy 76.900278 -87.02294) (xy 76.98867 -87.02294) (xy 76.993242 -87.02294)
				(xy 77.002894 -87.02294) (xy 77.028802 -87.02294)
				(arc
					(start 77.03058 -87.024718)
					(mid 77.154741 -87.059258)
					(end 77.259942 -87.133684)
				)
				(arc
					(start 77.259942 -87.133684)
					(mid 77.401375 -87.638822)
					(end 77.088238 -87.218012)
				)
				(arc
					(start 77.088238 -87.218012)
					(mid 77.042157 -87.200568)
					(end 76.993242 -87.194644)
				)
				(xy 76.98867 -87.194644) (xy 76.900278 -87.194644)
				(arc
					(start 76.900278 -87.399114)
					(mid 77.283691 -87.782908)
					(end 77.667358 -87.399368)
				)
			)
		)
	)
	(zone
		(layer "F.Cu")
		(hatch none 0.5)
		(connect_pads
			(clearance 0)
		)
		(min_thickness 0.25)
		(keepout
			(tracks allowed)
			(vias allowed)
			(pads allowed)
			(copperpour allowed)
			(footprints not_allowed)
		)
		(placement
			(enabled no)
			(sheetname "")
		)
		(fill
			(thermal_gap 0.5)
			(thermal_bridge_width 0.5)
			(island_removal_mode 0)
		)
		(polygon
			(pts
				(xy 73.429876 -113.199926) (xy 24.5999 -113.199926) (xy 24.5999 -129.519934) (xy 73.429876 -129.519934)
			)
		)
	)
	(zone
		(layer "F.Cu")
		(hatch none 0.5)
		(connect_pads
			(clearance 0)
		)
		(min_thickness 0.25)
		(keepout
			(tracks allowed)
			(vias allowed)
			(pads allowed)
			(copperpour allowed)
			(footprints allowed)
		)
		(placement
			(enabled no)
			(sheetname "")
		)
		(fill
			(thermal_gap 0.5)
			(thermal_bridge_width 0.5)
			(island_removal_mode 0)
		)
		(polygon
			(pts
				(xy 183.6928 -48.5902) (xy 183.6928 -46.355) (xy 184.404 -46.355) (xy 184.404 -48.5902)
			)
		)
	)
	(zone
		(layer "F.Cu")
		(hatch none 0.5)
		(connect_pads
			(clearance 0)
		)
		(min_thickness 0.25)
		(keepout
			(tracks not_allowed)
			(vias allowed)
			(pads allowed)
			(copperpour not_allowed)
			(footprints allowed)
		)
		(placement
			(enabled no)
			(sheetname "")
		)
		(fill
			(thermal_gap 0.5)
			(thermal_bridge_width 0.5)
			(island_removal_mode 0)
		)
		(polygon
			(pts
				(arc
					(start 78.49997 -35.299904)
					(mid 73.749916 -40.049958)
					(end 78.49997 -44.800012)
				)
				(xy 89.499948 -44.800012) (xy 89.499948 -35.299904)
			)
		)
	)
	(zone
		(layer "F.Cu")
		(hatch none 0.5)
		(connect_pads
			(clearance 0)
		)
		(min_thickness 0.25)
		(keepout
			(tracks allowed)
			(vias allowed)
			(pads allowed)
			(copperpour allowed)
			(footprints not_allowed)
		)
		(placement
			(enabled no)
			(sheetname "")
		)
		(fill
			(thermal_gap 0.5)
			(thermal_bridge_width 0.5)
			(island_removal_mode 0)
		)
		(polygon
			(pts
				(arc
					(start 227.24999 -187.999878)
					(mid 222.499936 -192.749932)
					(end 217.749882 -187.999878)
				)
				(arc
					(start 217.749882 -187.999878)
					(mid 222.499936 -183.249824)
					(end 227.24999 -187.999878)
				)
			)
		)
	)
	(zone
		(net "GND")
		(layer "F.Cu")
		(hatch none 0.5)
		(connect_pads
			(clearance 0.5)
		)
		(min_thickness 0.25)
		(fill yes
			(thermal_gap 0.5)
			(thermal_bridge_width 0.5)
			(island_removal_mode 0)
		)
		(polygon
			(pts
				(xy 48.166528 -178.655472) (xy 47.879 -178.943) (xy 47.879 -181.7116) (xy 48.387 -182.2196) (xy 51.689 -182.2196)
				(xy 52.5272 -181.3814) (xy 57.912 -181.3814) (xy 58.1406 -181.1528) (xy 58.1406 -179.0446) (xy 57.751472 -178.655472)
			)
		)
		(polygon
			(pts
				(xy 57.658 -180.6956) (xy 57.4548 -180.6956) (xy 57.4548 -180.8988) (xy 57.658 -180.8988)
			)
		)
		(polygon
			(pts
				(xy 57.0484 -180.6956) (xy 56.8452 -180.6956) (xy 56.8452 -180.8988) (xy 57.0484 -180.8988)
			)
		)
	)
	(zone
		(layer "F.Cu")
		(hatch none 0.5)
		(connect_pads
			(clearance 0)
		)
		(min_thickness 0.25)
		(keepout
			(tracks allowed)
			(vias allowed)
			(pads allowed)
			(copperpour allowed)
			(footprints allowed)
		)
		(placement
			(enabled no)
			(sheetname "")
		)
		(fill
			(thermal_gap 0.5)
			(thermal_bridge_width 0.5)
			(island_removal_mode 0)
		)
		(polygon
			(pts
				(xy 79.497428 -138.550904) (xy 79.497428 -138.792204) (xy 79.662528 -138.957304) (xy 81.313528 -138.957304)
				(xy 81.377028 -138.893804) (xy 81.377028 -138.436604) (xy 81.262728 -138.322304) (xy 81.021428 -138.322304)
				(xy 79.726028 -138.322304)
			)
		)
	)
	(zone
		(net "P3V3_STBY")
		(layer "F.Cu")
		(hatch none 0.5)
		(connect_pads
			(clearance 0.5)
		)
		(min_thickness 0.25)
		(fill yes
			(thermal_gap 0.5)
			(thermal_bridge_width 0.5)
			(island_removal_mode 0)
		)
		(polygon
			(pts
				(xy 95.123 -146.05) (xy 95.123 -146.3294) (xy 95.1992 -146.4056) (xy 95.6818 -146.4056) (xy 95.885 -146.6088)
				(xy 95.885 -147.701) (xy 96.012 -147.828) (xy 97.78492 -147.828) (xy 98.024696 -148.067776) (xy 98.457004 -148.067776)
				(xy 98.776282 -148.387308) (xy 98.776282 -149.244304) (xy 99.06 -149.528022) (xy 99.06 -154.299158)
				(xy 99.163632 -154.40279) (xy 99.737164 -154.40279) (xy 99.931728 -154.597354) (xy 99.931728 -156.035248)
				(xy 99.587558 -156.379418) (xy 99.236276 -156.379418) (xy 99.076256 -156.539438) (xy 99.076256 -157.632146)
				(xy 99.190302 -157.746192) (xy 99.809554 -157.746192) (xy 99.9744 -157.911038) (xy 99.9744 -158.93669)
				(xy 99.689412 -159.221678) (xy 99.128326 -159.221678) (xy 99.01936 -159.330644) (xy 99.01936 -162.071304)
				(xy 99.124008 -162.175952) (xy 100.708206 -162.175952) (xy 100.973382 -161.910776) (xy 100.973382 -149.124162)
				(xy 99.15652 -147.3073) (xy 98.0821 -147.3073) (xy 97.5106 -146.7358) (xy 97.5106 -146.05)
			)
		)
		(polygon
			(pts
				(xy 99.6823 -161.505392) (xy 99.4791 -161.505392) (xy 99.4791 -161.708592) (xy 99.6823 -161.708592)
			)
		)
		(polygon
			(pts
				(xy 99.691444 -159.710374) (xy 99.488244 -159.710374) (xy 99.488244 -159.913574) (xy 99.691444 -159.913574)
			)
		)
		(polygon
			(pts
				(xy 99.729544 -157.023054) (xy 99.526344 -157.023054) (xy 99.526344 -157.226254) (xy 99.729544 -157.226254)
			)
		)
		(polygon
			(pts
				(xy 99.7204 -153.5938) (xy 99.5172 -153.5938) (xy 99.5172 -153.797) (xy 99.7204 -153.797)
			)
		)
		(polygon
			(pts
				(xy 99.7204 -153.1112) (xy 99.5172 -153.1112) (xy 99.5172 -153.3144) (xy 99.7204 -153.3144)
			)
		)
		(polygon
			(pts
				(xy 99.7204 -152.5524) (xy 99.5172 -152.5524) (xy 99.5172 -152.7556) (xy 99.7204 -152.7556)
			)
		)
		(polygon
			(pts
				(xy 99.982782 -152.04186) (xy 99.779582 -152.04186) (xy 99.779582 -152.24506) (xy 99.982782 -152.24506)
			)
		)
		(polygon
			(pts
				(xy 99.423982 -152.04186) (xy 99.220782 -152.04186) (xy 99.220782 -152.24506) (xy 99.423982 -152.24506)
			)
		)
		(polygon
			(pts
				(xy 99.695 -149.928834) (xy 99.4918 -149.928834) (xy 99.4918 -150.132034) (xy 99.695 -150.132034)
			)
		)
		(polygon
			(pts
				(xy 99.695 -149.370034) (xy 99.4918 -149.370034) (xy 99.4918 -149.573234) (xy 99.695 -149.573234)
			)
		)
		(polygon
			(pts
				(xy 99.435666 -148.905722) (xy 99.232466 -148.905722) (xy 99.232466 -149.108922) (xy 99.435666 -149.108922)
			)
		)
		(polygon
			(pts
				(xy 97.5487 -147.296124) (xy 97.3455 -147.296124) (xy 97.3455 -147.499324) (xy 97.5487 -147.499324)
			)
		)
		(polygon
			(pts
				(xy 96.9899 -147.296124) (xy 96.7867 -147.296124) (xy 96.7867 -147.499324) (xy 96.9899 -147.499324)
			)
		)
		(polygon
			(pts
				(xy 96.4819 -147.296124) (xy 96.2787 -147.296124) (xy 96.2787 -147.499324) (xy 96.4819 -147.499324)
			)
		)
	)
	(zone
		(net "EXT1_CONN_GND")
		(layer "F.Cu")
		(hatch none 0.5)
		(connect_pads
			(clearance 0.5)
		)
		(min_thickness 0.25)
		(fill yes
			(thermal_gap 0.5)
			(thermal_bridge_width 0.5)
			(island_removal_mode 0)
		)
		(polygon
			(pts
				(xy 190.3476 -28.1686) (xy 190.0682 -28.448) (xy 190.0682 -32.385) (xy 190.4746 -32.7914) (xy 191.6938 -32.7914)
				(xy 191.8716 -32.6136) (xy 191.8716 -31.6992) (xy 192.151 -31.4198) (xy 192.532 -31.4198) (xy 192.9384 -31.0134)
				(xy 192.9384 -28.5242) (xy 192.5828 -28.1686)
			)
		)
		(polygon
			(pts
				(xy 191.41948 -32.31134) (xy 191.21628 -32.31134) (xy 191.21628 -32.51454) (xy 191.41948 -32.51454)
			)
		)
		(polygon
			(pts
				(xy 191.41948 -31.75254) (xy 191.21628 -31.75254) (xy 191.21628 -31.95574) (xy 191.41948 -31.95574)
			)
		)
	)
	(zone
		(layer "F.Cu")
		(hatch none 0.5)
		(connect_pads
			(clearance 0)
		)
		(min_thickness 0.25)
		(keepout
			(tracks not_allowed)
			(vias allowed)
			(pads allowed)
			(copperpour not_allowed)
			(footprints allowed)
		)
		(placement
			(enabled no)
			(sheetname "")
		)
		(fill
			(thermal_gap 0.5)
			(thermal_bridge_width 0.5)
			(island_removal_mode 0)
		)
		(polygon
			(pts
				(arc
					(start 199.084692 -88.728296)
					(mid 199.084692 -88.189308)
					(end 198.545704 -88.189308)
				)
				(xy 198.402194 -88.332818) (xy 198.465186 -88.39581)
				(arc
					(start 198.468488 -88.399112)
					(mid 198.505703 -88.428502)
					(end 198.548752 -88.448388)
				)
				(arc
					(start 198.548752 -88.448388)
					(mid 199.067604 -88.372819)
					(end 198.610474 -88.629744)
				)
				(arc
					(start 198.610474 -88.629744)
					(mid 198.485328 -88.60795)
					(end 198.374762 -88.545416)
				)
				(xy 198.372222 -88.545416) (xy 198.353934 -88.527382) (xy 198.347076 -88.520524) (xy 198.343774 -88.517222)
				(xy 198.281036 -88.45423) (xy 198.181976 -88.553036) (xy 198.244968 -88.615774) (xy 198.24827 -88.619076)
				(xy 198.255128 -88.625934) (xy 198.273162 -88.644222)
				(arc
					(start 198.273162 -88.646762)
					(mid 198.335823 -88.757312)
					(end 198.357744 -88.882474)
				)
				(arc
					(start 198.357744 -88.882474)
					(mid 198.10092 -89.3397)
					(end 198.176134 -88.820752)
				)
				(arc
					(start 198.176134 -88.820752)
					(mid 198.156245 -88.777705)
					(end 198.126858 -88.740488)
				)
				(xy 198.123556 -88.737186) (xy 198.060818 -88.674448)
				(arc
					(start 197.922134 -88.813132)
					(mid 197.915055 -89.354246)
					(end 198.456296 -89.356692)
				)
			)
		)
	)
	(zone
		(net "EXT2_CONN_GND")
		(layer "F.Cu")
		(hatch none 0.5)
		(connect_pads
			(clearance 0.5)
		)
		(min_thickness 0.25)
		(fill yes
			(thermal_gap 0.5)
			(thermal_bridge_width 0.5)
			(island_removal_mode 0)
		)
		(polygon
			(pts
				(xy 159.9692 -36.9316) (xy 159.6644 -37.2364) (xy 159.6644 -39.9034) (xy 160.0962 -40.3352) (xy 162.9918 -40.3352)
				(xy 163.2458 -40.0812) (xy 163.2458 -37.338) (xy 162.8394 -36.9316)
			)
		)
		(polygon
			(pts
				(xy 162.69716 -39.67734) (xy 162.49396 -39.67734) (xy 162.49396 -39.88054) (xy 162.69716 -39.88054)
			)
		)
		(polygon
			(pts
				(xy 162.13836 -39.67734) (xy 161.93516 -39.67734) (xy 161.93516 -39.88054) (xy 162.13836 -39.88054)
			)
		)
	)
	(zone
		(net "P12V_STBY")
		(layer "F.Cu")
		(hatch none 0.5)
		(connect_pads
			(clearance 0.5)
		)
		(min_thickness 0.25)
		(fill yes
			(thermal_gap 0.5)
			(thermal_bridge_width 0.5)
			(island_removal_mode 0)
		)
		(polygon
			(pts
				(xy 19.780504 -182.340758) (xy 19.466052 -182.65521) (xy 19.466052 -184.316878) (xy 19.7104 -184.561226)
				(xy 22.987762 -184.561226) (xy 23.021798 -184.52719) (xy 23.021798 -182.509414) (xy 23.013162 -182.509414)
				(xy 22.844506 -182.340758)
			)
		)
		(polygon
			(pts
				(xy 21.8567 -184.1627) (xy 21.6535 -184.1627) (xy 21.6535 -184.3659) (xy 21.8567 -184.3659)
			)
		)
		(polygon
			(pts
				(xy 21.8567 -182.7657) (xy 21.6535 -182.7657) (xy 21.6535 -182.9689) (xy 21.8567 -182.9689)
			)
		)
	)
	(zone
		(layer "F.Cu")
		(hatch none 0.5)
		(connect_pads
			(clearance 0)
		)
		(min_thickness 0.25)
		(keepout
			(tracks allowed)
			(vias allowed)
			(pads allowed)
			(copperpour allowed)
			(footprints not_allowed)
		)
		(placement
			(enabled no)
			(sheetname "")
		)
		(fill
			(thermal_gap 0.5)
			(thermal_bridge_width 0.5)
			(island_removal_mode 0)
		)
		(polygon
			(pts
				(arc
					(start 17.249902 -187.999878)
					(mid 12.500102 -192.749678)
					(end 7.750048 -187.999878)
				)
				(arc
					(start 7.750048 -187.999878)
					(mid 12.500102 -183.249824)
					(end 17.249902 -187.999878)
				)
			)
		)
	)
	(zone
		(layer "F.Cu")
		(hatch none 0.5)
		(connect_pads
			(clearance 0)
		)
		(min_thickness 0.25)
		(keepout
			(tracks not_allowed)
			(vias allowed)
			(pads allowed)
			(copperpour not_allowed)
			(footprints allowed)
		)
		(placement
			(enabled no)
			(sheetname "")
		)
		(fill
			(thermal_gap 0.5)
			(thermal_bridge_width 0.5)
			(island_removal_mode 0)
		)
		(polygon
			(pts
				(arc
					(start 212.306154 -65.828926)
					(mid 212.306154 -65.290446)
					(end 211.767674 -65.290446)
				)
				(xy 211.76742 -65.290192) (xy 211.559902 -65.49771)
				(arc
					(start 211.740496 -65.678304)
					(mid 211.769992 -65.692743)
					(end 211.802218 -65.686178)
				)
				(arc
					(start 211.802218 -65.686178)
					(mid 212.226039 -65.371765)
					(end 211.908898 -65.79362)
				)
				(xy 211.896198 -65.80632)
				(arc
					(start 211.892134 -65.80632)
					(mid 211.77631 -65.843128)
					(end 211.660486 -65.80632)
				)
				(xy 211.656422 -65.80632) (xy 211.45373 -65.603882) (xy 211.272374 -65.785238) (xy 211.474812 -65.987676)
				(arc
					(start 211.474812 -65.99174)
					(mid 211.511766 -66.107714)
					(end 211.474812 -66.223642)
				)
				(xy 211.474812 -66.227706)
				(arc
					(start 211.46262 -66.239898)
					(mid 211.040198 -66.556697)
					(end 211.355178 -66.132964)
				)
				(arc
					(start 211.355178 -66.132964)
					(mid 211.361363 -66.100933)
					(end 211.346796 -66.07175)
				)
				(xy 211.166456 -65.891156) (xy 210.959192 -66.09842)
				(arc
					(start 210.959446 -66.098674)
					(mid 210.959446 -66.637154)
					(end 211.497926 -66.637154)
				)
				(xy 211.49818 -66.637408) (xy 212.306154 -65.82918)
			)
		)
	)
	(zone
		(net "GND")
		(layer "F.Cu")
		(hatch none 0.5)
		(connect_pads
			(clearance 0.5)
		)
		(min_thickness 0.25)
		(fill yes
			(thermal_gap 0.5)
			(thermal_bridge_width 0.5)
			(island_removal_mode 0)
		)
		(polygon
			(pts
				(xy 158.538672 -135.821674) (xy 158.538672 -137.50163) (xy 160.060894 -137.50163) (xy 160.060894 -135.821674)
			)
		)
	)
	(zone
		(layer "F.Cu")
		(hatch none 0.5)
		(connect_pads
			(clearance 0)
		)
		(min_thickness 0.25)
		(keepout
			(tracks allowed)
			(vias allowed)
			(pads allowed)
			(copperpour allowed)
			(footprints not_allowed)
		)
		(placement
			(enabled no)
			(sheetname "")
		)
		(fill
			(thermal_gap 0.5)
			(thermal_bridge_width 0.5)
			(island_removal_mode 0)
		)
		(polygon
			(pts
				(arc
					(start 22.750018 -120.000014)
					(mid 17.999964 -124.750068)
					(end 13.24991 -120.000014)
				)
				(arc
					(start 13.24991 -120.000014)
					(mid 17.999964 -115.24996)
					(end 22.750018 -120.000014)
				)
			)
		)
	)
	(zone
		(layer "F.Cu")
		(hatch none 0.5)
		(connect_pads
			(clearance 0)
		)
		(min_thickness 0.25)
		(keepout
			(tracks not_allowed)
			(vias allowed)
			(pads allowed)
			(copperpour not_allowed)
			(footprints allowed)
		)
		(placement
			(enabled no)
			(sheetname "")
		)
		(fill
			(thermal_gap 0.5)
			(thermal_bridge_width 0.5)
			(island_removal_mode 0)
		)
		(polygon
			(pts
				(xy 11.8999 -109.799882) (xy 11.8999 -103.799894)
				(arc
					(start 18.317464 -103.799894)
					(mid 26.674651 -102.166784)
					(end 22.899878 -109.799882)
				)
			)
		)
	)
	(zone
		(net "P12V_STBY")
		(layer "F.Cu")
		(hatch none 0.5)
		(connect_pads
			(clearance 0.5)
		)
		(min_thickness 0.25)
		(fill yes
			(thermal_gap 0.5)
			(thermal_bridge_width 0.5)
			(island_removal_mode 0)
		)
		(polygon
			(pts
				(xy 177.596546 -104.538526) (xy 176.956212 -105.17886) (xy 176.956212 -109.409738) (xy 177.503328 -109.956854)
				(xy 180.481986 -109.956854) (xy 180.613812 -109.825028) (xy 181.180232 -109.258354) (xy 181.180232 -104.874314)
				(xy 180.844444 -104.538526)
			)
		)
	)
	(zone
		(net "GND")
		(layer "F.Cu")
		(hatch none 0.5)
		(connect_pads
			(clearance 0.5)
		)
		(min_thickness 0.25)
		(fill yes
			(thermal_gap 0.5)
			(thermal_bridge_width 0.5)
			(island_removal_mode 0)
		)
		(polygon
			(pts
				(xy 154.514804 -118.305072) (xy 153.676858 -119.143018) (xy 153.676858 -122.745754) (xy 154.098244 -123.16714)
				(xy 156.627068 -123.16714) (xy 156.948124 -122.846084) (xy 156.948124 -118.36273) (xy 156.890466 -118.305072)
			)
		)
		(polygon
			(pts
				(xy 156.4386 -118.8212) (xy 156.2354 -118.8212) (xy 156.2354 -119.0244) (xy 156.4386 -119.0244)
			)
		)
	)
	(zone
		(net "GND")
		(layer "F.Cu")
		(hatch none 0.5)
		(connect_pads
			(clearance 0.5)
		)
		(min_thickness 0.25)
		(fill yes
			(thermal_gap 0.5)
			(thermal_bridge_width 0.5)
			(island_removal_mode 0)
		)
		(polygon
			(pts
				(xy 164.554408 -160.465008) (xy 162.4584 -162.56127) (xy 162.4584 -176.5046) (xy 166.1922 -180.2384)
				(xy 168.4782 -180.2384) (xy 168.9608 -179.7558) (xy 168.9608 -161.2138) (xy 168.212008 -160.465008)
			)
		)
	)
	(zone
		(layer "F.Cu")
		(hatch none 0.5)
		(connect_pads
			(clearance 0)
		)
		(min_thickness 0.25)
		(keepout
			(tracks allowed)
			(vias allowed)
			(pads allowed)
			(copperpour allowed)
			(footprints not_allowed)
		)
		(placement
			(enabled no)
			(sheetname "")
		)
		(fill
			(thermal_gap 0.5)
			(thermal_bridge_width 0.5)
			(island_removal_mode 0)
		)
		(polygon
			(pts
				(arc
					(start 22.800056 -65.300098)
					(mid 27.55011 -60.550044)
					(end 22.800056 -55.79999)
				)
				(xy 8.64997 -55.79999) (xy 8.64997 -65.300098)
			)
		)
	)
	(zone
		(layer "F.Cu")
		(hatch none 0.5)
		(connect_pads
			(clearance 0)
		)
		(min_thickness 0.25)
		(keepout
			(tracks not_allowed)
			(vias allowed)
			(pads allowed)
			(copperpour not_allowed)
			(footprints allowed)
		)
		(placement
			(enabled no)
			(sheetname "")
		)
		(fill
			(thermal_gap 0.5)
			(thermal_bridge_width 0.5)
			(island_removal_mode 0)
		)
		(polygon
			(pts
				(arc
					(start 207.941672 -71.5264)
					(mid 207.960368 -71.548802)
					(end 207.967072 -71.5772)
				)
				(arc
					(start 207.967072 -71.7804)
					(mid 207.960368 -71.808798)
					(end 207.941672 -71.8312)
				)
				(arc
					(start 208.170272 -71.8312)
					(mid 208.151576 -71.808798)
					(end 208.144872 -71.7804)
				)
				(arc
					(start 208.144872 -71.5772)
					(mid 208.151576 -71.548802)
					(end 208.170272 -71.5264)
				)
			)
		)
	)
	(zone
		(layer "F.Cu")
		(hatch none 0.5)
		(connect_pads
			(clearance 0)
		)
		(min_thickness 0.25)
		(keepout
			(tracks not_allowed)
			(vias allowed)
			(pads allowed)
			(copperpour not_allowed)
			(footprints allowed)
		)
		(placement
			(enabled no)
			(sheetname "")
		)
		(fill
			(thermal_gap 0.5)
			(thermal_bridge_width 0.5)
			(island_removal_mode 0)
		)
		(polygon
			(pts
				(arc
					(start 214.795354 -72.255126)
					(mid 214.795354 -71.716646)
					(end 214.256874 -71.716646)
				)
				(xy 214.25662 -71.716392) (xy 214.04961 -71.923402)
				(arc
					(start 214.192104 -72.065896)
					(mid 214.233894 -72.09156)
					(end 214.282782 -72.09536)
				)
				(arc
					(start 214.282782 -72.09536)
					(mid 214.724861 -71.808077)
					(end 214.389208 -72.21474)
				)
				(arc
					(start 214.389208 -72.21474)
					(mid 214.247031 -72.245825)
					(end 214.111078 -72.193912)
				)
				(xy 214.10803 -72.193912) (xy 213.943438 -72.029574) (xy 213.762082 -72.21093) (xy 213.92642 -72.375268)
				(arc
					(start 213.92642 -72.378316)
					(mid 213.978294 -72.514838)
					(end 213.94674 -72.657462)
				)
				(arc
					(start 213.94674 -72.657462)
					(mid 213.53991 -72.992631)
					(end 213.827614 -72.551036)
				)
				(arc
					(start 213.827614 -72.551036)
					(mid 213.824132 -72.50165)
					(end 213.798404 -72.459342)
				)
				(xy 213.656164 -72.316848) (xy 213.448392 -72.52462)
				(arc
					(start 213.448646 -72.524874)
					(mid 213.448646 -73.063354)
					(end 213.987126 -73.063354)
				)
				(xy 213.98738 -73.063608) (xy 214.795354 -72.25538)
			)
		)
	)
	(zone
		(net "GND")
		(layer "F.Cu")
		(hatch none 0.5)
		(connect_pads
			(clearance 0.5)
		)
		(min_thickness 0.25)
		(fill yes
			(thermal_gap 0.5)
			(thermal_bridge_width 0.5)
			(island_removal_mode 0)
		)
		(polygon
			(pts
				(xy 23.020528 -186.9313) (xy 22.7838 -187.168028) (xy 22.7838 -189.611) (xy 22.83841 -189.66561)
				(xy 32.329374 -189.66561) (xy 32.512762 -189.482222) (xy 32.512762 -187.36056) (xy 32.469836 -187.317634)
				(xy 30.861254 -187.317634) (xy 30.47492 -186.9313)
			)
		)
	)
	(zone
		(layer "F.Cu")
		(hatch none 0.5)
		(connect_pads
			(clearance 0)
		)
		(min_thickness 0.25)
		(keepout
			(tracks allowed)
			(vias allowed)
			(pads allowed)
			(copperpour allowed)
			(footprints not_allowed)
		)
		(placement
			(enabled no)
			(sheetname "")
		)
		(fill
			(thermal_gap 0.5)
			(thermal_bridge_width 0.5)
			(island_removal_mode 0)
		)
		(polygon
			(pts
				(arc
					(start 227.24999 -110.000034)
					(mid 222.499936 -114.750088)
					(end 217.749882 -110.000034)
				)
				(arc
					(start 217.749882 -110.000034)
					(mid 222.499936 -105.24998)
					(end 227.24999 -110.000034)
				)
			)
		)
	)
	(zone
		(layer "F.Cu")
		(hatch none 0.5)
		(connect_pads
			(clearance 0)
		)
		(min_thickness 0.25)
		(keepout
			(tracks allowed)
			(vias allowed)
			(pads allowed)
			(copperpour allowed)
			(footprints not_allowed)
		)
		(placement
			(enabled no)
			(sheetname "")
		)
		(fill
			(thermal_gap 0.5)
			(thermal_bridge_width 0.5)
			(island_removal_mode 0)
		)
		(polygon
			(pts
				(xy 11.8999 -109.799882) (xy 11.8999 -103.799894)
				(arc
					(start 18.317464 -103.799894)
					(mid 26.674651 -102.166784)
					(end 22.899878 -109.799882)
				)
			)
		)
	)
	(zone
		(net "P3V3_STBY")
		(layer "F.Cu")
		(hatch none 0.5)
		(connect_pads
			(clearance 0.5)
		)
		(min_thickness 0.25)
		(fill yes
			(thermal_gap 0.5)
			(thermal_bridge_width 0.5)
			(island_removal_mode 0)
		)
		(polygon
			(pts
				(xy 77.04328 -181.48808) (xy 76.91628 -181.61508) (xy 76.91628 -182.03418) (xy 76.63688 -182.31358)
				(xy 74.90968 -182.31358) (xy 74.90968 -186.14517) (xy 75.110086 -186.345576) (xy 79.105506 -186.345576)
				(xy 79.58328 -185.867802) (xy 79.58328 -181.58968) (xy 79.48168 -181.48808)
			)
		)
		(polygon
			(pts
				(xy 78.969616 -181.99608) (xy 78.766416 -181.99608) (xy 78.766416 -182.19928) (xy 78.969616 -182.19928)
			)
		)
	)
	(zone
		(layer "F.Cu")
		(hatch none 0.5)
		(connect_pads
			(clearance 0)
		)
		(min_thickness 0.25)
		(keepout
			(tracks not_allowed)
			(vias allowed)
			(pads allowed)
			(copperpour not_allowed)
			(footprints allowed)
		)
		(placement
			(enabled no)
			(sheetname "")
		)
		(fill
			(thermal_gap 0.5)
			(thermal_bridge_width 0.5)
			(island_removal_mode 0)
		)
		(polygon
			(pts
				(arc
					(start 7.750048 -187.999878)
					(mid 12.500102 -183.249824)
					(end 17.249902 -187.999878)
				)
				(arc
					(start 17.249902 -187.999878)
					(mid 12.500102 -192.749678)
					(end 7.750048 -187.999878)
				)
			)
		)
	)
	(zone
		(net "MB0_CM_GATE_R")
		(layer "F.Cu")
		(hatch none 0.5)
		(connect_pads
			(clearance 0.5)
		)
		(min_thickness 0.25)
		(fill yes
			(thermal_gap 0.5)
			(thermal_bridge_width 0.5)
			(island_removal_mode 0)
		)
		(polygon
			(pts
				(xy 129.76733 -4.481068) (xy 129.65684 -4.591558) (xy 129.65684 -6.15188) (xy 129.3241 -6.48462)
				(xy 128.49098 -6.48462) (xy 128.4224 -6.5532) (xy 128.4224 -7.5184) (xy 128.4986 -7.5946) (xy 129.131314 -7.5946)
				(xy 129.300224 -7.76351) (xy 129.300224 -11.446256) (xy 129.347468 -11.4935) (xy 130.450336 -11.4935)
				(xy 130.464306 -11.47953) (xy 130.464306 -7.524242) (xy 130.83286 -7.155688) (xy 130.83286 -6.0452)
				(xy 130.85826 -6.0198) (xy 130.85826 -4.693666) (xy 130.645662 -4.481068)
			)
		)
	)
	(zone
		(layer "F.Cu")
		(hatch none 0.5)
		(connect_pads
			(clearance 0)
		)
		(min_thickness 0.25)
		(keepout
			(tracks allowed)
			(vias allowed)
			(pads allowed)
			(copperpour allowed)
			(footprints allowed)
		)
		(placement
			(enabled no)
			(sheetname "")
		)
		(fill
			(thermal_gap 0.5)
			(thermal_bridge_width 0.5)
			(island_removal_mode 0)
		)
		(polygon
			(pts
				(xy 207.42402 -68.614798) (xy 207.42402 -67.497198) (xy 208.71942 -67.497198) (xy 208.71942 -68.614798)
			)
		)
	)
	(zone
		(net "GND")
		(layer "F.Cu")
		(hatch none 0.5)
		(connect_pads
			(clearance 0.5)
		)
		(min_thickness 0.25)
		(fill yes
			(thermal_gap 0.5)
			(thermal_bridge_width 0.5)
			(island_removal_mode 0)
		)
		(polygon
			(pts
				(xy 166.411402 -103.264462) (xy 166.1414 -103.534464) (xy 166.1414 -112.6744) (xy 166.4208 -112.9538)
				(xy 168.3258 -112.9538) (xy 168.4528 -112.8268) (xy 168.4528 -112.0902) (xy 168.2496 -111.887) (xy 168.2496 -109.7534)
				(xy 168.529 -109.474) (xy 168.529 -103.602536) (xy 168.190926 -103.264462)
			)
		)
		(polygon
			(pts
				(xy 168.021 -112.1918) (xy 167.8178 -112.1918) (xy 167.8178 -112.395) (xy 168.021 -112.395)
			)
		)
		(polygon
			(pts
				(xy 167.9702 -109.4486) (xy 167.767 -109.4486) (xy 167.767 -109.6518) (xy 167.9702 -109.6518)
			)
		)
		(polygon
			(pts
				(xy 167.9702 -108.7374) (xy 167.767 -108.7374) (xy 167.767 -108.9406) (xy 167.9702 -108.9406)
			)
		)
		(polygon
			(pts
				(xy 167.9702 -108.4072) (xy 167.767 -108.4072) (xy 167.767 -108.6104) (xy 167.9702 -108.6104)
			)
		)
		(polygon
			(pts
				(xy 167.9702 -107.696) (xy 167.767 -107.696) (xy 167.767 -107.8992) (xy 167.9702 -107.8992)
			)
		)
		(polygon
			(pts
				(xy 167.9702 -107.3658) (xy 167.767 -107.3658) (xy 167.767 -107.569) (xy 167.9702 -107.569)
			)
		)
		(polygon
			(pts
				(xy 167.9702 -106.6546) (xy 167.767 -106.6546) (xy 167.767 -106.8578) (xy 167.9702 -106.8578)
			)
		)
		(polygon
			(pts
				(xy 167.9702 -106.3244) (xy 167.767 -106.3244) (xy 167.767 -106.5276) (xy 167.9702 -106.5276)
			)
		)
		(polygon
			(pts
				(xy 167.9702 -105.6132) (xy 167.767 -105.6132) (xy 167.767 -105.8164) (xy 167.9702 -105.8164)
			)
		)
		(polygon
			(pts
				(xy 167.9702 -105.283) (xy 167.767 -105.283) (xy 167.767 -105.4862) (xy 167.9702 -105.4862)
			)
		)
		(polygon
			(pts
				(xy 167.9702 -104.5718) (xy 167.767 -104.5718) (xy 167.767 -104.775) (xy 167.9702 -104.775)
			)
		)
		(polygon
			(pts
				(xy 167.9702 -104.2416) (xy 167.767 -104.2416) (xy 167.767 -104.4448) (xy 167.9702 -104.4448)
			)
		)
		(polygon
			(pts
				(xy 167.9702 -103.5304) (xy 167.767 -103.5304) (xy 167.767 -103.7336) (xy 167.9702 -103.7336)
			)
		)
	)
	(zone
		(net "GND")
		(layer "F.Cu")
		(hatch none 0.5)
		(connect_pads
			(clearance 0.5)
		)
		(min_thickness 0.25)
		(fill yes
			(thermal_gap 0.5)
			(thermal_bridge_width 0.5)
			(island_removal_mode 0)
		)
		(polygon
			(pts
				(xy 87.622888 -47.859696) (xy 87.503 -47.979584) (xy 87.503 -49.449228) (xy 87.544148 -49.490376)
				(xy 88.900508 -49.490376) (xy 89.116408 -49.274476) (xy 89.116408 -48.022256) (xy 88.953848 -47.859696)
			)
		)
		(polygon
			(pts
				(xy 88.170766 -48.813212) (xy 87.967566 -48.813212) (xy 87.967566 -49.016412) (xy 88.170766 -49.016412)
			)
		)
		(polygon
			(pts
				(xy 88.2142 -48.431196) (xy 88.011 -48.431196) (xy 88.011 -48.634396) (xy 88.2142 -48.634396)
			)
		)
	)
	(zone
		(layer "F.Cu")
		(hatch none 0.5)
		(connect_pads
			(clearance 0)
		)
		(min_thickness 0.25)
		(keepout
			(tracks not_allowed)
			(vias allowed)
			(pads allowed)
			(copperpour not_allowed)
			(footprints allowed)
		)
		(placement
			(enabled no)
			(sheetname "")
		)
		(fill
			(thermal_gap 0.5)
			(thermal_bridge_width 0.5)
			(island_removal_mode 0)
		)
		(polygon
			(pts
				(arc
					(start 213.779354 -67.479926)
					(mid 213.779354 -66.941446)
					(end 213.240874 -66.941446)
				)
				(xy 213.24062 -66.941192) (xy 213.03361 -67.148202)
				(arc
					(start 213.176104 -67.290696)
					(mid 213.217894 -67.31636)
					(end 213.266782 -67.32016)
				)
				(arc
					(start 213.266782 -67.32016)
					(mid 213.708861 -67.032877)
					(end 213.373208 -67.43954)
				)
				(arc
					(start 213.373208 -67.43954)
					(mid 213.231031 -67.470625)
					(end 213.095078 -67.418712)
				)
				(xy 213.09203 -67.418712) (xy 212.927438 -67.254374) (xy 212.746082 -67.43573) (xy 212.910674 -67.600322)
				(arc
					(start 212.910674 -67.60337)
					(mid 212.962644 -67.73978)
					(end 212.930994 -67.882262)
				)
				(arc
					(start 212.930994 -67.882262)
					(mid 212.524198 -68.21789)
					(end 212.811868 -67.775836)
				)
				(arc
					(start 212.811868 -67.775836)
					(mid 212.808402 -67.726557)
					(end 212.782658 -67.684396)
				)
				(xy 212.640164 -67.541648) (xy 212.432392 -67.74942)
				(arc
					(start 212.432646 -67.749674)
					(mid 212.432646 -68.288154)
					(end 212.971126 -68.288154)
				)
				(xy 212.97138 -68.288408) (xy 213.779354 -67.48018)
			)
		)
	)
	(zone
		(net "GND")
		(layer "F.Cu")
		(hatch none 0.5)
		(connect_pads
			(clearance 0.5)
		)
		(min_thickness 0.25)
		(fill yes
			(thermal_gap 0.5)
			(thermal_bridge_width 0.5)
			(island_removal_mode 0)
		)
		(polygon
			(pts
				(xy 82.5246 -172.0342) (xy 82.4484 -172.1104) (xy 82.4484 -172.6438) (xy 82.804 -172.9994) (xy 82.804 -173.222666)
				(xy 82.834734 -173.2534) (xy 82.834734 -176.306734) (xy 82.9056 -176.3776) (xy 83.2739 -176.3776)
				(xy 83.6676 -176.7713) (xy 83.6676 -178.5874) (xy 83.448398 -178.806602) (xy 79.018384 -178.806602)
				(xy 78.833726 -178.99126) (xy 78.833726 -179.164234) (xy 78.46568 -179.53228) (xy 76.73848 -179.53228)
				(xy 76.73848 -178.77028) (xy 76.708 -178.7398) (xy 73.43648 -178.7398) (xy 73.43648 -179.37988)
				(xy 73.27138 -179.54498) (xy 70.80758 -179.54498) (xy 70.66788 -179.68468) (xy 70.66788 -180.95468)
				(xy 70.87108 -181.15788) (xy 73.46188 -181.15788) (xy 73.48728 -181.18328) (xy 73.48728 -181.99608)
				(xy 76.71308 -181.99608) (xy 76.71308 -181.23408) (xy 76.76388 -181.18328) (xy 84.790788 -181.18328)
				(xy 85.615272 -180.358796) (xy 85.615272 -173.286928) (xy 84.362544 -172.0342)
			)
		)
		(polygon
			(pts
				(xy 79.579216 -180.47208) (xy 79.376016 -180.47208) (xy 79.376016 -180.67528) (xy 79.579216 -180.67528)
			)
		)
		(polygon
			(pts
				(xy 78.969616 -180.47208) (xy 78.766416 -180.47208) (xy 78.766416 -180.67528) (xy 78.969616 -180.67528)
			)
		)
	)
	(zone
		(net "AGND_CURRENT_MON")
		(layer "F.Cu")
		(hatch none 0.5)
		(connect_pads
			(clearance 0.5)
		)
		(min_thickness 0.25)
		(fill yes
			(thermal_gap 0.5)
			(thermal_bridge_width 0.5)
			(island_removal_mode 0)
		)
		(polygon
			(pts
				(xy 110.8202 -5.298694) (xy 109.5756 -6.543294) (xy 109.5756 -14.762734) (xy 111.043466 -16.2306)
				(xy 116.0272 -16.2306) (xy 116.1034 -16.1544) (xy 116.1034 -15.2654) (xy 115.951 -15.113) (xy 111.461042 -15.113)
				(xy 111.461042 -15.10919) (xy 111.289846 -14.937994) (xy 111.289846 -14.038326) (xy 110.987078 -13.735558)
				(xy 110.987078 -10.465308) (xy 110.5662 -10.04443) (xy 110.5662 -8.9662) (xy 110.617 -8.9154) (xy 111.8108 -8.9154)
				(xy 112.0902 -9.1948) (xy 112.0902 -9.8806) (xy 112.1918 -9.9822) (xy 112.649 -9.9822) (xy 112.6998 -9.9314)
				(xy 112.6998 -5.4102) (xy 112.596168 -5.306568) (xy 112.173258 -5.306568) (xy 112.165384 -5.298694)
			)
		)
		(polygon
			(pts
				(xy 110.840774 -14.642338) (xy 110.637574 -14.642338) (xy 110.637574 -14.845538) (xy 110.840774 -14.845538)
			)
		)
		(polygon
			(pts
				(xy 110.840774 -14.083538) (xy 110.637574 -14.083538) (xy 110.637574 -14.286738) (xy 110.840774 -14.286738)
			)
		)
		(polygon
			(pts
				(xy 110.0328 -13.654278) (xy 109.8296 -13.654278) (xy 109.8296 -13.857478) (xy 110.0328 -13.857478)
			)
		)
		(polygon
			(pts
				(xy 110.0328 -12.790678) (xy 109.8296 -12.790678) (xy 109.8296 -12.993878) (xy 110.0328 -12.993878)
			)
		)
		(polygon
			(pts
				(xy 110.0328 -12.409678) (xy 109.8296 -12.409678) (xy 109.8296 -12.612878) (xy 110.0328 -12.612878)
			)
		)
		(polygon
			(pts
				(xy 110.0328 -11.546078) (xy 109.8296 -11.546078) (xy 109.8296 -11.749278) (xy 110.0328 -11.749278)
			)
		)
		(polygon
			(pts
				(xy 110.0328 -11.165078) (xy 109.8296 -11.165078) (xy 109.8296 -11.368278) (xy 110.0328 -11.368278)
			)
		)
		(polygon
			(pts
				(xy 110.0328 -10.301478) (xy 109.8296 -10.301478) (xy 109.8296 -10.504678) (xy 110.0328 -10.504678)
			)
		)
		(polygon
			(pts
				(xy 110.10519 -9.844278) (xy 109.90199 -9.844278) (xy 109.90199 -10.047478) (xy 110.10519 -10.047478)
			)
		)
		(polygon
			(pts
				(xy 110.10519 -9.285478) (xy 109.90199 -9.285478) (xy 109.90199 -9.488678) (xy 110.10519 -9.488678)
			)
		)
		(polygon
			(pts
				(xy 112.20069 -8.320278) (xy 111.99749 -8.320278) (xy 111.99749 -8.523478) (xy 112.20069 -8.523478)
			)
		)
		(polygon
			(pts
				(xy 112.26419 -7.913878) (xy 112.06099 -7.913878) (xy 112.06099 -8.117078) (xy 112.26419 -8.117078)
			)
		)
		(polygon
			(pts
				(xy 112.26419 -7.355078) (xy 112.06099 -7.355078) (xy 112.06099 -7.558278) (xy 112.26419 -7.558278)
			)
		)
		(polygon
			(pts
				(xy 112.26419 -6.821678) (xy 112.06099 -6.821678) (xy 112.06099 -7.024878) (xy 112.26419 -7.024878)
			)
		)
		(polygon
			(pts
				(xy 112.26419 -6.262878) (xy 112.06099 -6.262878) (xy 112.06099 -6.466078) (xy 112.26419 -6.466078)
			)
		)
		(polygon
			(pts
				(xy 112.23879 -5.754878) (xy 112.03559 -5.754878) (xy 112.03559 -5.958078) (xy 112.23879 -5.958078)
			)
		)
	)
	(zone
		(net "P1V8_STBY_VBST")
		(layer "F.Cu")
		(hatch none 0.5)
		(connect_pads
			(clearance 0.5)
		)
		(min_thickness 0.25)
		(fill yes
			(thermal_gap 0.5)
			(thermal_bridge_width 0.5)
			(island_removal_mode 0)
		)
		(polygon
			(pts
				(xy 162.3568 -133.1214) (xy 162.2552 -133.223) (xy 161.2646 -133.223) (xy 159.893 -134.5946) (xy 159.893 -135.4836)
				(xy 159.894778 -135.4836) (xy 159.894778 -135.564372) (xy 159.90697 -135.576564) (xy 160.187386 -135.576564)
				(xy 160.20415 -135.5598) (xy 160.20415 -135.45185) (xy 161.544 -134.112) (xy 162.433 -134.112) (xy 162.8902 -133.6548)
				(xy 162.8902 -133.1468) (xy 162.8648 -133.1214)
			)
		)
		(polygon
			(pts
				(xy 162.42284 -133.589522) (xy 162.21964 -133.589522) (xy 162.21964 -133.792722) (xy 162.42284 -133.792722)
			)
		)
	)
	(zone
		(net "P5V_LL")
		(layer "F.Cu")
		(hatch none 0.5)
		(connect_pads
			(clearance 0.5)
		)
		(min_thickness 0.25)
		(fill yes
			(thermal_gap 0.5)
			(thermal_bridge_width 0.5)
			(island_removal_mode 0)
		)
		(polygon
			(pts
				(xy 175.2346 -148.61921) (xy 175.2346 -148.8186) (xy 174.5742 -149.479) (xy 171.402248 -149.479)
				(xy 170.919648 -149.9616) (xy 170.919648 -154.0002) (xy 170.970448 -154.051) (xy 177.9778 -154.051)
				(xy 178.127152 -153.901648) (xy 178.127152 -148.74621) (xy 178.000152 -148.61921)
			)
		)
		(polygon
			(pts
				(xy 172.159676 -149.994366) (xy 171.956476 -149.994366) (xy 171.956476 -150.197566) (xy 172.159676 -150.197566)
			)
		)
		(polygon
			(pts
				(xy 171.550076 -149.994366) (xy 171.346876 -149.994366) (xy 171.346876 -150.197566) (xy 171.550076 -150.197566)
			)
		)
	)
	(zone
		(net "GND")
		(layer "F.Cu")
		(hatch none 0.5)
		(connect_pads
			(clearance 0.5)
		)
		(min_thickness 0.25)
		(fill yes
			(thermal_gap 0.5)
			(thermal_bridge_width 0.5)
			(island_removal_mode 0)
		)
		(polygon
			(pts
				(xy 194.14744 -29.3497) (xy 194.05346 -29.44368) (xy 194.05346 -31.11754) (xy 193.42862 -31.74238)
				(xy 192.29832 -31.74238) (xy 192.19545 -31.84525) (xy 192.19545 -32.83077) (xy 192.59804 -33.23336)
				(xy 195.86194 -33.23336) (xy 196.01434 -33.08096) (xy 196.01434 -29.85262) (xy 195.51142 -29.3497)
			)
		)
		(polygon
			(pts
				(xy 192.84188 -32.31134) (xy 192.63868 -32.31134) (xy 192.63868 -32.51454) (xy 192.84188 -32.51454)
			)
		)
	)
	(zone
		(layer "F.Cu")
		(hatch none 0.5)
		(connect_pads
			(clearance 0)
		)
		(min_thickness 0.25)
		(keepout
			(tracks allowed)
			(vias allowed)
			(pads allowed)
			(copperpour allowed)
			(footprints not_allowed)
		)
		(placement
			(enabled no)
			(sheetname "")
		)
		(fill
			(thermal_gap 0.5)
			(thermal_bridge_width 0.5)
			(island_removal_mode 0)
		)
		(polygon
			(pts
				(arc
					(start 87.749888 -187.999878)
					(mid 92.499942 -183.249824)
					(end 97.249996 -187.999878)
				)
				(arc
					(start 97.249996 -187.999878)
					(mid 92.499942 -192.749932)
					(end 87.749888 -187.999878)
				)
			)
		)
	)
	(zone
		(net "GND")
		(layer "F.Cu")
		(hatch none 0.5)
		(connect_pads
			(clearance 0.5)
		)
		(min_thickness 0.25)
		(fill yes
			(thermal_gap 0.5)
			(thermal_bridge_width 0.5)
			(island_removal_mode 0)
		)
		(polygon
			(pts
				(xy 136.36752 -17.99844) (xy 136.20877 -18.15719) (xy 135.11403 -18.15719) (xy 134.44982 -18.8214)
				(xy 131.798314 -18.8214) (xy 131.65074 -18.968974) (xy 130.786886 -18.968974) (xy 130.56362 -19.19224)
				(xy 130.56362 -20.61718) (xy 130.75666 -20.81022) (xy 136.38276 -20.81022) (xy 137.06856 -20.12442)
				(xy 137.06856 -18.10004) (xy 136.96696 -17.99844)
			)
		)
		(polygon
			(pts
				(xy 136.15416 -18.92554) (xy 135.95096 -18.92554) (xy 135.95096 -19.12874) (xy 136.15416 -19.12874)
			)
		)
		(polygon
			(pts
				(xy 135.29056 -18.92554) (xy 135.08736 -18.92554) (xy 135.08736 -19.12874) (xy 135.29056 -19.12874)
			)
		)
		(polygon
			(pts
				(xy 136.5123 -18.51406) (xy 136.3091 -18.51406) (xy 136.3091 -18.71726) (xy 136.5123 -18.71726)
			)
		)
	)
	(zone
		(layer "F.Cu")
		(hatch none 0.5)
		(connect_pads
			(clearance 0)
		)
		(min_thickness 0.25)
		(keepout
			(tracks not_allowed)
			(vias allowed)
			(pads allowed)
			(copperpour not_allowed)
			(footprints allowed)
		)
		(placement
			(enabled no)
			(sheetname "")
		)
		(fill
			(thermal_gap 0.5)
			(thermal_bridge_width 0.5)
			(island_removal_mode 0)
		)
		(polygon
			(pts
				(arc
					(start 22.800056 -65.300098)
					(mid 27.55011 -60.550044)
					(end 22.800056 -55.79999)
				)
				(xy 8.64997 -55.79999) (xy 8.64997 -65.300098)
			)
		)
	)
	(zone
		(layer "F.Cu")
		(hatch none 0.5)
		(connect_pads
			(clearance 0)
		)
		(min_thickness 0.25)
		(keepout
			(tracks allowed)
			(vias allowed)
			(pads allowed)
			(copperpour allowed)
			(footprints allowed)
		)
		(placement
			(enabled no)
			(sheetname "")
		)
		(fill
			(thermal_gap 0.5)
			(thermal_bridge_width 0.5)
			(island_removal_mode 0)
		)
		(polygon
			(pts
				(xy 158.1912 -135.7376) (xy 158.1912 -133.7564) (xy 160.274 -133.7564) (xy 160.9344 -133.096) (xy 162.814 -133.096)
				(xy 162.8902 -133.1722) (xy 162.8902 -133.6802) (xy 160.8328 -135.7376) (xy 160.274 -135.7376)
			)
		)
	)
	(zone
		(layer "F.Cu")
		(hatch none 0.5)
		(connect_pads
			(clearance 0)
		)
		(min_thickness 0.25)
		(keepout
			(tracks not_allowed)
			(vias allowed)
			(pads allowed)
			(copperpour not_allowed)
			(footprints allowed)
		)
		(placement
			(enabled no)
			(sheetname "")
		)
		(fill
			(thermal_gap 0.5)
			(thermal_bridge_width 0.5)
			(island_removal_mode 0)
		)
		(polygon
			(pts
				(arc
					(start 85.367368 -72.08139)
					(mid 84.983955 -71.697596)
					(end 84.600288 -72.081136)
				)
				(xy 84.600288 -72.30872) (xy 84.699856 -72.30872)
				(arc
					(start 84.704428 -72.30872)
					(mid 84.757231 -72.30145)
					(end 84.806028 -72.280018)
				)
				(arc
					(start 84.806028 -72.280018)
					(mid 85.077919 -71.831509)
					(end 84.986114 -72.347836)
				)
				(arc
					(start 84.986114 -72.347836)
					(mid 84.876788 -72.437151)
					(end 84.741766 -72.478392)
				)
				(xy 84.739988 -72.480424) (xy 84.71408 -72.480424) (xy 84.704428 -72.480424) (xy 84.699856 -72.480424)
				(xy 84.600288 -72.480424) (xy 84.600288 -72.620124) (xy 84.714842 -72.620124) (xy 84.719414 -72.61987)
				(xy 84.728812 -72.620124) (xy 84.754974 -72.620124)
				(arc
					(start 84.756752 -72.621902)
					(mid 84.859322 -72.649065)
					(end 84.94903 -72.705722)
				)
				(arc
					(start 84.94903 -72.705722)
					(mid 85.113562 -73.203148)
					(end 84.777326 -72.801226)
				)
				(arc
					(start 84.777326 -72.801226)
					(mid 84.748769 -72.794004)
					(end 84.719414 -72.791574)
				)
				(xy 84.714842 -72.79132) (xy 84.600288 -72.79132)
				(arc
					(start 84.600288 -72.970136)
					(mid 84.983828 -73.353676)
					(end 85.367368 -72.970136)
				)
			)
		)
	)
	(zone
		(layer "F.Cu")
		(hatch none 0.5)
		(connect_pads
			(clearance 0)
		)
		(min_thickness 0.25)
		(keepout
			(tracks not_allowed)
			(vias allowed)
			(pads allowed)
			(copperpour not_allowed)
			(footprints allowed)
		)
		(placement
			(enabled no)
			(sheetname "")
		)
		(fill
			(thermal_gap 0.5)
			(thermal_bridge_width 0.5)
			(island_removal_mode 0)
		)
		(polygon
			(pts
				(arc
					(start 202.107292 -85.731096)
					(mid 202.107292 -85.192108)
					(end 201.568304 -85.192108)
				)
				(xy 201.424794 -85.335618) (xy 201.48677 -85.397594)
				(arc
					(start 201.490072 -85.400896)
					(mid 201.527736 -85.430652)
					(end 201.571352 -85.45068)
				)
				(arc
					(start 201.571352 -85.45068)
					(mid 201.580479 -85.391388)
					(end 201.602594 -85.335618)
				)
				(arc
					(start 201.602594 -85.335618)
					(mid 202.103268 -85.434794)
					(end 201.632566 -85.632036)
				)
				(arc
					(start 201.632566 -85.632036)
					(mid 201.507151 -85.609969)
					(end 201.396346 -85.5472)
				)
				(xy 201.393806 -85.5472) (xy 201.375772 -85.529166) (xy 201.36866 -85.522308) (xy 201.365358 -85.519006)
				(xy 201.303636 -85.45703) (xy 201.204576 -85.555836) (xy 201.266806 -85.617812) (xy 201.270108 -85.621114)
				(xy 201.276966 -85.628226) (xy 201.295 -85.64626)
				(arc
					(start 201.295 -85.6488)
					(mid 201.35773 -85.759474)
					(end 201.379836 -85.884766)
				)
				(arc
					(start 201.379836 -85.884766)
					(mid 201.124079 -86.342758)
					(end 201.198226 -85.823552)
				)
				(arc
					(start 201.198226 -85.823552)
					(mid 201.17827 -85.7801)
					(end 201.148696 -85.742526)
				)
				(xy 201.145394 -85.739224) (xy 201.083418 -85.677248)
				(arc
					(start 200.944734 -85.815932)
					(mid 200.937655 -86.357046)
					(end 201.478896 -86.359492)
				)
			)
		)
	)
	(zone
		(net "MB0_12V_CTRL_GATE1")
		(layer "F.Cu")
		(hatch none 0.5)
		(connect_pads
			(clearance 0.5)
		)
		(min_thickness 0.25)
		(fill yes
			(thermal_gap 0.5)
			(thermal_bridge_width 0.5)
			(island_removal_mode 0)
		)
		(polygon
			(pts
				(xy 131.59994 -4.65328) (xy 131.34848 -4.90474) (xy 131.34848 -7.103364) (xy 131.401058 -7.155942)
				(xy 132.755386 -7.155942) (xy 132.75564 -7.155688) (xy 132.92074 -7.155688) (xy 133.06171 -7.014718)
				(xy 133.06171 -7.00659) (xy 133.33476 -6.73354) (xy 135.13308 -6.73354) (xy 135.20039 -6.66623)
				(xy 135.20039 -5.486654) (xy 135.184134 -5.470398) (xy 135.184134 -4.955794) (xy 134.88162 -4.65328)
			)
		)
	)
	(zone
		(net "P3V3_STBY")
		(layer "F.Cu")
		(hatch none 0.5)
		(connect_pads
			(clearance 0.5)
		)
		(min_thickness 0.25)
		(fill yes
			(thermal_gap 0.5)
			(thermal_bridge_width 0.5)
			(island_removal_mode 0)
		)
		(polygon
			(pts
				(xy 46.545246 -161.32175) (xy 46.326806 -161.54019) (xy 45.236892 -161.54019) (xy 45.215302 -161.5186)
				(xy 43.7642 -161.5186) (xy 43.5356 -161.7472) (xy 43.5356 -162.9156) (xy 43.6626 -163.0426) (xy 44.1325 -163.0426)
				(xy 44.228258 -162.946842) (xy 44.228258 -162.505644) (xy 44.503594 -162.230308) (xy 44.977558 -162.230308)
				(xy 45.055282 -162.308032) (xy 45.509688 -162.308032) (xy 45.687996 -162.129724) (xy 46.271942 -162.129724)
				(xy 46.885098 -162.74288) (xy 48.928782 -162.74288) (xy 49.039018 -162.853116) (xy 49.268634 -162.853116)
				(xy 49.433988 -162.687762) (xy 49.433988 -161.44621) (xy 49.309528 -161.32175)
			)
		)
		(polygon
			(pts
				(xy 45.3644 -161.9758) (xy 45.1612 -161.9758) (xy 45.1612 -162.179) (xy 45.3644 -162.179)
			)
		)
		(polygon
			(pts
				(xy 44.323 -161.9758) (xy 44.1198 -161.9758) (xy 44.1198 -162.179) (xy 44.323 -162.179)
			)
		)
		(polygon
			(pts
				(xy 48.965104 -161.789872) (xy 48.761904 -161.789872) (xy 48.761904 -161.993072) (xy 48.965104 -161.993072)
			)
		)
		(polygon
			(pts
				(xy 48.482504 -161.789872) (xy 48.279304 -161.789872) (xy 48.279304 -161.993072) (xy 48.482504 -161.993072)
			)
		)
		(polygon
			(pts
				(xy 47.923704 -161.789872) (xy 47.720504 -161.789872) (xy 47.720504 -161.993072) (xy 47.923704 -161.993072)
			)
		)
		(polygon
			(pts
				(xy 47.441104 -161.789872) (xy 47.237904 -161.789872) (xy 47.237904 -161.993072) (xy 47.441104 -161.993072)
			)
		)
		(polygon
			(pts
				(xy 46.882304 -161.789872) (xy 46.679104 -161.789872) (xy 46.679104 -161.993072) (xy 46.882304 -161.993072)
			)
		)
	)
	(zone
		(layer "F.Cu")
		(hatch none 0.5)
		(connect_pads
			(clearance 0)
		)
		(min_thickness 0.25)
		(keepout
			(tracks allowed)
			(vias allowed)
			(pads allowed)
			(copperpour allowed)
			(footprints allowed)
		)
		(placement
			(enabled no)
			(sheetname "")
		)
		(fill
			(thermal_gap 0.5)
			(thermal_bridge_width 0.5)
			(island_removal_mode 0)
		)
		(polygon
			(pts
				(xy 93.3704 -172.2882) (xy 96.012 -172.2882) (xy 96.2406 -172.0596) (xy 96.2406 -171.4754) (xy 95.8596 -171.0944)
				(xy 93.472 -171.0944) (xy 93.1926 -171.3738) (xy 93.1926 -172.1104)
			)
		)
	)
	(zone
		(net "P1V5_OUT")
		(layer "F.Cu")
		(hatch none 0.5)
		(connect_pads
			(clearance 0.5)
		)
		(min_thickness 0.25)
		(fill yes
			(thermal_gap 0.5)
			(thermal_bridge_width 0.5)
			(island_removal_mode 0)
		)
		(polygon
			(pts
				(xy 208.6356 -118.4148) (xy 207.5942 -119.4562) (xy 205.4352 -119.4562) (xy 205.3082 -119.5832)
				(xy 205.3082 -121.4374) (xy 205.359 -121.4882) (xy 205.8924 -121.4882) (xy 206.1972 -121.793) (xy 206.1972 -123.444)
				(xy 205.5876 -124.0536) (xy 205.5876 -124.9934) (xy 205.613 -125.0188) (xy 207.6704 -125.0188) (xy 207.7212 -125.0696)
				(xy 207.7212 -125.8316) (xy 208.915 -125.8316) (xy 209.0166 -125.73) (xy 209.0166 -125.4252) (xy 209.2706 -125.1712)
				(xy 212.725 -125.1712) (xy 213.0806 -124.8156) (xy 213.0806 -118.5926) (xy 212.9028 -118.4148)
			)
		)
		(polygon
			(pts
				(xy 212.5472 -120.9802) (xy 212.344 -120.9802) (xy 212.344 -121.1834) (xy 212.5472 -121.1834)
			)
		)
		(polygon
			(pts
				(xy 206.0194 -120.8024) (xy 205.8162 -120.8024) (xy 205.8162 -121.0056) (xy 206.0194 -121.0056)
			)
		)
		(polygon
			(pts
				(xy 205.9432 -120.4468) (xy 205.74 -120.4468) (xy 205.74 -120.65) (xy 205.9432 -120.65)
			)
		)
		(polygon
			(pts
				(xy 212.5472 -120.3706) (xy 212.344 -120.3706) (xy 212.344 -120.5738) (xy 212.5472 -120.5738)
			)
		)
		(polygon
			(pts
				(xy 205.9432 -119.888) (xy 205.74 -119.888) (xy 205.74 -120.0912) (xy 205.9432 -120.0912)
			)
		)
	)
	(zone
		(layer "F.Cu")
		(hatch none 0.5)
		(connect_pads
			(clearance 0)
		)
		(min_thickness 0.25)
		(keepout
			(tracks not_allowed)
			(vias allowed)
			(pads allowed)
			(copperpour not_allowed)
			(footprints allowed)
		)
		(placement
			(enabled no)
			(sheetname "")
		)
		(fill
			(thermal_gap 0.5)
			(thermal_bridge_width 0.5)
			(island_removal_mode 0)
		)
		(polygon
			(pts
				(arc
					(start 207.941672 -68.1736)
					(mid 207.960368 -68.196002)
					(end 207.967072 -68.2244)
				)
				(arc
					(start 207.967072 -68.4276)
					(mid 207.960368 -68.455998)
					(end 207.941672 -68.4784)
				)
				(arc
					(start 208.170272 -68.4784)
					(mid 208.151576 -68.455998)
					(end 208.144872 -68.4276)
				)
				(arc
					(start 208.144872 -68.2244)
					(mid 208.151576 -68.196002)
					(end 208.170272 -68.1736)
				)
			)
		)
	)
	(zone
		(layer "F.Cu")
		(hatch none 0.5)
		(connect_pads
			(clearance 0)
		)
		(min_thickness 0.25)
		(keepout
			(tracks not_allowed)
			(vias allowed)
			(pads allowed)
			(copperpour not_allowed)
			(footprints allowed)
		)
		(placement
			(enabled no)
			(sheetname "")
		)
		(fill
			(thermal_gap 0.5)
			(thermal_bridge_width 0.5)
			(island_removal_mode 0)
		)
		(polygon
			(pts
				(arc
					(start 83.741768 -94.492572)
					(mid 83.358228 -94.109032)
					(end 82.974688 -94.492572)
				)
				(xy 82.974688 -94.708472) (xy 83.051904 -94.708472)
				(arc
					(start 83.056476 -94.708472)
					(mid 83.113629 -94.700779)
					(end 83.166712 -94.678246)
				)
				(arc
					(start 83.166712 -94.678246)
					(mid 83.471272 -94.250964)
					(end 83.338416 -94.75851)
				)
				(arc
					(start 83.338416 -94.75851)
					(mid 83.226873 -94.840678)
					(end 83.09356 -94.878398)
				)
				(xy 83.092036 -94.880176) (xy 83.066382 -94.880176) (xy 83.056476 -94.880176) (xy 83.051904 -94.880176)
				(xy 82.974688 -94.880176) (xy 82.974688 -95.019876) (xy 83.077558 -95.019876) (xy 83.08213 -95.019622)
				(xy 83.091782 -95.019876) (xy 83.11769 -95.019876)
				(arc
					(start 83.119468 -95.021654)
					(mid 83.231708 -95.051999)
					(end 83.32851 -95.116396)
				)
				(arc
					(start 83.32851 -95.116396)
					(mid 83.482282 -95.617818)
					(end 83.156806 -95.206566)
				)
				(arc
					(start 83.156806 -95.206566)
					(mid 83.120238 -95.19517)
					(end 83.08213 -95.191326)
				)
				(xy 83.077558 -95.191072) (xy 82.974688 -95.191072)
				(arc
					(start 82.974688 -95.381318)
					(mid 83.358101 -95.765112)
					(end 83.741768 -95.381572)
				)
			)
		)
	)
	(zone
		(layer "F.Cu")
		(hatch none 0.5)
		(connect_pads
			(clearance 0)
		)
		(min_thickness 0.25)
		(keepout
			(tracks allowed)
			(vias allowed)
			(pads allowed)
			(copperpour allowed)
			(footprints not_allowed)
		)
		(placement
			(enabled no)
			(sheetname "")
		)
		(fill
			(thermal_gap 0.5)
			(thermal_bridge_width 0.5)
			(island_removal_mode 0)
		)
		(polygon
			(pts
				(arc
					(start 73.03008 -0.999998)
					(mid 73.322973 -0.292893)
					(end 74.030078 0)
				)
				(xy 82.300064 0) (xy 82.300064 -29.200094) (xy 85.700108 -29.200094) (xy 85.700108 -35.299904)
				(arc
					(start 78.49997 -35.299904)
					(mid 73.749916 -40.049958)
					(end 78.49997 -44.800012)
				)
				(xy 85.700108 -44.800012) (xy 85.700108 -100.300028)
				(arc
					(start 78.550008 -100.300028)
					(mid 73.799954 -105.050082)
					(end 78.550008 -109.799882)
				)
				(xy 85.700108 -109.799882) (xy 85.700108 -113.050066) (xy 6.700012 -113.050066) (xy 6.700012 -109.799882)
				(arc
					(start 22.899878 -109.799882)
					(mid 26.674832 -102.166646)
					(end 18.317464 -103.799894)
				)
				(xy 6.700012 -103.799894) (xy 6.700012 -65.300098)
				(arc
					(start 22.800056 -65.300098)
					(mid 27.55011 -60.550044)
					(end 22.800056 -55.79999)
				)
				(xy 6.700012 -55.79999) (xy 6.700012 -48.600106) (xy 30.530038 -48.600106)
				(arc
					(start 30.530038 -109.050074)
					(mid 30.822931 -109.757179)
					(end 31.530036 -110.050072)
				)
				(arc
					(start 72.030082 -110.050072)
					(mid 72.737187 -109.757179)
					(end 73.03008 -109.050074)
				)
			)
		)
	)
	(zone
		(layers "F.Cu" "B.Cu" "In1.Cu" "In2.Cu" "In3.Cu" "In4.Cu" "In5.Cu" "In6.Cu")
		(hatch none 0.5)
		(connect_pads
			(clearance 0)
		)
		(min_thickness 0.25)
		(keepout
			(tracks not_allowed)
			(vias allowed)
			(pads allowed)
			(copperpour not_allowed)
			(footprints allowed)
		)
		(placement
			(enabled no)
			(sheetname "")
		)
		(fill
			(thermal_gap 0.5)
			(thermal_bridge_width 0.5)
			(island_removal_mode 0)
		)
		(polygon
			(pts
				(arc
					(start 222.807784 -84.479892)
					(mid 216.79154 -84.479892)
					(end 222.807784 -84.479892)
				)
			)
		)
	)
	(zone
		(layers "F.Cu" "B.Cu" "In1.Cu" "In2.Cu" "In3.Cu" "In4.Cu" "In5.Cu" "In6.Cu")
		(name "Route Keepin")
		(hatch none 0.5)
		(connect_pads
			(clearance 0)
		)
		(min_thickness 0.25)
		(keepout
			(tracks allowed)
			(vias allowed)
			(pads allowed)
			(copperpour allowed)
			(footprints allowed)
		)
		(placement
			(enabled no)
			(sheetname "")
		)
		(fill
			(thermal_gap 0.5)
			(thermal_bridge_width 0.5)
			(island_removal_mode 0)
		)
		(polygon
			(pts
				(arc
					(start 5.40512 -193.106548)
					(mid 5.492861 -193.202556)
					(end 5.617972 -193.23812)
				)
				(arc
					(start 98.081846 -193.23812)
					(mid 98.207115 -193.202642)
					(end 98.294952 -193.106548)
				)
				(arc
					(start 102.912926 -183.870346)
					(mid 102.931684 -183.818596)
					(end 102.938072 -183.76392)
				)
				(arc
					(start 102.938072 -47.999904)
					(mid 103.798188 -46.803514)
					(end 105.206038 -47.237904)
				)
				(arc
					(start 142.793974 -47.237904)
					(mid 144.201748 -46.80374)
					(end 145.06194 -47.999904)
				)
				(arc
					(start 145.06194 -183.76392)
					(mid 145.068307 -183.818601)
					(end 145.087086 -183.870346)
				)
				(arc
					(start 149.70506 -193.106548)
					(mid 149.792801 -193.202556)
					(end 149.917912 -193.23812)
				)
				(arc
					(start 229.382066 -193.23812)
					(mid 229.507189 -193.202575)
					(end 229.594918 -193.106548)
				)
				(arc
					(start 234.212892 -183.870346)
					(mid 234.23165 -183.818596)
					(end 234.238038 -183.76392)
				)
				(arc
					(start 234.238038 -0.999998)
					(mid 234.16833 -0.831708)
					(end 234.00004 -0.762)
				)
				(arc
					(start 74.030078 -0.762)
					(mid 73.861788 -0.831708)
					(end 73.79208 -0.999998)
				)
				(arc
					(start 73.79208 -109.050074)
					(mid 73.276003 -110.295995)
					(end 72.030082 -110.812072)
				)
				(arc
					(start 31.530036 -110.812072)
					(mid 30.284115 -110.295995)
					(end 29.768038 -109.050074)
				)
				(arc
					(start 29.768038 -0.999998)
					(mid 29.69833 -0.831708)
					(end 29.53004 -0.762)
				)
				(arc
					(start 0.999998 -0.762)
					(mid 0.831708 -0.831708)
					(end 0.762 -0.999998)
				)
				(arc
					(start 0.762 -183.76392)
					(mid 0.768367 -183.818601)
					(end 0.787146 -183.870346)
				)
			)
		)
	)
	(zone
		(layers "F.Cu" "B.Cu" "In1.Cu" "In2.Cu" "In3.Cu" "In4.Cu" "In5.Cu" "In6.Cu")
		(hatch none 0.5)
		(connect_pads
			(clearance 0)
		)
		(min_thickness 0.25)
		(keepout
			(tracks not_allowed)
			(vias allowed)
			(pads allowed)
			(copperpour not_allowed)
			(footprints allowed)
		)
		(placement
			(enabled no)
			(sheetname "")
		)
		(fill yes
			(thermal_gap 0.5)
			(thermal_bridge_width 0.5)
			(island_removal_mode 0)
		)
		(polygon
			(pts
				(arc
					(start 162.80003 -45.72)
					(mid 165.800024 -42.720006)
					(end 168.800018 -45.72)
				)
				(arc
					(start 168.800018 -45.72)
					(mid 165.800024 -48.719994)
					(end 162.80003 -45.72)
				)
			)
		)
	)
	(zone
		(layers "F.Cu" "B.Cu" "In1.Cu" "In2.Cu" "In3.Cu" "In4.Cu" "In5.Cu" "In6.Cu")
		(name "Package Keepin")
		(hatch none 0.5)
		(connect_pads
			(clearance 0)
		)
		(min_thickness 0.25)
		(keepout
			(tracks allowed)
			(vias allowed)
			(pads allowed)
			(copperpour allowed)
			(footprints allowed)
		)
		(placement
			(enabled no)
			(sheetname "")
		)
		(fill
			(thermal_gap 0.5)
			(thermal_bridge_width 0.5)
			(island_removal_mode 0)
		)
		(polygon
			(pts
				(xy 8.092694 -188.99632) (xy 95.607378 -188.99632) (xy 98.696272 -182.818532)
				(arc
					(start 98.696272 -47.99965)
					(mid 101.227215 -43.367996)
					(end 106.49204 -42.996104)
				)
				(arc
					(start 141.507972 -42.996104)
					(mid 146.772667 -43.368198)
					(end 149.30374 -47.99965)
				)
				(xy 149.30374 -182.818532) (xy 152.392634 -188.99632) (xy 226.907344 -188.99632) (xy 229.996238 -182.818532)
				(xy 229.996238 -5.0038) (xy 78.03388 -5.0038)
				(arc
					(start 78.03388 -109.050074)
					(mid 76.275408 -113.2954)
					(end 72.030082 -115.053872)
				)
				(arc
					(start 31.530036 -115.053872)
					(mid 27.28471 -113.2954)
					(end 25.526238 -109.050074)
				)
				(xy 25.526238 -5.0038) (xy 5.0038 -5.0038) (xy 5.0038 -182.818532)
			)
		)
	)
	(zone
		(layers "F.Cu" "B.Cu" "In2.Cu")
		(hatch none 0.5)
		(connect_pads
			(clearance 0)
		)
		(min_thickness 0.25)
		(keepout
			(tracks not_allowed)
			(vias allowed)
			(pads allowed)
			(copperpour not_allowed)
			(footprints allowed)
		)
		(placement
			(enabled no)
			(sheetname "")
		)
		(fill yes
			(thermal_gap 0.5)
			(thermal_bridge_width 0.5)
			(island_removal_mode 0)
		)
		(polygon
			(pts
				(arc
					(start 139.984988 -33.200086)
					(mid 139.499848 -32.714946)
					(end 139.014708 -33.200086)
				)
				(arc
					(start 139.014708 -34.600134)
					(mid 139.498578 -35.085272)
					(end 139.984988 -34.602674)
				)
				(arc
					(start 139.893548 -34.602674)
					(mid 139.499848 -34.993842)
					(end 139.106148 -34.602674)
				)
				(arc
					(start 139.106148 -34.600134)
					(mid 139.499848 -34.206434)
					(end 139.893548 -34.600134)
				)
				(xy 139.984988 -34.600134) (xy 139.984988 -33.202626)
				(arc
					(start 139.893548 -33.202626)
					(mid 139.499848 -33.593794)
					(end 139.106148 -33.202626)
				)
				(arc
					(start 139.106148 -33.200086)
					(mid 139.499848 -32.806386)
					(end 139.893548 -33.200086)
				)
			)
		)
	)
	(zone
		(layers "F.Cu" "B.Cu" "In2.Cu")
		(hatch none 0.5)
		(connect_pads
			(clearance 0)
		)
		(min_thickness 0.25)
		(keepout
			(tracks not_allowed)
			(vias allowed)
			(pads allowed)
			(copperpour not_allowed)
			(footprints allowed)
		)
		(placement
			(enabled no)
			(sheetname "")
		)
		(fill yes
			(thermal_gap 0.5)
			(thermal_bridge_width 0.5)
			(island_removal_mode 0)
		)
		(polygon
			(pts
				(arc
					(start 160.472374 -29.100018)
					(mid 160.11488 -28.641775)
					(end 159.583374 -28.877006)
				)
				(arc
					(start 158.833566 -30.277054)
					(mid 159.027114 -30.916626)
					(end 159.666686 -30.723078)
				)
				(xy 159.784796 -30.502606)
				(arc
					(start 159.631126 -30.502606)
					(mid 159.250126 -30.881074)
					(end 158.869126 -30.502606)
				)
				(arc
					(start 158.869126 -30.500066)
					(mid 159.250126 -30.119066)
					(end 159.631126 -30.500066)
				)
				(xy 159.786066 -30.500066)
				(arc
					(start 160.413446 -29.328618)
					(mid 160.457126 -29.219291)
					(end 160.472374 -29.102558)
				)
				(arc
					(start 160.380934 -29.102558)
					(mid 159.999934 -29.481026)
					(end 159.618934 -29.102558)
				)
				(arc
					(start 159.618934 -29.100018)
					(mid 159.999934 -28.719018)
					(end 160.380934 -29.100018)
				)
			)
		)
	)
	(zone
		(layers "F.Cu" "B.Cu" "In2.Cu")
		(hatch none 0.5)
		(connect_pads
			(clearance 0)
		)
		(min_thickness 0.25)
		(keepout
			(tracks not_allowed)
			(vias allowed)
			(pads allowed)
			(copperpour not_allowed)
			(footprints allowed)
		)
		(placement
			(enabled no)
			(sheetname "")
		)
		(fill yes
			(thermal_gap 0.5)
			(thermal_bridge_width 0.5)
			(island_removal_mode 0)
		)
		(polygon
			(pts
				(arc
					(start 162.72256 -25.299924)
					(mid 162.365066 -24.841681)
					(end 161.83356 -25.076912)
				)
				(arc
					(start 161.083498 -26.47696)
					(mid 161.277046 -27.116532)
					(end 161.916618 -26.922984)
				)
				(xy 162.034728 -26.702512)
				(arc
					(start 161.881058 -26.702512)
					(mid 161.500058 -27.08098)
					(end 161.119058 -26.702512)
				)
				(arc
					(start 161.119058 -26.699972)
					(mid 161.500058 -26.318972)
					(end 161.881058 -26.699972)
				)
				(xy 162.035998 -26.699972)
				(arc
					(start 162.663632 -25.528524)
					(mid 162.707312 -25.419197)
					(end 162.72256 -25.302464)
				)
				(arc
					(start 162.63112 -25.302464)
					(mid 162.25012 -25.680932)
					(end 161.86912 -25.302464)
				)
				(arc
					(start 161.86912 -25.299924)
					(mid 162.25012 -24.918924)
					(end 162.63112 -25.299924)
				)
			)
		)
	)
	(zone
		(layers "F.Cu" "B.Cu" "In2.Cu")
		(hatch none 0.5)
		(connect_pads
			(clearance 0)
		)
		(min_thickness 0.25)
		(keepout
			(tracks not_allowed)
			(vias allowed)
			(pads allowed)
			(copperpour not_allowed)
			(footprints allowed)
		)
		(placement
			(enabled no)
			(sheetname "")
		)
		(fill yes
			(thermal_gap 0.5)
			(thermal_bridge_width 0.5)
			(island_removal_mode 0)
		)
		(polygon
			(pts
				(arc
					(start 130.985006 -32.00019)
					(mid 130.499866 -31.51505)
					(end 130.014726 -32.00019)
				)
				(arc
					(start 130.014726 -33.399984)
					(mid 130.498596 -33.885122)
					(end 130.985006 -33.402524)
				)
				(arc
					(start 130.893566 -33.402524)
					(mid 130.499866 -33.793692)
					(end 130.106166 -33.402524)
				)
				(arc
					(start 130.106166 -33.399984)
					(mid 130.499866 -33.006284)
					(end 130.893566 -33.399984)
				)
				(xy 130.985006 -33.399984) (xy 130.985006 -32.00273)
				(arc
					(start 130.893566 -32.00273)
					(mid 130.499866 -32.393898)
					(end 130.106166 -32.00273)
				)
				(arc
					(start 130.106166 -32.00019)
					(mid 130.499866 -31.60649)
					(end 130.893566 -32.00019)
				)
			)
		)
	)
	(zone
		(layers "F.Cu" "B.Cu" "In2.Cu")
		(hatch none 0.5)
		(connect_pads
			(clearance 0)
		)
		(min_thickness 0.25)
		(keepout
			(tracks not_allowed)
			(vias allowed)
			(pads allowed)
			(copperpour not_allowed)
			(footprints allowed)
		)
		(placement
			(enabled no)
			(sheetname "")
		)
		(fill yes
			(thermal_gap 0.5)
			(thermal_bridge_width 0.5)
			(island_removal_mode 0)
		)
		(polygon
			(pts
				(arc
					(start 116.584984 -35.600132)
					(mid 116.099844 -35.114992)
					(end 115.614704 -35.600132)
				)
				(arc
					(start 115.614704 -37.00018)
					(mid 116.098574 -37.485318)
					(end 116.584984 -37.00272)
				)
				(arc
					(start 116.493544 -37.00272)
					(mid 116.099844 -37.393888)
					(end 115.706144 -37.00272)
				)
				(arc
					(start 115.706144 -37.00018)
					(mid 116.099844 -36.60648)
					(end 116.493544 -37.00018)
				)
				(xy 116.584984 -37.00018) (xy 116.584984 -35.602672)
				(arc
					(start 116.493544 -35.602672)
					(mid 116.099844 -35.99384)
					(end 115.706144 -35.602672)
				)
				(arc
					(start 115.706144 -35.600132)
					(mid 116.099844 -35.206432)
					(end 116.493544 -35.600132)
				)
			)
		)
	)
	(zone
		(layers "F.Cu" "B.Cu" "In2.Cu")
		(hatch none 0.5)
		(connect_pads
			(clearance 0)
		)
		(min_thickness 0.25)
		(keepout
			(tracks not_allowed)
			(vias allowed)
			(pads allowed)
			(copperpour not_allowed)
			(footprints allowed)
		)
		(placement
			(enabled no)
			(sheetname "")
		)
		(fill yes
			(thermal_gap 0.5)
			(thermal_bridge_width 0.5)
			(island_removal_mode 0)
		)
		(polygon
			(pts
				(arc
					(start 180.497734 -25.299924)
					(mid 180.121008 -24.817041)
					(end 179.560982 -25.064974)
				)
				(arc
					(start 178.811174 -26.465022)
					(mid 179.015136 -27.138884)
					(end 179.688998 -26.934922)
				)
				(xy 179.813458 -26.702512)
				(arc
					(start 179.631086 -26.702512)
					(mid 179.250086 -27.08098)
					(end 178.869086 -26.702512)
				)
				(arc
					(start 178.869086 -26.699972)
					(mid 179.250086 -26.318972)
					(end 179.631086 -26.699972)
				)
				(xy 179.814728 -26.699972)
				(arc
					(start 180.43398 -25.543764)
					(mid 180.481242 -25.427176)
					(end 180.497734 -25.302464)
				)
				(arc
					(start 180.380894 -25.302464)
					(mid 179.999894 -25.680932)
					(end 179.618894 -25.302464)
				)
				(arc
					(start 179.618894 -25.299924)
					(mid 179.999894 -24.918924)
					(end 180.380894 -25.299924)
				)
			)
		)
	)
	(zone
		(layers "F.Cu" "B.Cu" "In2.Cu")
		(hatch none 0.5)
		(connect_pads
			(clearance 0)
		)
		(min_thickness 0.25)
		(keepout
			(tracks not_allowed)
			(vias allowed)
			(pads allowed)
			(copperpour not_allowed)
			(footprints allowed)
		)
		(placement
			(enabled no)
			(sheetname "")
		)
		(fill yes
			(thermal_gap 0.5)
			(thermal_bridge_width 0.5)
			(island_removal_mode 0)
		)
		(polygon
			(pts
				(arc
					(start 180.472334 -29.100018)
					(mid 180.11484 -28.641775)
					(end 179.583334 -28.877006)
				)
				(arc
					(start 178.833526 -30.277054)
					(mid 179.027074 -30.916626)
					(end 179.666646 -30.723078)
				)
				(xy 179.784756 -30.502606)
				(arc
					(start 179.631086 -30.502606)
					(mid 179.250086 -30.881074)
					(end 178.869086 -30.502606)
				)
				(arc
					(start 178.869086 -30.500066)
					(mid 179.250086 -30.119066)
					(end 179.631086 -30.500066)
				)
				(xy 179.786026 -30.500066)
				(arc
					(start 180.413406 -29.328618)
					(mid 180.457086 -29.219291)
					(end 180.472334 -29.102558)
				)
				(arc
					(start 180.380894 -29.102558)
					(mid 179.999894 -29.481026)
					(end 179.618894 -29.102558)
				)
				(arc
					(start 179.618894 -29.100018)
					(mid 179.999894 -28.719018)
					(end 180.380894 -29.100018)
				)
			)
		)
	)
	(zone
		(layers "F.Cu" "B.Cu" "In2.Cu")
		(hatch none 0.5)
		(connect_pads
			(clearance 0)
		)
		(min_thickness 0.25)
		(keepout
			(tracks not_allowed)
			(vias allowed)
			(pads allowed)
			(copperpour not_allowed)
			(footprints allowed)
		)
		(placement
			(enabled no)
			(sheetname "")
		)
		(fill yes
			(thermal_gap 0.5)
			(thermal_bridge_width 0.5)
			(island_removal_mode 0)
		)
		(polygon
			(pts
				(arc
					(start 114.78514 -36.800028)
					(mid 114.3 -36.314888)
					(end 113.81486 -36.800028)
				)
				(arc
					(start 113.81486 -38.200076)
					(mid 114.29873 -38.685214)
					(end 114.78514 -38.202616)
				)
				(arc
					(start 114.6937 -38.202616)
					(mid 114.3 -38.593784)
					(end 113.9063 -38.202616)
				)
				(arc
					(start 113.9063 -38.200076)
					(mid 114.3 -37.806376)
					(end 114.6937 -38.200076)
				)
				(xy 114.78514 -38.200076) (xy 114.78514 -36.802568)
				(arc
					(start 114.6937 -36.802568)
					(mid 114.3 -37.193736)
					(end 113.9063 -36.802568)
				)
				(arc
					(start 113.9063 -36.800028)
					(mid 114.3 -36.406328)
					(end 114.6937 -36.800028)
				)
			)
		)
	)
	(zone
		(layers "F.Cu" "B.Cu" "In2.Cu")
		(hatch none 0.5)
		(connect_pads
			(clearance 0)
		)
		(min_thickness 0.25)
		(keepout
			(tracks not_allowed)
			(vias allowed)
			(pads allowed)
			(copperpour not_allowed)
			(footprints allowed)
		)
		(placement
			(enabled no)
			(sheetname "")
		)
		(fill yes
			(thermal_gap 0.5)
			(thermal_bridge_width 0.5)
			(island_removal_mode 0)
		)
		(polygon
			(pts
				(arc
					(start 129.185162 -33.200086)
					(mid 128.700022 -32.714946)
					(end 128.214882 -33.200086)
				)
				(arc
					(start 128.214882 -34.600134)
					(mid 128.698752 -35.085272)
					(end 129.185162 -34.602674)
				)
				(arc
					(start 129.093722 -34.602674)
					(mid 128.700022 -34.993842)
					(end 128.306322 -34.602674)
				)
				(arc
					(start 128.306322 -34.600134)
					(mid 128.700022 -34.206434)
					(end 129.093722 -34.600134)
				)
				(xy 129.185162 -34.600134) (xy 129.185162 -33.202626)
				(arc
					(start 129.093722 -33.202626)
					(mid 128.700022 -33.593794)
					(end 128.306322 -33.202626)
				)
				(arc
					(start 128.306322 -33.200086)
					(mid 128.700022 -32.806386)
					(end 129.093722 -33.200086)
				)
			)
		)
	)
	(zone
		(layers "F.Cu" "B.Cu" "In2.Cu")
		(hatch none 0.5)
		(connect_pads
			(clearance 0)
		)
		(min_thickness 0.25)
		(keepout
			(tracks not_allowed)
			(vias allowed)
			(pads allowed)
			(copperpour not_allowed)
			(footprints allowed)
		)
		(placement
			(enabled no)
			(sheetname "")
		)
		(fill yes
			(thermal_gap 0.5)
			(thermal_bridge_width 0.5)
			(island_removal_mode 0)
		)
		(polygon
			(pts
				(arc
					(start 182.72252 -29.100018)
					(mid 182.365026 -28.641775)
					(end 181.83352 -28.877006)
				)
				(arc
					(start 181.083458 -30.277054)
					(mid 181.277006 -30.916626)
					(end 181.916578 -30.723078)
				)
				(xy 182.034688 -30.502606)
				(arc
					(start 181.881018 -30.502606)
					(mid 181.500018 -30.881074)
					(end 181.119018 -30.502606)
				)
				(arc
					(start 181.119018 -30.500066)
					(mid 181.500018 -30.119066)
					(end 181.881018 -30.500066)
				)
				(xy 182.035958 -30.500066)
				(arc
					(start 182.663592 -29.328618)
					(mid 182.707272 -29.219291)
					(end 182.72252 -29.102558)
				)
				(arc
					(start 182.63108 -29.102558)
					(mid 182.25008 -29.481026)
					(end 181.86908 -29.102558)
				)
				(arc
					(start 181.86908 -29.100018)
					(mid 182.25008 -28.719018)
					(end 182.63108 -29.100018)
				)
			)
		)
	)
	(zone
		(layers "F.Cu" "B.Cu" "In2.Cu")
		(hatch none 0.5)
		(connect_pads
			(clearance 0)
		)
		(min_thickness 0.25)
		(keepout
			(tracks not_allowed)
			(vias allowed)
			(pads allowed)
			(copperpour not_allowed)
			(footprints allowed)
		)
		(placement
			(enabled no)
			(sheetname "")
		)
		(fill yes
			(thermal_gap 0.5)
			(thermal_bridge_width 0.5)
			(island_removal_mode 0)
		)
		(polygon
			(pts
				(arc
					(start 109.3851 -35.600132)
					(mid 108.89996 -35.114992)
					(end 108.41482 -35.600132)
				)
				(arc
					(start 108.41482 -37.00018)
					(mid 108.89869 -37.485318)
					(end 109.3851 -37.00272)
				)
				(arc
					(start 109.29366 -37.00272)
					(mid 108.89996 -37.393888)
					(end 108.50626 -37.00272)
				)
				(arc
					(start 108.50626 -37.00018)
					(mid 108.89996 -36.60648)
					(end 109.29366 -37.00018)
				)
				(xy 109.3851 -37.00018) (xy 109.3851 -35.602672)
				(arc
					(start 109.29366 -35.602672)
					(mid 108.89996 -35.99384)
					(end 108.50626 -35.602672)
				)
				(arc
					(start 108.50626 -35.600132)
					(mid 108.89996 -35.206432)
					(end 109.29366 -35.600132)
				)
			)
		)
	)
	(zone
		(layers "F.Cu" "B.Cu" "In2.Cu")
		(hatch none 0.5)
		(connect_pads
			(clearance 0)
		)
		(min_thickness 0.25)
		(keepout
			(tracks not_allowed)
			(vias allowed)
			(pads allowed)
			(copperpour not_allowed)
			(footprints allowed)
		)
		(placement
			(enabled no)
			(sheetname "")
		)
		(fill yes
			(thermal_gap 0.5)
			(thermal_bridge_width 0.5)
			(island_removal_mode 0)
		)
		(polygon
			(pts
				(arc
					(start 141.785086 -32.00019)
					(mid 141.299946 -31.51505)
					(end 140.814806 -32.00019)
				)
				(arc
					(start 140.814806 -33.399984)
					(mid 141.298676 -33.885122)
					(end 141.785086 -33.402524)
				)
				(arc
					(start 141.693646 -33.402524)
					(mid 141.299946 -33.793692)
					(end 140.906246 -33.402524)
				)
				(arc
					(start 140.906246 -33.399984)
					(mid 141.299946 -33.006284)
					(end 141.693646 -33.399984)
				)
				(xy 141.785086 -33.399984) (xy 141.785086 -32.00273)
				(arc
					(start 141.693646 -32.00273)
					(mid 141.299946 -32.393898)
					(end 140.906246 -32.00273)
				)
				(arc
					(start 140.906246 -32.00019)
					(mid 141.299946 -31.60649)
					(end 141.693646 -32.00019)
				)
			)
		)
	)
	(zone
		(layers "F.Cu" "B.Cu" "In2.Cu")
		(hatch none 0.5)
		(connect_pads
			(clearance 0)
		)
		(min_thickness 0.25)
		(keepout
			(tracks not_allowed)
			(vias allowed)
			(pads allowed)
			(copperpour not_allowed)
			(footprints allowed)
		)
		(placement
			(enabled no)
			(sheetname "")
		)
		(fill yes
			(thermal_gap 0.5)
			(thermal_bridge_width 0.5)
			(island_removal_mode 0)
		)
		(polygon
			(pts
				(arc
					(start 112.985042 -35.600132)
					(mid 112.499902 -35.114992)
					(end 112.014762 -35.600132)
				)
				(arc
					(start 112.014762 -37.00018)
					(mid 112.498632 -37.485318)
					(end 112.985042 -37.00272)
				)
				(arc
					(start 112.893602 -37.00272)
					(mid 112.499902 -37.393888)
					(end 112.106202 -37.00272)
				)
				(arc
					(start 112.106202 -37.00018)
					(mid 112.499902 -36.60648)
					(end 112.893602 -37.00018)
				)
				(xy 112.985042 -37.00018) (xy 112.985042 -35.602672)
				(arc
					(start 112.893602 -35.602672)
					(mid 112.499902 -35.99384)
					(end 112.106202 -35.602672)
				)
				(arc
					(start 112.106202 -35.600132)
					(mid 112.499902 -35.206432)
					(end 112.893602 -35.600132)
				)
			)
		)
	)
	(zone
		(layers "F.Cu" "B.Cu" "In2.Cu")
		(hatch none 0.5)
		(connect_pads
			(clearance 0)
		)
		(min_thickness 0.25)
		(keepout
			(tracks not_allowed)
			(vias allowed)
			(pads allowed)
			(copperpour not_allowed)
			(footprints allowed)
		)
		(placement
			(enabled no)
			(sheetname "")
		)
		(fill yes
			(thermal_gap 0.5)
			(thermal_bridge_width 0.5)
			(island_removal_mode 0)
		)
		(polygon
			(pts
				(arc
					(start 111.185198 -36.800028)
					(mid 110.700058 -36.314888)
					(end 110.214918 -36.800028)
				)
				(arc
					(start 110.214918 -38.200076)
					(mid 110.698788 -38.685214)
					(end 111.185198 -38.202616)
				)
				(arc
					(start 111.093758 -38.202616)
					(mid 110.700058 -38.593784)
					(end 110.306358 -38.202616)
				)
				(arc
					(start 110.306358 -38.200076)
					(mid 110.700058 -37.806376)
					(end 111.093758 -38.200076)
				)
				(xy 111.185198 -38.200076) (xy 111.185198 -36.802568)
				(arc
					(start 111.093758 -36.802568)
					(mid 110.700058 -37.193736)
					(end 110.306358 -36.802568)
				)
				(arc
					(start 110.306358 -36.800028)
					(mid 110.700058 -36.406328)
					(end 111.093758 -36.800028)
				)
			)
		)
	)
	(zone
		(layers "F.Cu" "B.Cu" "In2.Cu")
		(hatch none 0.5)
		(connect_pads
			(clearance 0)
		)
		(min_thickness 0.25)
		(keepout
			(tracks not_allowed)
			(vias allowed)
			(pads allowed)
			(copperpour not_allowed)
			(footprints allowed)
		)
		(placement
			(enabled no)
			(sheetname "")
		)
		(fill yes
			(thermal_gap 0.5)
			(thermal_bridge_width 0.5)
			(island_removal_mode 0)
		)
		(polygon
			(pts
				(arc
					(start 182.74792 -25.299924)
					(mid 182.371302 -24.817068)
					(end 181.811168 -25.06472)
				)
				(arc
					(start 181.061106 -26.464768)
					(mid 181.264814 -27.138884)
					(end 181.93893 -26.935176)
				)
				(xy 182.063644 -26.702512)
				(arc
					(start 181.881018 -26.702512)
					(mid 181.500018 -27.08098)
					(end 181.119018 -26.702512)
				)
				(arc
					(start 181.119018 -26.699972)
					(mid 181.500018 -26.318972)
					(end 181.881018 -26.699972)
				)
				(xy 182.064914 -26.699972)
				(arc
					(start 182.684166 -25.543764)
					(mid 182.731428 -25.427176)
					(end 182.74792 -25.302464)
				)
				(arc
					(start 182.63108 -25.302464)
					(mid 182.25008 -25.680932)
					(end 181.86908 -25.302464)
				)
				(arc
					(start 181.86908 -25.299924)
					(mid 182.25008 -24.918924)
					(end 182.63108 -25.299924)
				)
			)
		)
	)
	(zone
		(layers "F.Cu" "B.Cu" "In2.Cu")
		(hatch none 0.5)
		(connect_pads
			(clearance 0)
		)
		(min_thickness 0.25)
		(keepout
			(tracks not_allowed)
			(vias allowed)
			(pads allowed)
			(copperpour not_allowed)
			(footprints allowed)
		)
		(placement
			(enabled no)
			(sheetname "")
		)
		(fill yes
			(thermal_gap 0.5)
			(thermal_bridge_width 0.5)
			(island_removal_mode 0)
		)
		(polygon
			(pts
				(arc
					(start 118.385082 -36.800028)
					(mid 117.899942 -36.314888)
					(end 117.414802 -36.800028)
				)
				(arc
					(start 117.414802 -38.200076)
					(mid 117.898672 -38.685214)
					(end 118.385082 -38.202616)
				)
				(arc
					(start 118.293642 -38.202616)
					(mid 117.899942 -38.593784)
					(end 117.506242 -38.202616)
				)
				(arc
					(start 117.506242 -38.200076)
					(mid 117.899942 -37.806376)
					(end 118.293642 -38.200076)
				)
				(xy 118.385082 -38.200076) (xy 118.385082 -36.802568)
				(arc
					(start 118.293642 -36.802568)
					(mid 117.899942 -37.193736)
					(end 117.506242 -36.802568)
				)
				(arc
					(start 117.506242 -36.800028)
					(mid 117.899942 -36.406328)
					(end 118.293642 -36.800028)
				)
			)
		)
	)
	(zone
		(layers "F.Cu" "B.Cu" "In2.Cu")
		(hatch none 0.5)
		(connect_pads
			(clearance 0)
		)
		(min_thickness 0.25)
		(keepout
			(tracks not_allowed)
			(vias allowed)
			(pads allowed)
			(copperpour not_allowed)
			(footprints allowed)
		)
		(placement
			(enabled no)
			(sheetname "")
		)
		(fill yes
			(thermal_gap 0.5)
			(thermal_bridge_width 0.5)
			(island_removal_mode 0)
		)
		(polygon
			(pts
				(arc
					(start 138.185144 -32.00019)
					(mid 137.700004 -31.51505)
					(end 137.214864 -32.00019)
				)
				(arc
					(start 137.214864 -33.399984)
					(mid 137.698734 -33.885122)
					(end 138.185144 -33.402524)
				)
				(arc
					(start 138.093704 -33.402524)
					(mid 137.700004 -33.793692)
					(end 137.306304 -33.402524)
				)
				(arc
					(start 137.306304 -33.399984)
					(mid 137.700004 -33.006284)
					(end 138.093704 -33.399984)
				)
				(xy 138.185144 -33.399984) (xy 138.185144 -32.00273)
				(arc
					(start 138.093704 -32.00273)
					(mid 137.700004 -32.393898)
					(end 137.306304 -32.00273)
				)
				(arc
					(start 137.306304 -32.00019)
					(mid 137.700004 -31.60649)
					(end 138.093704 -32.00019)
				)
			)
		)
	)
	(zone
		(layers "F.Cu" "B.Cu" "In2.Cu")
		(hatch none 0.5)
		(connect_pads
			(clearance 0)
		)
		(min_thickness 0.25)
		(keepout
			(tracks not_allowed)
			(vias allowed)
			(pads allowed)
			(copperpour not_allowed)
			(footprints allowed)
		)
		(placement
			(enabled no)
			(sheetname "")
		)
		(fill yes
			(thermal_gap 0.5)
			(thermal_bridge_width 0.5)
			(island_removal_mode 0)
		)
		(polygon
			(pts
				(arc
					(start 162.72256 -29.100018)
					(mid 162.365066 -28.641775)
					(end 161.83356 -28.877006)
				)
				(arc
					(start 161.083498 -30.277054)
					(mid 161.277046 -30.916626)
					(end 161.916618 -30.723078)
				)
				(xy 162.034728 -30.502606)
				(arc
					(start 161.881058 -30.502606)
					(mid 161.500058 -30.881074)
					(end 161.119058 -30.502606)
				)
				(arc
					(start 161.119058 -30.500066)
					(mid 161.500058 -30.119066)
					(end 161.881058 -30.500066)
				)
				(xy 162.035998 -30.500066)
				(arc
					(start 162.663632 -29.328618)
					(mid 162.707312 -29.219291)
					(end 162.72256 -29.102558)
				)
				(arc
					(start 162.63112 -29.102558)
					(mid 162.25012 -29.481026)
					(end 161.86912 -29.102558)
				)
				(arc
					(start 161.86912 -29.100018)
					(mid 162.25012 -28.719018)
					(end 162.63112 -29.100018)
				)
			)
		)
	)
	(zone
		(layers "F.Cu" "B.Cu" "In2.Cu")
		(hatch none 0.5)
		(connect_pads
			(clearance 0)
		)
		(min_thickness 0.25)
		(keepout
			(tracks not_allowed)
			(vias allowed)
			(pads allowed)
			(copperpour not_allowed)
			(footprints allowed)
		)
		(placement
			(enabled no)
			(sheetname "")
		)
		(fill yes
			(thermal_gap 0.5)
			(thermal_bridge_width 0.5)
			(island_removal_mode 0)
		)
		(polygon
			(pts
				(arc
					(start 107.585002 -36.800028)
					(mid 107.099862 -36.314888)
					(end 106.614722 -36.800028)
				)
				(arc
					(start 106.614722 -38.200076)
					(mid 107.098592 -38.685214)
					(end 107.585002 -38.202616)
				)
				(arc
					(start 107.493562 -38.202616)
					(mid 107.099862 -38.593784)
					(end 106.706162 -38.202616)
				)
				(arc
					(start 106.706162 -38.200076)
					(mid 107.099862 -37.806376)
					(end 107.493562 -38.200076)
				)
				(xy 107.585002 -38.200076) (xy 107.585002 -36.802568)
				(arc
					(start 107.493562 -36.802568)
					(mid 107.099862 -37.193736)
					(end 106.706162 -36.802568)
				)
				(arc
					(start 106.706162 -36.800028)
					(mid 107.099862 -36.406328)
					(end 107.493562 -36.800028)
				)
			)
		)
	)
	(zone
		(layers "F.Cu" "B.Cu" "In2.Cu")
		(hatch none 0.5)
		(connect_pads
			(clearance 0)
		)
		(min_thickness 0.25)
		(keepout
			(tracks not_allowed)
			(vias allowed)
			(pads allowed)
			(copperpour not_allowed)
			(footprints allowed)
		)
		(placement
			(enabled no)
			(sheetname "")
		)
		(fill yes
			(thermal_gap 0.5)
			(thermal_bridge_width 0.5)
			(island_removal_mode 0)
		)
		(polygon
			(pts
				(arc
					(start 120.18518 -35.600132)
					(mid 119.70004 -35.114992)
					(end 119.2149 -35.600132)
				)
				(arc
					(start 119.2149 -37.00018)
					(mid 119.69877 -37.485318)
					(end 120.18518 -37.00272)
				)
				(arc
					(start 120.09374 -37.00272)
					(mid 119.70004 -37.393888)
					(end 119.30634 -37.00272)
				)
				(arc
					(start 119.30634 -37.00018)
					(mid 119.70004 -36.60648)
					(end 120.09374 -37.00018)
				)
				(xy 120.18518 -37.00018) (xy 120.18518 -35.602672)
				(arc
					(start 120.09374 -35.602672)
					(mid 119.70004 -35.99384)
					(end 119.30634 -35.602672)
				)
				(arc
					(start 119.30634 -35.600132)
					(mid 119.70004 -35.206432)
					(end 120.09374 -35.600132)
				)
			)
		)
	)
	(zone
		(layers "F.Cu" "B.Cu" "In2.Cu")
		(hatch none 0.5)
		(connect_pads
			(clearance 0)
		)
		(min_thickness 0.25)
		(keepout
			(tracks not_allowed)
			(vias allowed)
			(pads allowed)
			(copperpour not_allowed)
			(footprints allowed)
		)
		(placement
			(enabled no)
			(sheetname "")
		)
		(fill yes
			(thermal_gap 0.5)
			(thermal_bridge_width 0.5)
			(island_removal_mode 0)
		)
		(polygon
			(pts
				(arc
					(start 132.785104 -33.200086)
					(mid 132.299964 -32.714946)
					(end 131.814824 -33.200086)
				)
				(arc
					(start 131.814824 -34.600134)
					(mid 132.298694 -35.085272)
					(end 132.785104 -34.602674)
				)
				(arc
					(start 132.693664 -34.602674)
					(mid 132.299964 -34.993842)
					(end 131.906264 -34.602674)
				)
				(arc
					(start 131.906264 -34.600134)
					(mid 132.299964 -34.206434)
					(end 132.693664 -34.600134)
				)
				(xy 132.785104 -34.600134) (xy 132.785104 -33.202626)
				(arc
					(start 132.693664 -33.202626)
					(mid 132.299964 -33.593794)
					(end 131.906264 -33.202626)
				)
				(arc
					(start 131.906264 -33.200086)
					(mid 132.299964 -32.806386)
					(end 132.693664 -33.200086)
				)
			)
		)
	)
	(zone
		(layers "F.Cu" "B.Cu" "In2.Cu")
		(hatch none 0.5)
		(connect_pads
			(clearance 0)
		)
		(min_thickness 0.25)
		(keepout
			(tracks not_allowed)
			(vias allowed)
			(pads allowed)
			(copperpour not_allowed)
			(footprints allowed)
		)
		(placement
			(enabled no)
			(sheetname "")
		)
		(fill yes
			(thermal_gap 0.5)
			(thermal_bridge_width 0.5)
			(island_removal_mode 0)
		)
		(polygon
			(pts
				(arc
					(start 160.472374 -25.299924)
					(mid 160.11488 -24.841681)
					(end 159.583374 -25.076912)
				)
				(arc
					(start 158.833566 -26.47696)
					(mid 159.027114 -27.116532)
					(end 159.666686 -26.922984)
				)
				(xy 159.784796 -26.702512)
				(arc
					(start 159.631126 -26.702512)
					(mid 159.250126 -27.08098)
					(end 158.869126 -26.702512)
				)
				(arc
					(start 158.869126 -26.699972)
					(mid 159.250126 -26.318972)
					(end 159.631126 -26.699972)
				)
				(xy 159.786066 -26.699972)
				(arc
					(start 160.413446 -25.528524)
					(mid 160.457126 -25.419197)
					(end 160.472374 -25.302464)
				)
				(arc
					(start 160.380934 -25.302464)
					(mid 159.999934 -25.680932)
					(end 159.618934 -25.302464)
				)
				(arc
					(start 159.618934 -25.299924)
					(mid 159.999934 -24.918924)
					(end 160.380934 -25.299924)
				)
			)
		)
	)
	(zone
		(layers "F.Cu" "B.Cu" "In2.Cu")
		(hatch none 0.5)
		(connect_pads
			(clearance 0)
		)
		(min_thickness 0.25)
		(keepout
			(tracks not_allowed)
			(vias allowed)
			(pads allowed)
			(copperpour not_allowed)
			(footprints allowed)
		)
		(placement
			(enabled no)
			(sheetname "")
		)
		(fill yes
			(thermal_gap 0.5)
			(thermal_bridge_width 0.5)
			(island_removal_mode 0)
		)
		(polygon
			(pts
				(arc
					(start 134.585202 -32.00019)
					(mid 134.100062 -31.51505)
					(end 133.614922 -32.00019)
				)
				(arc
					(start 133.614922 -33.399984)
					(mid 134.098792 -33.885122)
					(end 134.585202 -33.402524)
				)
				(arc
					(start 134.493762 -33.402524)
					(mid 134.100062 -33.793692)
					(end 133.706362 -33.402524)
				)
				(arc
					(start 133.706362 -33.399984)
					(mid 134.100062 -33.006284)
					(end 134.493762 -33.399984)
				)
				(xy 134.585202 -33.399984) (xy 134.585202 -32.00273)
				(arc
					(start 134.493762 -32.00273)
					(mid 134.100062 -32.393898)
					(end 133.706362 -32.00273)
				)
				(arc
					(start 133.706362 -32.00019)
					(mid 134.100062 -31.60649)
					(end 134.493762 -32.00019)
				)
			)
		)
	)
	(zone
		(layers "F.Cu" "B.Cu" "In2.Cu")
		(hatch none 0.5)
		(connect_pads
			(clearance 0)
		)
		(min_thickness 0.25)
		(keepout
			(tracks not_allowed)
			(vias allowed)
			(pads allowed)
			(copperpour not_allowed)
			(footprints allowed)
		)
		(placement
			(enabled no)
			(sheetname "")
		)
		(fill yes
			(thermal_gap 0.5)
			(thermal_bridge_width 0.5)
			(island_removal_mode 0)
		)
		(polygon
			(pts
				(arc
					(start 136.385046 -33.200086)
					(mid 135.899906 -32.714946)
					(end 135.414766 -33.200086)
				)
				(arc
					(start 135.414766 -34.600134)
					(mid 135.898636 -35.085272)
					(end 136.385046 -34.602674)
				)
				(arc
					(start 136.293606 -34.602674)
					(mid 135.899906 -34.993842)
					(end 135.506206 -34.602674)
				)
				(arc
					(start 135.506206 -34.600134)
					(mid 135.899906 -34.206434)
					(end 136.293606 -34.600134)
				)
				(xy 136.385046 -34.600134) (xy 136.385046 -33.202626)
				(arc
					(start 136.293606 -33.202626)
					(mid 135.899906 -33.593794)
					(end 135.506206 -33.202626)
				)
				(arc
					(start 135.506206 -33.200086)
					(mid 135.899906 -32.806386)
					(end 136.293606 -33.200086)
				)
			)
		)
	)
	(zone
		(layers "F.Cu" "In2.Cu" "In5.Cu")
		(hatch none 0.5)
		(connect_pads
			(clearance 0)
		)
		(min_thickness 0.25)
		(keepout
			(tracks not_allowed)
			(vias allowed)
			(pads allowed)
			(copperpour not_allowed)
			(footprints allowed)
		)
		(placement
			(enabled no)
			(sheetname "")
		)
		(fill yes
			(thermal_gap 0.5)
			(thermal_bridge_width 0.5)
			(island_removal_mode 0)
		)
		(polygon
			(pts
				(arc
					(start 160.472374 -21.500084)
					(mid 160.11488 -21.041841)
					(end 159.583374 -21.277072)
				)
				(arc
					(start 158.836614 -22.671278)
					(mid 159.024316 -23.31492)
					(end 159.666686 -23.12289)
				)
				(xy 159.784796 -22.902418)
				(arc
					(start 159.631126 -22.902418)
					(mid 159.250126 -23.280886)
					(end 158.869126 -22.902418)
				)
				(arc
					(start 158.869126 -22.899878)
					(mid 159.250126 -22.518878)
					(end 159.631126 -22.899878)
				)
				(xy 159.786066 -22.899878)
				(arc
					(start 160.416494 -21.723096)
					(mid 160.457925 -21.616276)
					(end 160.472374 -21.502624)
				)
				(arc
					(start 160.380934 -21.502624)
					(mid 159.999934 -21.881092)
					(end 159.618934 -21.502624)
				)
				(arc
					(start 159.618934 -21.500084)
					(mid 159.999934 -21.119084)
					(end 160.380934 -21.500084)
				)
			)
		)
	)
	(zone
		(layers "F.Cu" "In2.Cu" "In5.Cu")
		(hatch none 0.5)
		(connect_pads
			(clearance 0)
		)
		(min_thickness 0.25)
		(keepout
			(tracks not_allowed)
			(vias allowed)
			(pads allowed)
			(copperpour not_allowed)
			(footprints allowed)
		)
		(placement
			(enabled no)
			(sheetname "")
		)
		(fill yes
			(thermal_gap 0.5)
			(thermal_bridge_width 0.5)
			(island_removal_mode 0)
		)
		(polygon
			(pts
				(arc
					(start 182.72252 -17.69999)
					(mid 182.365026 -17.241747)
					(end 181.83352 -17.476978)
				)
				(arc
					(start 181.083458 -18.877026)
					(mid 181.277006 -19.516598)
					(end 181.916578 -19.32305)
				)
				(xy 182.034688 -19.102578)
				(arc
					(start 181.881018 -19.102578)
					(mid 181.500018 -19.481046)
					(end 181.119018 -19.102578)
				)
				(arc
					(start 181.119018 -19.100038)
					(mid 181.500018 -18.719038)
					(end 181.881018 -19.100038)
				)
				(xy 182.035958 -19.100038)
				(arc
					(start 182.663592 -17.92859)
					(mid 182.707272 -17.819263)
					(end 182.72252 -17.70253)
				)
				(arc
					(start 182.63108 -17.70253)
					(mid 182.25008 -18.080998)
					(end 181.86908 -17.70253)
				)
				(arc
					(start 181.86908 -17.69999)
					(mid 182.25008 -17.31899)
					(end 182.63108 -17.69999)
				)
			)
		)
	)
	(zone
		(layers "F.Cu" "In2.Cu" "In5.Cu")
		(hatch none 0.5)
		(connect_pads
			(clearance 0)
		)
		(min_thickness 0.25)
		(keepout
			(tracks not_allowed)
			(vias allowed)
			(pads allowed)
			(copperpour not_allowed)
			(footprints allowed)
		)
		(placement
			(enabled no)
			(sheetname "")
		)
		(fill yes
			(thermal_gap 0.5)
			(thermal_bridge_width 0.5)
			(island_removal_mode 0)
		)
		(polygon
			(pts
				(arc
					(start 116.584984 -32.00019)
					(mid 116.099844 -31.51505)
					(end 115.614704 -32.00019)
				)
				(arc
					(start 115.614704 -33.399984)
					(mid 116.098574 -33.885122)
					(end 116.584984 -33.402524)
				)
				(arc
					(start 116.493544 -33.402524)
					(mid 116.099844 -33.793692)
					(end 115.706144 -33.402524)
				)
				(arc
					(start 115.706144 -33.399984)
					(mid 116.099844 -33.006284)
					(end 116.493544 -33.399984)
				)
				(xy 116.584984 -33.399984) (xy 116.584984 -32.00273)
				(arc
					(start 116.493544 -32.00273)
					(mid 116.099844 -32.393898)
					(end 115.706144 -32.00273)
				)
				(arc
					(start 115.706144 -32.00019)
					(mid 116.099844 -31.60649)
					(end 116.493544 -32.00019)
				)
			)
		)
	)
	(zone
		(layers "F.Cu" "In2.Cu" "In5.Cu")
		(hatch none 0.5)
		(connect_pads
			(clearance 0)
		)
		(min_thickness 0.25)
		(keepout
			(tracks not_allowed)
			(vias allowed)
			(pads allowed)
			(copperpour not_allowed)
			(footprints allowed)
		)
		(placement
			(enabled no)
			(sheetname "")
		)
		(fill yes
			(thermal_gap 0.5)
			(thermal_bridge_width 0.5)
			(island_removal_mode 0)
		)
		(polygon
			(pts
				(arc
					(start 162.72256 -21.500084)
					(mid 162.365124 -21.041855)
					(end 161.833814 -21.277072)
				)
				(xy 161.831528 -21.275802) (xy 161.081466 -22.675596)
				(arc
					(start 161.083752 -22.676866)
					(mid 161.277046 -23.316184)
					(end 161.916364 -23.12289)
				)
				(xy 161.91865 -23.12416) (xy 162.037522 -22.902418)
				(arc
					(start 161.881058 -22.902418)
					(mid 161.500058 -23.280886)
					(end 161.119058 -22.902418)
				)
				(arc
					(start 161.119058 -22.899878)
					(mid 161.500058 -22.518878)
					(end 161.881058 -22.899878)
				)
				(xy 162.038792 -22.899878) (xy 162.668712 -21.72462) (xy 162.668458 -21.724366)
				(arc
					(start 162.666426 -21.72335)
					(mid 162.707968 -21.616417)
					(end 162.72256 -21.502624)
				)
				(arc
					(start 162.63112 -21.502624)
					(mid 162.25012 -21.881092)
					(end 161.86912 -21.502624)
				)
				(arc
					(start 161.86912 -21.500084)
					(mid 162.25012 -21.119084)
					(end 162.63112 -21.500084)
				)
			)
		)
	)
	(zone
		(layers "F.Cu" "In2.Cu" "In5.Cu")
		(hatch none 0.5)
		(connect_pads
			(clearance 0)
		)
		(min_thickness 0.25)
		(keepout
			(tracks not_allowed)
			(vias allowed)
			(pads allowed)
			(copperpour not_allowed)
			(footprints allowed)
		)
		(placement
			(enabled no)
			(sheetname "")
		)
		(fill yes
			(thermal_gap 0.5)
			(thermal_bridge_width 0.5)
			(island_removal_mode 0)
		)
		(polygon
			(pts
				(arc
					(start 109.3851 -32.00019)
					(mid 108.89996 -31.51505)
					(end 108.41482 -32.00019)
				)
				(arc
					(start 108.41482 -33.399984)
					(mid 108.89869 -33.885122)
					(end 109.3851 -33.402524)
				)
				(arc
					(start 109.29366 -33.402524)
					(mid 108.89996 -33.793692)
					(end 108.50626 -33.402524)
				)
				(arc
					(start 108.50626 -33.399984)
					(mid 108.89996 -33.006284)
					(end 109.29366 -33.399984)
				)
				(xy 109.3851 -33.399984) (xy 109.3851 -32.00273)
				(arc
					(start 109.29366 -32.00273)
					(mid 108.89996 -32.393898)
					(end 108.50626 -32.00273)
				)
				(arc
					(start 108.50626 -32.00019)
					(mid 108.89996 -31.60649)
					(end 109.29366 -32.00019)
				)
			)
		)
	)
	(zone
		(layers "F.Cu" "In2.Cu" "In5.Cu")
		(hatch none 0.5)
		(connect_pads
			(clearance 0)
		)
		(min_thickness 0.25)
		(keepout
			(tracks not_allowed)
			(vias allowed)
			(pads allowed)
			(copperpour not_allowed)
			(footprints allowed)
		)
		(placement
			(enabled no)
			(sheetname "")
		)
		(fill yes
			(thermal_gap 0.5)
			(thermal_bridge_width 0.5)
			(island_removal_mode 0)
		)
		(polygon
			(pts
				(arc
					(start 180.472334 -21.500084)
					(mid 180.11484 -21.041841)
					(end 179.583334 -21.277072)
				)
				(arc
					(start 178.836574 -22.671278)
					(mid 179.024276 -23.31492)
					(end 179.666646 -23.12289)
				)
				(xy 179.784756 -22.902418)
				(arc
					(start 179.631086 -22.902418)
					(mid 179.250086 -23.280886)
					(end 178.869086 -22.902418)
				)
				(arc
					(start 178.869086 -22.899878)
					(mid 179.250086 -22.518878)
					(end 179.631086 -22.899878)
				)
				(xy 179.786026 -22.899878)
				(arc
					(start 180.416454 -21.723096)
					(mid 180.457885 -21.616276)
					(end 180.472334 -21.502624)
				)
				(arc
					(start 180.380894 -21.502624)
					(mid 179.999894 -21.881092)
					(end 179.618894 -21.502624)
				)
				(arc
					(start 179.618894 -21.500084)
					(mid 179.999894 -21.119084)
					(end 180.380894 -21.500084)
				)
			)
		)
	)
	(zone
		(layers "F.Cu" "In2.Cu" "In5.Cu")
		(hatch none 0.5)
		(connect_pads
			(clearance 0)
		)
		(min_thickness 0.25)
		(keepout
			(tracks not_allowed)
			(vias allowed)
			(pads allowed)
			(copperpour not_allowed)
			(footprints allowed)
		)
		(placement
			(enabled no)
			(sheetname "")
		)
		(fill yes
			(thermal_gap 0.5)
			(thermal_bridge_width 0.5)
			(island_removal_mode 0)
		)
		(polygon
			(pts
				(arc
					(start 132.785104 -36.800028)
					(mid 132.299964 -36.314888)
					(end 131.814824 -36.800028)
				)
				(arc
					(start 131.814824 -38.200076)
					(mid 132.298694 -38.685214)
					(end 132.785104 -38.202616)
				)
				(arc
					(start 132.693664 -38.202616)
					(mid 132.299964 -38.593784)
					(end 131.906264 -38.202616)
				)
				(arc
					(start 131.906264 -38.200076)
					(mid 132.299964 -37.806376)
					(end 132.693664 -38.200076)
				)
				(xy 132.785104 -38.200076) (xy 132.785104 -36.802568)
				(arc
					(start 132.693664 -36.802568)
					(mid 132.299964 -37.193736)
					(end 131.906264 -36.802568)
				)
				(arc
					(start 131.906264 -36.800028)
					(mid 132.299964 -36.406328)
					(end 132.693664 -36.800028)
				)
			)
		)
	)
	(zone
		(layers "F.Cu" "In2.Cu" "In5.Cu")
		(hatch none 0.5)
		(connect_pads
			(clearance 0)
		)
		(min_thickness 0.25)
		(keepout
			(tracks not_allowed)
			(vias allowed)
			(pads allowed)
			(copperpour not_allowed)
			(footprints allowed)
		)
		(placement
			(enabled no)
			(sheetname "")
		)
		(fill yes
			(thermal_gap 0.5)
			(thermal_bridge_width 0.5)
			(island_removal_mode 0)
		)
		(polygon
			(pts
				(arc
					(start 130.985006 -35.600132)
					(mid 130.499866 -35.114992)
					(end 130.014726 -35.600132)
				)
				(arc
					(start 130.014726 -37.00018)
					(mid 130.498596 -37.485318)
					(end 130.985006 -37.00272)
				)
				(arc
					(start 130.893566 -37.00272)
					(mid 130.499866 -37.393888)
					(end 130.106166 -37.00272)
				)
				(arc
					(start 130.106166 -37.00018)
					(mid 130.499866 -36.60648)
					(end 130.893566 -37.00018)
				)
				(xy 130.985006 -37.00018) (xy 130.985006 -35.602672)
				(arc
					(start 130.893566 -35.602672)
					(mid 130.499866 -35.99384)
					(end 130.106166 -35.602672)
				)
				(arc
					(start 130.106166 -35.600132)
					(mid 130.499866 -35.206432)
					(end 130.893566 -35.600132)
				)
			)
		)
	)
	(zone
		(layers "F.Cu" "In2.Cu" "In5.Cu")
		(hatch none 0.5)
		(connect_pads
			(clearance 0)
		)
		(min_thickness 0.25)
		(keepout
			(tracks not_allowed)
			(vias allowed)
			(pads allowed)
			(copperpour not_allowed)
			(footprints allowed)
		)
		(placement
			(enabled no)
			(sheetname "")
		)
		(fill yes
			(thermal_gap 0.5)
			(thermal_bridge_width 0.5)
			(island_removal_mode 0)
		)
		(polygon
			(pts
				(arc
					(start 134.585202 -35.600132)
					(mid 134.100062 -35.114992)
					(end 133.614922 -35.600132)
				)
				(arc
					(start 133.614922 -37.00018)
					(mid 134.098792 -37.485318)
					(end 134.585202 -37.00272)
				)
				(arc
					(start 134.493762 -37.00272)
					(mid 134.100062 -37.393888)
					(end 133.706362 -37.00272)
				)
				(arc
					(start 133.706362 -37.00018)
					(mid 134.100062 -36.60648)
					(end 134.493762 -37.00018)
				)
				(xy 134.585202 -37.00018) (xy 134.585202 -35.602672)
				(arc
					(start 134.493762 -35.602672)
					(mid 134.100062 -35.99384)
					(end 133.706362 -35.602672)
				)
				(arc
					(start 133.706362 -35.600132)
					(mid 134.100062 -35.206432)
					(end 134.493762 -35.600132)
				)
			)
		)
	)
	(zone
		(layers "F.Cu" "In2.Cu" "In5.Cu")
		(hatch none 0.5)
		(connect_pads
			(clearance 0)
		)
		(min_thickness 0.25)
		(keepout
			(tracks not_allowed)
			(vias allowed)
			(pads allowed)
			(copperpour not_allowed)
			(footprints allowed)
		)
		(placement
			(enabled no)
			(sheetname "")
		)
		(fill yes
			(thermal_gap 0.5)
			(thermal_bridge_width 0.5)
			(island_removal_mode 0)
		)
		(polygon
			(pts
				(arc
					(start 160.472374 -17.69999)
					(mid 160.11488 -17.241747)
					(end 159.583374 -17.476978)
				)
				(arc
					(start 158.833566 -18.877026)
					(mid 159.027114 -19.516598)
					(end 159.666686 -19.32305)
				)
				(xy 159.784796 -19.102578)
				(arc
					(start 159.631126 -19.102578)
					(mid 159.250126 -19.481046)
					(end 158.869126 -19.102578)
				)
				(arc
					(start 158.869126 -19.100038)
					(mid 159.250126 -18.719038)
					(end 159.631126 -19.100038)
				)
				(xy 159.786066 -19.100038)
				(arc
					(start 160.413446 -17.92859)
					(mid 160.457126 -17.819263)
					(end 160.472374 -17.70253)
				)
				(arc
					(start 160.380934 -17.70253)
					(mid 159.999934 -18.080998)
					(end 159.618934 -17.70253)
				)
				(arc
					(start 159.618934 -17.69999)
					(mid 159.999934 -17.31899)
					(end 160.380934 -17.69999)
				)
			)
		)
	)
	(zone
		(layers "F.Cu" "In2.Cu" "In5.Cu")
		(hatch none 0.5)
		(connect_pads
			(clearance 0)
		)
		(min_thickness 0.25)
		(keepout
			(tracks not_allowed)
			(vias allowed)
			(pads allowed)
			(copperpour not_allowed)
			(footprints allowed)
		)
		(placement
			(enabled no)
			(sheetname "")
		)
		(fill yes
			(thermal_gap 0.5)
			(thermal_bridge_width 0.5)
			(island_removal_mode 0)
		)
		(polygon
			(pts
				(arc
					(start 107.585002 -33.200086)
					(mid 107.099862 -32.714946)
					(end 106.614722 -33.200086)
				)
				(arc
					(start 106.614722 -34.600134)
					(mid 107.098592 -35.085272)
					(end 107.585002 -34.602674)
				)
				(arc
					(start 107.493562 -34.602674)
					(mid 107.099862 -34.993842)
					(end 106.706162 -34.602674)
				)
				(arc
					(start 106.706162 -34.600134)
					(mid 107.099862 -34.206434)
					(end 107.493562 -34.600134)
				)
				(xy 107.585002 -34.600134) (xy 107.585002 -33.202626)
				(arc
					(start 107.493562 -33.202626)
					(mid 107.099862 -33.593794)
					(end 106.706162 -33.202626)
				)
				(arc
					(start 106.706162 -33.200086)
					(mid 107.099862 -32.806386)
					(end 107.493562 -33.200086)
				)
			)
		)
	)
	(zone
		(layers "F.Cu" "In2.Cu" "In5.Cu")
		(hatch none 0.5)
		(connect_pads
			(clearance 0)
		)
		(min_thickness 0.25)
		(keepout
			(tracks not_allowed)
			(vias allowed)
			(pads allowed)
			(copperpour not_allowed)
			(footprints allowed)
		)
		(placement
			(enabled no)
			(sheetname "")
		)
		(fill yes
			(thermal_gap 0.5)
			(thermal_bridge_width 0.5)
			(island_removal_mode 0)
		)
		(polygon
			(pts
				(arc
					(start 120.18518 -32.00019)
					(mid 119.70004 -31.51505)
					(end 119.2149 -32.00019)
				)
				(arc
					(start 119.2149 -33.399984)
					(mid 119.69877 -33.885122)
					(end 120.18518 -33.402524)
				)
				(arc
					(start 120.09374 -33.402524)
					(mid 119.70004 -33.793692)
					(end 119.30634 -33.402524)
				)
				(arc
					(start 119.30634 -33.399984)
					(mid 119.70004 -33.006284)
					(end 120.09374 -33.399984)
				)
				(xy 120.18518 -33.399984) (xy 120.18518 -32.00273)
				(arc
					(start 120.09374 -32.00273)
					(mid 119.70004 -32.393898)
					(end 119.30634 -32.00273)
				)
				(arc
					(start 119.30634 -32.00019)
					(mid 119.70004 -31.60649)
					(end 120.09374 -32.00019)
				)
			)
		)
	)
	(zone
		(layers "F.Cu" "In2.Cu" "In5.Cu")
		(hatch none 0.5)
		(connect_pads
			(clearance 0)
		)
		(min_thickness 0.25)
		(keepout
			(tracks not_allowed)
			(vias allowed)
			(pads allowed)
			(copperpour not_allowed)
			(footprints allowed)
		)
		(placement
			(enabled no)
			(sheetname "")
		)
		(fill yes
			(thermal_gap 0.5)
			(thermal_bridge_width 0.5)
			(island_removal_mode 0)
		)
		(polygon
			(pts
				(arc
					(start 111.185198 -33.200086)
					(mid 110.700058 -32.714946)
					(end 110.214918 -33.200086)
				)
				(arc
					(start 110.214918 -34.600134)
					(mid 110.698788 -35.085272)
					(end 111.185198 -34.602674)
				)
				(arc
					(start 111.093758 -34.602674)
					(mid 110.700058 -34.993842)
					(end 110.306358 -34.602674)
				)
				(arc
					(start 110.306358 -34.600134)
					(mid 110.700058 -34.206434)
					(end 111.093758 -34.600134)
				)
				(xy 111.185198 -34.600134) (xy 111.185198 -33.202626)
				(arc
					(start 111.093758 -33.202626)
					(mid 110.700058 -33.593794)
					(end 110.306358 -33.202626)
				)
				(arc
					(start 110.306358 -33.200086)
					(mid 110.700058 -32.806386)
					(end 111.093758 -33.200086)
				)
			)
		)
	)
	(zone
		(layers "F.Cu" "In2.Cu" "In5.Cu")
		(hatch none 0.5)
		(connect_pads
			(clearance 0)
		)
		(min_thickness 0.25)
		(keepout
			(tracks not_allowed)
			(vias allowed)
			(pads allowed)
			(copperpour not_allowed)
			(footprints allowed)
		)
		(placement
			(enabled no)
			(sheetname "")
		)
		(fill yes
			(thermal_gap 0.5)
			(thermal_bridge_width 0.5)
			(island_removal_mode 0)
		)
		(polygon
			(pts
				(arc
					(start 129.185162 -36.800028)
					(mid 128.700022 -36.314888)
					(end 128.214882 -36.800028)
				)
				(arc
					(start 128.214882 -38.200076)
					(mid 128.698752 -38.685214)
					(end 129.185162 -38.202616)
				)
				(arc
					(start 129.093722 -38.202616)
					(mid 128.700022 -38.593784)
					(end 128.306322 -38.202616)
				)
				(arc
					(start 128.306322 -38.200076)
					(mid 128.700022 -37.806376)
					(end 129.093722 -38.200076)
				)
				(xy 129.185162 -38.200076) (xy 129.185162 -36.802568)
				(arc
					(start 129.093722 -36.802568)
					(mid 128.700022 -37.193736)
					(end 128.306322 -36.802568)
				)
				(arc
					(start 128.306322 -36.800028)
					(mid 128.700022 -36.406328)
					(end 129.093722 -36.800028)
				)
			)
		)
	)
	(zone
		(layers "F.Cu" "In2.Cu" "In5.Cu")
		(hatch none 0.5)
		(connect_pads
			(clearance 0)
		)
		(min_thickness 0.25)
		(keepout
			(tracks not_allowed)
			(vias allowed)
			(pads allowed)
			(copperpour not_allowed)
			(footprints allowed)
		)
		(placement
			(enabled no)
			(sheetname "")
		)
		(fill yes
			(thermal_gap 0.5)
			(thermal_bridge_width 0.5)
			(island_removal_mode 0)
		)
		(polygon
			(pts
				(arc
					(start 114.78514 -33.200086)
					(mid 114.3 -32.714946)
					(end 113.81486 -33.200086)
				)
				(arc
					(start 113.81486 -34.600134)
					(mid 114.29873 -35.085272)
					(end 114.78514 -34.602674)
				)
				(arc
					(start 114.6937 -34.602674)
					(mid 114.3 -34.993842)
					(end 113.9063 -34.602674)
				)
				(arc
					(start 113.9063 -34.600134)
					(mid 114.3 -34.206434)
					(end 114.6937 -34.600134)
				)
				(xy 114.78514 -34.600134) (xy 114.78514 -33.202626)
				(arc
					(start 114.6937 -33.202626)
					(mid 114.3 -33.593794)
					(end 113.9063 -33.202626)
				)
				(arc
					(start 113.9063 -33.200086)
					(mid 114.3 -32.806386)
					(end 114.6937 -33.200086)
				)
			)
		)
	)
	(zone
		(layers "F.Cu" "In2.Cu" "In5.Cu")
		(hatch none 0.5)
		(connect_pads
			(clearance 0)
		)
		(min_thickness 0.25)
		(keepout
			(tracks not_allowed)
			(vias allowed)
			(pads allowed)
			(copperpour not_allowed)
			(footprints allowed)
		)
		(placement
			(enabled no)
			(sheetname "")
		)
		(fill yes
			(thermal_gap 0.5)
			(thermal_bridge_width 0.5)
			(island_removal_mode 0)
		)
		(polygon
			(pts
				(arc
					(start 180.472334 -17.69999)
					(mid 180.11484 -17.241747)
					(end 179.583334 -17.476978)
				)
				(arc
					(start 178.833526 -18.877026)
					(mid 179.027074 -19.516598)
					(end 179.666646 -19.32305)
				)
				(xy 179.784756 -19.102578)
				(arc
					(start 179.631086 -19.102578)
					(mid 179.250086 -19.481046)
					(end 178.869086 -19.102578)
				)
				(arc
					(start 178.869086 -19.100038)
					(mid 179.250086 -18.719038)
					(end 179.631086 -19.100038)
				)
				(xy 179.786026 -19.100038)
				(arc
					(start 180.413406 -17.92859)
					(mid 180.457086 -17.819263)
					(end 180.472334 -17.70253)
				)
				(arc
					(start 180.380894 -17.70253)
					(mid 179.999894 -18.080998)
					(end 179.618894 -17.70253)
				)
				(arc
					(start 179.618894 -17.69999)
					(mid 179.999894 -17.31899)
					(end 180.380894 -17.69999)
				)
			)
		)
	)
	(zone
		(layers "F.Cu" "In2.Cu" "In5.Cu")
		(hatch none 0.5)
		(connect_pads
			(clearance 0)
		)
		(min_thickness 0.25)
		(keepout
			(tracks not_allowed)
			(vias allowed)
			(pads allowed)
			(copperpour not_allowed)
			(footprints allowed)
		)
		(placement
			(enabled no)
			(sheetname "")
		)
		(fill yes
			(thermal_gap 0.5)
			(thermal_bridge_width 0.5)
			(island_removal_mode 0)
		)
		(polygon
			(pts
				(arc
					(start 112.985042 -32.00019)
					(mid 112.499902 -31.51505)
					(end 112.014762 -32.00019)
				)
				(arc
					(start 112.014762 -33.399984)
					(mid 112.498632 -33.885122)
					(end 112.985042 -33.402524)
				)
				(arc
					(start 112.893602 -33.402524)
					(mid 112.499902 -33.793692)
					(end 112.106202 -33.402524)
				)
				(arc
					(start 112.106202 -33.399984)
					(mid 112.499902 -33.006284)
					(end 112.893602 -33.399984)
				)
				(xy 112.985042 -33.399984) (xy 112.985042 -32.00273)
				(arc
					(start 112.893602 -32.00273)
					(mid 112.499902 -32.393898)
					(end 112.106202 -32.00273)
				)
				(arc
					(start 112.106202 -32.00019)
					(mid 112.499902 -31.60649)
					(end 112.893602 -32.00019)
				)
			)
		)
	)
	(zone
		(layers "F.Cu" "In2.Cu" "In5.Cu")
		(hatch none 0.5)
		(connect_pads
			(clearance 0)
		)
		(min_thickness 0.25)
		(keepout
			(tracks not_allowed)
			(vias allowed)
			(pads allowed)
			(copperpour not_allowed)
			(footprints allowed)
		)
		(placement
			(enabled no)
			(sheetname "")
		)
		(fill yes
			(thermal_gap 0.5)
			(thermal_bridge_width 0.5)
			(island_removal_mode 0)
		)
		(polygon
			(pts
				(arc
					(start 139.984988 -36.800028)
					(mid 139.499848 -36.314888)
					(end 139.014708 -36.800028)
				)
				(arc
					(start 139.014708 -38.200076)
					(mid 139.498578 -38.685214)
					(end 139.984988 -38.202616)
				)
				(arc
					(start 139.893548 -38.202616)
					(mid 139.499848 -38.593784)
					(end 139.106148 -38.202616)
				)
				(arc
					(start 139.106148 -38.200076)
					(mid 139.499848 -37.806376)
					(end 139.893548 -38.200076)
				)
				(xy 139.984988 -38.200076) (xy 139.984988 -36.802568)
				(arc
					(start 139.893548 -36.802568)
					(mid 139.499848 -37.193736)
					(end 139.106148 -36.802568)
				)
				(arc
					(start 139.106148 -36.800028)
					(mid 139.499848 -36.406328)
					(end 139.893548 -36.800028)
				)
			)
		)
	)
	(zone
		(layers "F.Cu" "In2.Cu" "In5.Cu")
		(hatch none 0.5)
		(connect_pads
			(clearance 0)
		)
		(min_thickness 0.25)
		(keepout
			(tracks not_allowed)
			(vias allowed)
			(pads allowed)
			(copperpour not_allowed)
			(footprints allowed)
		)
		(placement
			(enabled no)
			(sheetname "")
		)
		(fill yes
			(thermal_gap 0.5)
			(thermal_bridge_width 0.5)
			(island_removal_mode 0)
		)
		(polygon
			(pts
				(arc
					(start 136.385046 -36.800028)
					(mid 135.899906 -36.314888)
					(end 135.414766 -36.800028)
				)
				(arc
					(start 135.414766 -38.200076)
					(mid 135.898636 -38.685214)
					(end 136.385046 -38.202616)
				)
				(arc
					(start 136.293606 -38.202616)
					(mid 135.899906 -38.593784)
					(end 135.506206 -38.202616)
				)
				(arc
					(start 135.506206 -38.200076)
					(mid 135.899906 -37.806376)
					(end 136.293606 -38.200076)
				)
				(xy 136.385046 -38.200076) (xy 136.385046 -36.802568)
				(arc
					(start 136.293606 -36.802568)
					(mid 135.899906 -37.193736)
					(end 135.506206 -36.802568)
				)
				(arc
					(start 135.506206 -36.800028)
					(mid 135.899906 -36.406328)
					(end 136.293606 -36.800028)
				)
			)
		)
	)
	(zone
		(layers "F.Cu" "In2.Cu" "In5.Cu")
		(hatch none 0.5)
		(connect_pads
			(clearance 0)
		)
		(min_thickness 0.25)
		(keepout
			(tracks not_allowed)
			(vias allowed)
			(pads allowed)
			(copperpour not_allowed)
			(footprints allowed)
		)
		(placement
			(enabled no)
			(sheetname "")
		)
		(fill yes
			(thermal_gap 0.5)
			(thermal_bridge_width 0.5)
			(island_removal_mode 0)
		)
		(polygon
			(pts
				(arc
					(start 182.72252 -21.500084)
					(mid 182.365084 -21.041855)
					(end 181.833774 -21.277072)
				)
				(xy 181.831488 -21.275802) (xy 181.081426 -22.675596)
				(arc
					(start 181.083712 -22.676866)
					(mid 181.277006 -23.316184)
					(end 181.916324 -23.12289)
				)
				(xy 181.91861 -23.12416) (xy 182.037482 -22.902418)
				(arc
					(start 181.881018 -22.902418)
					(mid 181.500018 -23.280886)
					(end 181.119018 -22.902418)
				)
				(arc
					(start 181.119018 -22.899878)
					(mid 181.500018 -22.518878)
					(end 181.881018 -22.899878)
				)
				(xy 182.038752 -22.899878) (xy 182.668672 -21.72462) (xy 182.668418 -21.724366)
				(arc
					(start 182.666386 -21.72335)
					(mid 182.707928 -21.616417)
					(end 182.72252 -21.502624)
				)
				(arc
					(start 182.63108 -21.502624)
					(mid 182.25008 -21.881092)
					(end 181.86908 -21.502624)
				)
				(arc
					(start 181.86908 -21.500084)
					(mid 182.25008 -21.119084)
					(end 182.63108 -21.500084)
				)
			)
		)
	)
	(zone
		(layers "F.Cu" "In2.Cu" "In5.Cu")
		(hatch none 0.5)
		(connect_pads
			(clearance 0)
		)
		(min_thickness 0.25)
		(keepout
			(tracks not_allowed)
			(vias allowed)
			(pads allowed)
			(copperpour not_allowed)
			(footprints allowed)
		)
		(placement
			(enabled no)
			(sheetname "")
		)
		(fill yes
			(thermal_gap 0.5)
			(thermal_bridge_width 0.5)
			(island_removal_mode 0)
		)
		(polygon
			(pts
				(arc
					(start 162.72256 -17.69999)
					(mid 162.365066 -17.241747)
					(end 161.83356 -17.476978)
				)
				(arc
					(start 161.083498 -18.877026)
					(mid 161.277046 -19.516598)
					(end 161.916618 -19.32305)
				)
				(xy 162.034728 -19.102578)
				(arc
					(start 161.881058 -19.102578)
					(mid 161.500058 -19.481046)
					(end 161.119058 -19.102578)
				)
				(arc
					(start 161.119058 -19.100038)
					(mid 161.500058 -18.719038)
					(end 161.881058 -19.100038)
				)
				(xy 162.035998 -19.100038)
				(arc
					(start 162.663632 -17.92859)
					(mid 162.707312 -17.819263)
					(end 162.72256 -17.70253)
				)
				(arc
					(start 162.63112 -17.70253)
					(mid 162.25012 -18.080998)
					(end 161.86912 -17.70253)
				)
				(arc
					(start 161.86912 -17.69999)
					(mid 162.25012 -17.31899)
					(end 162.63112 -17.69999)
				)
			)
		)
	)
	(zone
		(layers "F.Cu" "In2.Cu" "In5.Cu")
		(hatch none 0.5)
		(connect_pads
			(clearance 0)
		)
		(min_thickness 0.25)
		(keepout
			(tracks not_allowed)
			(vias allowed)
			(pads allowed)
			(copperpour not_allowed)
			(footprints allowed)
		)
		(placement
			(enabled no)
			(sheetname "")
		)
		(fill yes
			(thermal_gap 0.5)
			(thermal_bridge_width 0.5)
			(island_removal_mode 0)
		)
		(polygon
			(pts
				(arc
					(start 118.385082 -33.200086)
					(mid 117.899942 -32.714946)
					(end 117.414802 -33.200086)
				)
				(arc
					(start 117.414802 -34.600134)
					(mid 117.898672 -35.085272)
					(end 118.385082 -34.602674)
				)
				(arc
					(start 118.293642 -34.602674)
					(mid 117.899942 -34.993842)
					(end 117.506242 -34.602674)
				)
				(arc
					(start 117.506242 -34.600134)
					(mid 117.899942 -34.206434)
					(end 118.293642 -34.600134)
				)
				(xy 118.385082 -34.600134) (xy 118.385082 -33.202626)
				(arc
					(start 118.293642 -33.202626)
					(mid 117.899942 -33.593794)
					(end 117.506242 -33.202626)
				)
				(arc
					(start 117.506242 -33.200086)
					(mid 117.899942 -32.806386)
					(end 118.293642 -33.200086)
				)
			)
		)
	)
	(zone
		(layers "F.Cu" "In2.Cu" "In5.Cu")
		(hatch none 0.5)
		(connect_pads
			(clearance 0)
		)
		(min_thickness 0.25)
		(keepout
			(tracks not_allowed)
			(vias allowed)
			(pads allowed)
			(copperpour not_allowed)
			(footprints allowed)
		)
		(placement
			(enabled no)
			(sheetname "")
		)
		(fill yes
			(thermal_gap 0.5)
			(thermal_bridge_width 0.5)
			(island_removal_mode 0)
		)
		(polygon
			(pts
				(arc
					(start 141.785086 -35.600132)
					(mid 141.299946 -35.114992)
					(end 140.814806 -35.600132)
				)
				(arc
					(start 140.814806 -37.00018)
					(mid 141.298676 -37.485318)
					(end 141.785086 -37.00272)
				)
				(arc
					(start 141.693646 -37.00272)
					(mid 141.299946 -37.393888)
					(end 140.906246 -37.00272)
				)
				(arc
					(start 140.906246 -37.00018)
					(mid 141.299946 -36.60648)
					(end 141.693646 -37.00018)
				)
				(xy 141.785086 -37.00018) (xy 141.785086 -35.602672)
				(arc
					(start 141.693646 -35.602672)
					(mid 141.299946 -35.99384)
					(end 140.906246 -35.602672)
				)
				(arc
					(start 140.906246 -35.600132)
					(mid 141.299946 -35.206432)
					(end 141.693646 -35.600132)
				)
			)
		)
	)
	(zone
		(layers "F.Cu" "In2.Cu" "In5.Cu")
		(hatch none 0.5)
		(connect_pads
			(clearance 0)
		)
		(min_thickness 0.25)
		(keepout
			(tracks not_allowed)
			(vias allowed)
			(pads allowed)
			(copperpour not_allowed)
			(footprints allowed)
		)
		(placement
			(enabled no)
			(sheetname "")
		)
		(fill yes
			(thermal_gap 0.5)
			(thermal_bridge_width 0.5)
			(island_removal_mode 0)
		)
		(polygon
			(pts
				(arc
					(start 138.185144 -35.600132)
					(mid 137.700004 -35.114992)
					(end 137.214864 -35.600132)
				)
				(arc
					(start 137.214864 -37.00018)
					(mid 137.698734 -37.485318)
					(end 138.185144 -37.00272)
				)
				(arc
					(start 138.093704 -37.00272)
					(mid 137.700004 -37.393888)
					(end 137.306304 -37.00272)
				)
				(arc
					(start 137.306304 -37.00018)
					(mid 137.700004 -36.60648)
					(end 138.093704 -37.00018)
				)
				(xy 138.185144 -37.00018) (xy 138.185144 -35.602672)
				(arc
					(start 138.093704 -35.602672)
					(mid 137.700004 -35.99384)
					(end 137.306304 -35.602672)
				)
				(arc
					(start 137.306304 -35.600132)
					(mid 137.700004 -35.206432)
					(end 138.093704 -35.600132)
				)
			)
		)
	)
	(zone
		(net "DDR_VREF")
		(layer "B.Cu")
		(hatch none 0.5)
		(connect_pads
			(clearance 0.5)
		)
		(min_thickness 0.25)
		(fill yes
			(thermal_gap 0.5)
			(thermal_bridge_width 0.5)
			(island_removal_mode 0)
		)
		(polygon
			(pts
				(xy 43.621706 -145.481548) (xy 43.230292 -145.872962) (xy 42.6974 -145.872962) (xy 42.62755 -145.942812)
				(xy 42.62755 -146.24939) (xy 42.678858 -146.300698) (xy 43.106594 -146.300698) (xy 43.26509 -146.459194)
				(xy 43.26509 -149.361906) (xy 43.332654 -149.42947) (xy 44.074334 -149.42947) (xy 44.102782 -149.401022)
				(xy 44.102782 -145.560288) (xy 44.024042 -145.481548)
			)
		)
		(polygon
			(pts
				(xy 43.612308 -145.988532) (xy 43.409108 -145.988532) (xy 43.409108 -146.191732) (xy 43.612308 -146.191732)
			)
		)
	)
	(zone
		(layer "B.Cu")
		(hatch none 0.5)
		(connect_pads
			(clearance 0)
		)
		(min_thickness 0.25)
		(keepout
			(tracks allowed)
			(vias allowed)
			(pads allowed)
			(copperpour allowed)
			(footprints not_allowed)
		)
		(placement
			(enabled no)
			(sheetname "")
		)
		(fill
			(thermal_gap 0.5)
			(thermal_bridge_width 0.5)
			(island_removal_mode 0)
		)
		(polygon
			(pts
				(arc
					(start 0.999998 0)
					(mid 0.292893 -0.292893)
					(end 0 -0.999998)
				)
				(arc
					(start 0 -183.76392)
					(mid 0.026764 -183.993728)
					(end 0.105664 -184.211214)
				)
				(arc
					(start 4.723638 -193.447162)
					(mid 4.843062 -193.631987)
					(end 4.99999 -193.786252)
				)
				(xy 4.99999 0)
			)
		)
	)
	(zone
		(layer "B.Cu")
		(hatch none 0.5)
		(connect_pads
			(clearance 0)
		)
		(min_thickness 0.25)
		(keepout
			(tracks not_allowed)
			(vias allowed)
			(pads allowed)
			(copperpour not_allowed)
			(footprints allowed)
		)
		(placement
			(enabled no)
			(sheetname "")
		)
		(fill
			(thermal_gap 0.5)
			(thermal_bridge_width 0.5)
			(island_removal_mode 0)
		)
		(polygon
			(pts
				(arc
					(start 83.300062 -105.050082)
					(mid 78.550008 -100.300028)
					(end 73.799954 -105.050082)
				)
				(arc
					(start 73.799954 -105.050082)
					(mid 78.550008 -109.800136)
					(end 83.300062 -105.050082)
				)
			)
		)
	)
	(zone
		(layer "B.Cu")
		(hatch none 0.5)
		(connect_pads
			(clearance 0)
		)
		(min_thickness 0.25)
		(keepout
			(tracks allowed)
			(vias allowed)
			(pads allowed)
			(copperpour allowed)
			(footprints allowed)
		)
		(placement
			(enabled no)
			(sheetname "")
		)
		(fill
			(thermal_gap 0.5)
			(thermal_bridge_width 0.5)
			(island_removal_mode 0)
		)
		(polygon
			(pts
				(xy 187.7568 -81.788) (xy 187.7568 -80.4926) (xy 188.849 -80.4926) (xy 188.849 -81.788)
			)
		)
	)
	(zone
		(net "P1V8")
		(layer "B.Cu")
		(hatch none 0.5)
		(connect_pads
			(clearance 0.5)
		)
		(min_thickness 0.25)
		(fill yes
			(thermal_gap 0.5)
			(thermal_bridge_width 0.5)
			(island_removal_mode 0)
		)
		(polygon
			(pts
				(xy 179.113942 -63.236348) (xy 178.825144 -63.525146) (xy 178.825144 -64.006984) (xy 178.59629 -64.235838)
				(xy 171.946062 -64.235838) (xy 171.4754 -64.7065) (xy 171.4754 -69.723) (xy 172.6184 -70.866) (xy 172.6184 -73.4568)
				(xy 172.0088 -74.0664) (xy 168.9862 -74.0664) (xy 167.5003 -75.5523) (xy 167.5003 -76.1111) (xy 167.1828 -76.4286)
				(xy 165.3286 -76.4286) (xy 165.1 -76.2) (xy 165.1 -75.8952) (xy 164.9857 -75.7809) (xy 164.5285 -75.7809)
				(xy 164.3888 -75.9206) (xy 164.3888 -76.844398) (xy 166.826692 -79.28229) (xy 170.3832 -79.28229)
				(xy 170.3832 -77.851) (xy 170.3324 -77.8002) (xy 169.6974 -77.8002) (xy 169.418 -77.5208) (xy 169.418 -75.819)
				(xy 169.926 -75.311) (xy 173.482 -75.311) (xy 173.776132 -75.016868) (xy 173.776132 -73.295256)
				(xy 174.443644 -72.627744) (xy 174.443644 -66.843656) (xy 174.7266 -66.5607) (xy 176.6951 -66.5607)
				(xy 176.9618 -66.8274) (xy 180.023516 -66.8274) (xy 180.023516 -66.355976) (xy 179.85994 -66.1924)
				(xy 178.9938 -66.1924) (xy 178.985672 -66.184272) (xy 178.509676 -66.184272) (xy 178.444652 -66.119248)
				(xy 178.444652 -65.05956) (xy 178.669442 -64.83477) (xy 180.61051 -64.83477) (xy 180.70576 -64.73952)
				(xy 180.70576 -64.2112) (xy 180.69306 -64.2112) (xy 179.718208 -63.236348)
			)
		)
		(polygon
			(pts
				(xy 170.0022 -78.2574) (xy 169.799 -78.2574) (xy 169.799 -78.4606) (xy 170.0022 -78.4606)
			)
		)
		(polygon
			(pts
				(xy 166.10711 -76.877164) (xy 165.90391 -76.877164) (xy 165.90391 -77.080364) (xy 166.10711 -77.080364)
			)
		)
		(polygon
			(pts
				(xy 165.54831 -76.877164) (xy 165.34511 -76.877164) (xy 165.34511 -77.080364) (xy 165.54831 -77.080364)
			)
		)
		(polygon
			(pts
				(xy 167.17391 -76.851764) (xy 166.97071 -76.851764) (xy 166.97071 -77.054964) (xy 167.17391 -77.054964)
			)
		)
		(polygon
			(pts
				(xy 166.61511 -76.851764) (xy 166.41191 -76.851764) (xy 166.41191 -77.054964) (xy 166.61511 -77.054964)
			)
		)
		(polygon
			(pts
				(xy 173.9646 -68.5546) (xy 173.7614 -68.5546) (xy 173.7614 -68.7578) (xy 173.9646 -68.7578)
			)
		)
		(polygon
			(pts
				(xy 173.9646 -67.9958) (xy 173.7614 -67.9958) (xy 173.7614 -68.199) (xy 173.9646 -68.199)
			)
		)
		(polygon
			(pts
				(xy 173.9646 -67.5132) (xy 173.7614 -67.5132) (xy 173.7614 -67.7164) (xy 173.9646 -67.7164)
			)
		)
		(polygon
			(pts
				(xy 173.9646 -66.9544) (xy 173.7614 -66.9544) (xy 173.7614 -67.1576) (xy 173.9646 -67.1576)
			)
		)
		(polygon
			(pts
				(xy 180.256942 -64.105282) (xy 180.053742 -64.105282) (xy 180.053742 -64.308482) (xy 180.256942 -64.308482)
			)
		)
	)
	(zone
		(net "GND")
		(layer "B.Cu")
		(hatch none 0.5)
		(connect_pads
			(clearance 0.5)
		)
		(min_thickness 0.25)
		(fill yes
			(thermal_gap 0.5)
			(thermal_bridge_width 0.5)
			(island_removal_mode 0)
		)
		(polygon
			(pts
				(xy 44.330366 -146.986244) (xy 44.238418 -147.078192) (xy 44.238418 -149.427184) (xy 44.102782 -149.56282)
				(xy 42.724832 -149.56282) (xy 42.606722 -149.68093) (xy 42.606722 -149.897338) (xy 42.692066 -149.982682)
				(xy 44.815506 -149.982682) (xy 44.907454 -149.890734) (xy 44.907454 -147.030186) (xy 44.863512 -146.986244)
			)
		)
	)
	(zone
		(layer "B.Cu")
		(hatch none 0.5)
		(connect_pads
			(clearance 0)
		)
		(min_thickness 0.25)
		(keepout
			(tracks allowed)
			(vias allowed)
			(pads allowed)
			(copperpour allowed)
			(footprints allowed)
		)
		(placement
			(enabled no)
			(sheetname "")
		)
		(fill
			(thermal_gap 0.5)
			(thermal_bridge_width 0.5)
			(island_removal_mode 0)
		)
		(polygon
			(pts
				(xy 165.0746 -37.7444) (xy 166.1668 -37.7444) (xy 166.1668 -39.116) (xy 165.0746 -39.116)
			)
		)
	)
	(zone
		(net "GND")
		(layer "B.Cu")
		(hatch none 0.5)
		(connect_pads
			(clearance 0.5)
		)
		(min_thickness 0.25)
		(fill yes
			(thermal_gap 0.5)
			(thermal_bridge_width 0.5)
			(island_removal_mode 0)
		)
		(polygon
			(pts
				(xy 196.1134 -48.9712) (xy 195.9356 -49.149) (xy 195.9356 -52.088288) (xy 195.344288 -52.6796) (xy 194.9704 -52.6796)
				(xy 194.8942 -52.7558) (xy 194.8942 -53.2638) (xy 194.945 -53.3146) (xy 195.4276 -53.3146) (xy 195.600066 -53.487066)
				(xy 195.600066 -54.945534) (xy 195.3514 -55.1942) (xy 194.6402 -55.1942) (xy 194.185032 -55.649368)
				(xy 194.185032 -56.591962) (xy 193.970148 -56.806846) (xy 193.20891 -56.806846) (xy 193.08699 -56.684926)
				(xy 193.08699 -56.559704) (xy 193.092832 -56.553862) (xy 193.092832 -56.074056) (xy 193.042032 -56.023256)
				(xy 192.661032 -56.023256) (xy 192.541398 -56.14289) (xy 192.541398 -56.5531) (xy 192.300352 -56.794146)
				(xy 190.872618 -56.794146) (xy 190.68288 -56.604408) (xy 190.68288 -55.351934) (xy 190.598298 -55.267352)
				(xy 190.114936 -55.267352) (xy 190.044832 -55.337456) (xy 190.044832 -56.455056) (xy 190.043816 -56.456072)
				(xy 190.043816 -56.62295) (xy 189.941708 -56.725058) (xy 189.22492 -56.725058) (xy 189.067694 -56.567832)
				(xy 189.067694 -55.579518) (xy 188.749432 -55.261256) (xy 188.216032 -55.261256) (xy 188.114432 -55.362856)
				(xy 188.114432 -55.921656) (xy 188.393832 -56.201056) (xy 188.393832 -56.817768) (xy 188.28258 -56.92902)
				(xy 187.56376 -56.92902) (xy 187.49518 -56.86044) (xy 187.49518 -56.12892) (xy 187.4012 -56.03494)
				(xy 187.03798 -56.03494) (xy 186.93892 -56.134) (xy 186.93892 -56.68518) (xy 186.70016 -56.92394)
				(xy 186.07532 -56.92394) (xy 186.01436 -56.9849) (xy 186.01436 -58.89244) (xy 186.0042 -58.89244)
				(xy 185.646822 -59.249818) (xy 185.151014 -59.249818) (xy 184.914032 -59.012836) (xy 184.914032 -58.603896)
				(xy 184.802018 -58.491882) (xy 184.186576 -58.491882) (xy 184.126124 -58.552334) (xy 184.126124 -59.017408)
				(xy 184.3151 -59.206384) (xy 184.3151 -70.104) (xy 184.4167 -70.2056) (xy 192.4685 -70.2056) (xy 193.3575 -71.0946)
				(xy 196.6087 -71.0946) (xy 196.6976 -71.0057) (xy 197.7263 -71.0057) (xy 197.8533 -70.8787) (xy 197.8533 -69.723)
				(xy 197.5866 -69.4563) (xy 194.818 -69.4563) (xy 194.7418 -69.3801) (xy 194.7418 -67.3608) (xy 194.84975 -67.25285)
				(xy 194.84975 -66.24955) (xy 194.691 -66.0908) (xy 194.691 -62.5221) (xy 194.9831 -62.23) (xy 195.2752 -62.23)
				(xy 195.5038 -62.0014) (xy 195.5038 -60.7695) (xy 194.66306 -59.92876) (xy 194.66306 -56.68264)
				(xy 194.72148 -56.62422) (xy 196.29374 -56.62422) (xy 196.598032 -56.928512) (xy 196.598032 -59.819032)
				(xy 197.57136 -60.79236) (xy 197.57136 -62.40018) (xy 197.38594 -62.5856) (xy 197.38594 -64.389)
				(xy 197.1167 -64.65824) (xy 197.1167 -64.9859) (xy 196.9262 -65.1764) (xy 196.4944 -65.1764) (xy 196.2912 -64.9732)
				(xy 196.2912 -63.1952) (xy 196.1642 -63.0682) (xy 195.7324 -63.0682) (xy 195.6943 -63.1063) (xy 195.6943 -64.5541)
				(xy 195.6054 -64.643) (xy 195.6054 -65.8749) (xy 195.92036 -66.18986) (xy 195.92036 -66.86296) (xy 196.1642 -67.1068)
				(xy 196.6595 -67.1068) (xy 196.9643 -66.802) (xy 196.9643 -66.3702) (xy 197.14464 -66.18986) (xy 198.87438 -66.18986)
				(xy 198.96328 -66.27876) (xy 199.49668 -66.27876) (xy 199.50303 -66.27241) (xy 200.87717 -66.27241)
				(xy 201.0283 -66.12128) (xy 201.0283 -65.72758) (xy 200.87844 -65.57772) (xy 200.65746 -65.57772)
				(xy 200.63714 -65.59804) (xy 199.80148 -65.59804) (xy 199.53097 -65.32753) (xy 199.53097 -64.456564)
				(xy 199.547734 -64.4398) (xy 199.547734 -64.1096) (xy 199.408034 -63.9699) (xy 198.882 -63.9699)
				(xy 198.7296 -63.8175) (xy 198.7296 -62.9539) (xy 199.484234 -62.9539) (xy 199.547734 -62.8904)
				(xy 199.547734 -61.741812) (xy 199.548496 -61.740796) (xy 199.548496 -60.814204) (xy 200.12406 -60.23864)
				(xy 200.22312 -60.23864) (xy 200.373488 -60.088272) (xy 200.373488 -55.923688) (xy 200.807066 -55.489856)
				(xy 200.807066 -54.854856) (xy 200.874122 -54.7878) (xy 205.9686 -54.7878) (xy 206.0956 -54.6608)
				(xy 206.0956 -53.834792) (xy 205.507844 -53.247036) (xy 204.834998 -53.247036) (xy 204.675232 -53.08727)
				(xy 204.675232 -49.333658) (xy 204.416406 -49.074832) (xy 203.272136 -49.074832) (xy 203.272136 -50.603658)
				(xy 203.667106 -50.998628) (xy 203.667106 -51.837844) (xy 203.670408 -51.840892) (xy 203.38034 -52.13096)
				(xy 203.38034 -53.476398) (xy 203.15682 -53.699918) (xy 201.31151 -53.699918) (xy 201.247248 -53.635656)
				(xy 201.247248 -53.63337) (xy 201.138028 -53.52415) (xy 201.13752 -53.52415) (xy 200.99401 -53.38064)
				(xy 200.99401 -49.29505) (xy 200.782936 -49.083976) (xy 199.610218 -49.083976) (xy 199.631554 -49.105312)
				(xy 199.631554 -52.0065) (xy 199.72782 -52.102766) (xy 199.72782 -52.676298) (xy 199.064118 -53.34)
				(xy 197.680834 -53.34) (xy 197.5104 -53.169566) (xy 197.5104 -49.276) (xy 197.2056 -48.9712)
			)
		)
		(polygon
			(pts
				(xy 197.1802 -70.4596) (xy 196.977 -70.4596) (xy 196.977 -70.6628) (xy 197.1802 -70.6628)
			)
		)
		(polygon
			(pts
				(xy 196.8246 -70.4596) (xy 196.6214 -70.4596) (xy 196.6214 -70.6628) (xy 196.8246 -70.6628)
			)
		)
		(polygon
			(pts
				(xy 192.5574 -69.7357) (xy 192.3542 -69.7357) (xy 192.3542 -69.9389) (xy 192.5574 -69.9389)
			)
		)
		(polygon
			(pts
				(xy 192.2018 -69.7357) (xy 191.7954 -69.7357) (xy 191.7954 -69.9389) (xy 192.2018 -69.9389)
			)
		)
		(polygon
			(pts
				(xy 191.643 -69.7357) (xy 191.4398 -69.7357) (xy 191.4398 -69.9389) (xy 191.643 -69.9389)
			)
		)
		(polygon
			(pts
				(xy 185.4962 -69.4944) (xy 185.293 -69.4944) (xy 185.293 -69.6976) (xy 185.4962 -69.6976)
			)
		)
		(polygon
			(pts
				(xy 194.5894 -68.5292) (xy 194.3862 -68.5292) (xy 194.3862 -68.7324) (xy 194.5894 -68.7324)
			)
		)
		(polygon
			(pts
				(xy 190.4619 -68.5038) (xy 190.2587 -68.5038) (xy 190.2587 -68.707) (xy 190.4619 -68.707)
			)
		)
		(polygon
			(pts
				(xy 184.978802 -68.453508) (xy 184.775602 -68.453508) (xy 184.775602 -68.656708) (xy 184.978802 -68.656708)
			)
		)
		(polygon
			(pts
				(xy 194.5894 -67.9196) (xy 194.3862 -67.9196) (xy 194.3862 -68.1228) (xy 194.5894 -68.1228)
			)
		)
		(polygon
			(pts
				(xy 190.4619 -67.8942) (xy 190.2587 -67.8942) (xy 190.2587 -68.0974) (xy 190.4619 -68.0974)
			)
		)
		(polygon
			(pts
				(xy 184.978802 -67.843908) (xy 184.775602 -67.843908) (xy 184.775602 -68.047108) (xy 184.978802 -68.047108)
			)
		)
		(polygon
			(pts
				(xy 184.8866 -66.8274) (xy 184.6834 -66.8274) (xy 184.6834 -67.0306) (xy 184.8866 -67.0306)
			)
		)
		(polygon
			(pts
				(xy 184.8866 -66.2178) (xy 184.6834 -66.2178) (xy 184.6834 -66.421) (xy 184.8866 -66.421)
			)
		)
		(polygon
			(pts
				(xy 196.7992 -66.2051) (xy 196.596 -66.2051) (xy 196.596 -66.4083) (xy 196.7992 -66.4083)
			)
		)
		(polygon
			(pts
				(xy 200.14692 -65.70726) (xy 199.94372 -65.70726) (xy 199.94372 -65.91046) (xy 200.14692 -65.91046)
			)
		)
		(polygon
			(pts
				(xy 199.79132 -65.70726) (xy 199.58812 -65.70726) (xy 199.58812 -65.91046) (xy 199.79132 -65.91046)
			)
		)
		(polygon
			(pts
				(xy 198.80072 -65.66916) (xy 198.59752 -65.66916) (xy 198.59752 -65.87236) (xy 198.80072 -65.87236)
			)
		)
		(polygon
			(pts
				(xy 198.44512 -65.66916) (xy 198.24192 -65.66916) (xy 198.24192 -65.87236) (xy 198.44512 -65.87236)
			)
		)
		(polygon
			(pts
				(xy 196.9643 -65.4939) (xy 196.7611 -65.4939) (xy 196.7611 -65.6971) (xy 196.9643 -65.6971)
			)
		)
		(polygon
			(pts
				(xy 196.6087 -65.4939) (xy 196.4055 -65.4939) (xy 196.4055 -65.6971) (xy 196.6087 -65.6971)
			)
		)
		(polygon
			(pts
				(xy 194.564 -65.4558) (xy 194.3608 -65.4558) (xy 194.3608 -65.659) (xy 194.564 -65.659)
			)
		)
		(polygon
			(pts
				(xy 192.9892 -65.4558) (xy 192.786 -65.4558) (xy 192.786 -65.659) (xy 192.9892 -65.659)
			)
		)
		(polygon
			(pts
				(xy 192.024 -65.4558) (xy 191.8208 -65.4558) (xy 191.8208 -65.659) (xy 192.024 -65.659)
			)
		)
		(polygon
			(pts
				(xy 191.4017 -65.4558) (xy 191.1985 -65.4558) (xy 191.1985 -65.659) (xy 191.4017 -65.659)
			)
		)
		(polygon
			(pts
				(xy 190.4365 -65.4558) (xy 190.2333 -65.4558) (xy 190.2333 -65.659) (xy 190.4365 -65.659)
			)
		)
		(polygon
			(pts
				(xy 189.8396 -65.4558) (xy 189.6364 -65.4558) (xy 189.6364 -65.659) (xy 189.8396 -65.659)
			)
		)
		(polygon
			(pts
				(xy 188.8744 -65.4558) (xy 188.6712 -65.4558) (xy 188.6712 -65.659) (xy 188.8744 -65.659)
			)
		)
		(polygon
			(pts
				(xy 196.1134 -65.4431) (xy 195.9102 -65.4431) (xy 195.9102 -65.6463) (xy 196.1134 -65.6463)
			)
		)
		(polygon
			(pts
				(xy 184.9247 -65.3669) (xy 184.7215 -65.3669) (xy 184.7215 -65.5701) (xy 184.9247 -65.5701)
			)
		)
		(polygon
			(pts
				(xy 194.564 -64.897) (xy 194.3608 -64.897) (xy 194.3608 -65.3034) (xy 194.564 -65.3034)
			)
		)
		(polygon
			(pts
				(xy 192.9892 -64.897) (xy 192.786 -64.897) (xy 192.786 -65.3034) (xy 192.9892 -65.3034)
			)
		)
		(polygon
			(pts
				(xy 192.024 -64.897) (xy 191.8208 -64.897) (xy 191.8208 -65.3034) (xy 192.024 -65.3034)
			)
		)
		(polygon
			(pts
				(xy 191.4017 -64.897) (xy 191.1985 -64.897) (xy 191.1985 -65.3034) (xy 191.4017 -65.3034)
			)
		)
		(polygon
			(pts
				(xy 190.4365 -64.897) (xy 190.2333 -64.897) (xy 190.2333 -65.3034) (xy 190.4365 -65.3034)
			)
		)
		(polygon
			(pts
				(xy 189.8396 -64.897) (xy 189.6364 -64.897) (xy 189.6364 -65.3034) (xy 189.8396 -65.3034)
			)
		)
		(polygon
			(pts
				(xy 188.8744 -64.897) (xy 188.6712 -64.897) (xy 188.6712 -65.3034) (xy 188.8744 -65.3034)
			)
		)
		(polygon
			(pts
				(xy 196.1134 -64.8843) (xy 195.9102 -64.8843) (xy 195.9102 -65.2907) (xy 196.1134 -65.2907)
			)
		)
		(polygon
			(pts
				(xy 184.9247 -64.7573) (xy 184.7215 -64.7573) (xy 184.7215 -64.9605) (xy 184.9247 -64.9605)
			)
		)
		(polygon
			(pts
				(xy 194.564 -64.5414) (xy 194.3608 -64.5414) (xy 194.3608 -64.7446) (xy 194.564 -64.7446)
			)
		)
		(polygon
			(pts
				(xy 192.9892 -64.5414) (xy 192.786 -64.5414) (xy 192.786 -64.7446) (xy 192.9892 -64.7446)
			)
		)
		(polygon
			(pts
				(xy 192.024 -64.5414) (xy 191.8208 -64.5414) (xy 191.8208 -64.7446) (xy 192.024 -64.7446)
			)
		)
		(polygon
			(pts
				(xy 191.4017 -64.5414) (xy 191.1985 -64.5414) (xy 191.1985 -64.7446) (xy 191.4017 -64.7446)
			)
		)
		(polygon
			(pts
				(xy 190.4365 -64.5414) (xy 190.2333 -64.5414) (xy 190.2333 -64.7446) (xy 190.4365 -64.7446)
			)
		)
		(polygon
			(pts
				(xy 189.8396 -64.5414) (xy 189.6364 -64.5414) (xy 189.6364 -64.7446) (xy 189.8396 -64.7446)
			)
		)
		(polygon
			(pts
				(xy 188.8744 -64.5414) (xy 188.6712 -64.5414) (xy 188.6712 -64.7446) (xy 188.8744 -64.7446)
			)
		)
		(polygon
			(pts
				(xy 196.1134 -64.5287) (xy 195.9102 -64.5287) (xy 195.9102 -64.7319) (xy 196.1134 -64.7319)
			)
		)
		(polygon
			(pts
				(xy 198.1581 -64.2239) (xy 197.9549 -64.2239) (xy 197.9549 -64.4271) (xy 198.1581 -64.4271)
			)
		)
		(polygon
			(pts
				(xy 196.1769 -63.86576) (xy 195.9737 -63.86576) (xy 195.9737 -64.06896) (xy 196.1769 -64.06896)
			)
		)
		(polygon
			(pts
				(xy 194.5513 -63.8556) (xy 194.3481 -63.8556) (xy 194.3481 -64.0588) (xy 194.5513 -64.0588)
			)
		)
		(polygon
			(pts
				(xy 193.0019 -63.8556) (xy 192.7987 -63.8556) (xy 192.7987 -64.0588) (xy 193.0019 -64.0588)
			)
		)
		(polygon
			(pts
				(xy 192.0367 -63.8556) (xy 191.8335 -63.8556) (xy 191.8335 -64.0588) (xy 192.0367 -64.0588)
			)
		)
		(polygon
			(pts
				(xy 191.4398 -63.8556) (xy 191.2366 -63.8556) (xy 191.2366 -64.0588) (xy 191.4398 -64.0588)
			)
		)
		(polygon
			(pts
				(xy 190.4746 -63.8556) (xy 190.2714 -63.8556) (xy 190.2714 -64.0588) (xy 190.4746 -64.0588)
			)
		)
		(polygon
			(pts
				(xy 184.99836 -63.6651) (xy 184.79516 -63.6651) (xy 184.79516 -63.8683) (xy 184.99836 -63.8683)
			)
		)
		(polygon
			(pts
				(xy 198.1581 -63.5127) (xy 197.9549 -63.5127) (xy 197.9549 -63.7159) (xy 198.1581 -63.7159)
			)
		)
		(polygon
			(pts
				(xy 196.1769 -63.30696) (xy 195.9737 -63.30696) (xy 195.9737 -63.71336) (xy 196.1769 -63.71336)
			)
		)
		(polygon
			(pts
				(xy 194.5513 -63.2968) (xy 194.3481 -63.2968) (xy 194.3481 -63.7032) (xy 194.5513 -63.7032)
			)
		)
		(polygon
			(pts
				(xy 193.0019 -63.2968) (xy 192.7987 -63.2968) (xy 192.7987 -63.7032) (xy 193.0019 -63.7032)
			)
		)
		(polygon
			(pts
				(xy 192.0367 -63.2968) (xy 191.8335 -63.2968) (xy 191.8335 -63.7032) (xy 192.0367 -63.7032)
			)
		)
		(polygon
			(pts
				(xy 191.4398 -63.2968) (xy 191.2366 -63.2968) (xy 191.2366 -63.7032) (xy 191.4398 -63.7032)
			)
		)
		(polygon
			(pts
				(xy 190.4746 -63.2968) (xy 190.2714 -63.2968) (xy 190.2714 -63.7032) (xy 190.4746 -63.7032)
			)
		)
		(polygon
			(pts
				(xy 184.99836 -63.0555) (xy 184.79516 -63.0555) (xy 184.79516 -63.2587) (xy 184.99836 -63.2587)
			)
		)
		(polygon
			(pts
				(xy 194.5513 -62.9412) (xy 194.3481 -62.9412) (xy 194.3481 -63.1444) (xy 194.5513 -63.1444)
			)
		)
		(polygon
			(pts
				(xy 193.0019 -62.9412) (xy 192.7987 -62.9412) (xy 192.7987 -63.1444) (xy 193.0019 -63.1444)
			)
		)
		(polygon
			(pts
				(xy 192.0367 -62.9412) (xy 191.8335 -62.9412) (xy 191.8335 -63.1444) (xy 192.0367 -63.1444)
			)
		)
		(polygon
			(pts
				(xy 191.4398 -62.9412) (xy 191.2366 -62.9412) (xy 191.2366 -63.1444) (xy 191.4398 -63.1444)
			)
		)
		(polygon
			(pts
				(xy 190.4746 -62.9412) (xy 190.2714 -62.9412) (xy 190.2714 -63.1444) (xy 190.4746 -63.1444)
			)
		)
		(polygon
			(pts
				(xy 188.8871 -62.2681) (xy 188.6839 -62.2681) (xy 188.6839 -62.4713) (xy 188.8871 -62.4713)
			)
		)
		(polygon
			(pts
				(xy 191.416178 -62.25667) (xy 191.212978 -62.25667) (xy 191.212978 -62.45987) (xy 191.416178 -62.45987)
			)
		)
		(polygon
			(pts
				(xy 190.450978 -62.25667) (xy 190.247778 -62.25667) (xy 190.247778 -62.45987) (xy 190.450978 -62.45987)
			)
		)
		(polygon
			(pts
				(xy 194.564 -62.2554) (xy 194.3608 -62.2554) (xy 194.3608 -62.4586) (xy 194.564 -62.4586)
			)
		)
		(polygon
			(pts
				(xy 192.9892 -62.2554) (xy 192.786 -62.2554) (xy 192.786 -62.4586) (xy 192.9892 -62.4586)
			)
		)
		(polygon
			(pts
				(xy 192.024 -62.2554) (xy 191.8208 -62.2554) (xy 191.8208 -62.4586) (xy 192.024 -62.4586)
			)
		)
		(polygon
			(pts
				(xy 185.05678 -62.103) (xy 184.85358 -62.103) (xy 184.85358 -62.3062) (xy 185.05678 -62.3062)
			)
		)
		(polygon
			(pts
				(xy 194.564 -61.6966) (xy 194.3608 -61.6966) (xy 194.3608 -62.103) (xy 194.564 -62.103)
			)
		)
		(polygon
			(pts
				(xy 192.9892 -61.6966) (xy 192.786 -61.6966) (xy 192.786 -62.103) (xy 192.9892 -62.103)
			)
		)
		(polygon
			(pts
				(xy 192.024 -61.6966) (xy 191.8208 -61.6966) (xy 191.8208 -62.103) (xy 192.024 -62.103)
			)
		)
		(polygon
			(pts
				(xy 191.4144 -61.6966) (xy 191.2112 -61.6966) (xy 191.2112 -61.8998) (xy 191.212978 -61.90107) (xy 191.212978 -62.10427)
				(xy 191.416178 -62.10427) (xy 191.416178 -61.90107) (xy 191.4144 -61.8998)
			)
		)
		(polygon
			(pts
				(xy 190.4492 -61.6966) (xy 190.246 -61.6966) (xy 190.246 -61.8998) (xy 190.247778 -61.90107) (xy 190.247778 -62.10427)
				(xy 190.450978 -62.10427) (xy 190.450978 -61.90107) (xy 190.4492 -61.8998)
			)
		)
		(polygon
			(pts
				(xy 188.8871 -61.6966) (xy 188.6839 -61.6966) (xy 188.6839 -62.1157) (xy 188.8871 -62.1157)
			)
		)
		(polygon
			(pts
				(xy 185.05678 -61.4934) (xy 184.85358 -61.4934) (xy 184.85358 -61.6966) (xy 185.05678 -61.6966)
			)
		)
		(polygon
			(pts
				(xy 192.9892 -61.341) (xy 192.786 -61.341) (xy 192.786 -61.5442) (xy 192.9892 -61.5442)
			)
		)
		(polygon
			(pts
				(xy 192.024 -61.341) (xy 191.8208 -61.341) (xy 191.8208 -61.5442) (xy 192.024 -61.5442)
			)
		)
		(polygon
			(pts
				(xy 191.4144 -61.341) (xy 191.2112 -61.341) (xy 191.2112 -61.5442) (xy 191.4144 -61.5442)
			)
		)
		(polygon
			(pts
				(xy 190.4492 -61.341) (xy 190.246 -61.341) (xy 190.246 -61.5442) (xy 190.4492 -61.5442)
			)
		)
		(polygon
			(pts
				(xy 188.8871 -61.341) (xy 188.6839 -61.341) (xy 188.6839 -61.5442) (xy 188.8871 -61.5442)
			)
		)
		(polygon
			(pts
				(xy 184.919366 -60.582556) (xy 184.716166 -60.582556) (xy 184.716166 -60.785756) (xy 184.919366 -60.785756)
			)
		)
		(polygon
			(pts
				(xy 184.919366 -59.972956) (xy 184.716166 -59.972956) (xy 184.716166 -60.176156) (xy 184.919366 -60.176156)
			)
		)
		(polygon
			(pts
				(xy 199.7329 -59.83478) (xy 199.5297 -59.83478) (xy 199.5297 -60.03798) (xy 199.7329 -60.03798)
			)
		)
		(polygon
			(pts
				(xy 197.2818 -59.6138) (xy 197.0786 -59.6138) (xy 197.0786 -59.817) (xy 197.2818 -59.817)
			)
		)
		(polygon
			(pts
				(xy 197.2818 -59.0042) (xy 197.0786 -59.0042) (xy 197.0786 -59.2074) (xy 197.2818 -59.2074)
			)
		)
		(polygon
			(pts
				(xy 199.7329 -58.9661) (xy 199.5297 -58.9661) (xy 199.5297 -59.42838) (xy 199.7329 -59.42838)
			)
		)
		(polygon
			(pts
				(xy 186.83224 -58.83656) (xy 186.62904 -58.83656) (xy 186.62904 -59.03976) (xy 186.83224 -59.03976)
			)
		)
		(polygon
			(pts
				(xy 199.7329 -58.0898) (xy 199.5297 -58.0898) (xy 199.5297 -58.5597) (xy 199.7329 -58.5597)
			)
		)
		(polygon
			(pts
				(xy 186.83478 -57.9628) (xy 186.63158 -57.9628) (xy 186.63158 -58.166) (xy 186.62904 -58.22696)
				(xy 186.62904 -58.43016) (xy 186.83224 -58.43016) (xy 186.83224 -58.22696) (xy 186.83478 -58.166)
			)
		)
		(polygon
			(pts
				(xy 186.83478 -57.3532) (xy 186.63158 -57.3532) (xy 186.63158 -57.5564) (xy 186.83478 -57.5564)
			)
		)
		(polygon
			(pts
				(xy 199.771 -57.2008) (xy 199.5678 -57.2008) (xy 199.5678 -57.404) (xy 199.5297 -57.4802) (xy 199.5297 -57.6834)
				(xy 199.7329 -57.6834) (xy 199.7329 -57.4802) (xy 199.771 -57.404)
			)
		)
		(polygon
			(pts
				(xy 188.849 -55.7784) (xy 188.6458 -55.7784) (xy 188.6458 -55.9816) (xy 188.849 -55.9816)
			)
		)
		(polygon
			(pts
				(xy 200.690226 -54.984396) (xy 200.487026 -54.984396) (xy 200.487026 -55.187596) (xy 200.690226 -55.187596)
			)
		)
		(polygon
			(pts
				(xy 198.7804 -54.737) (xy 198.5772 -54.737) (xy 198.5772 -55.1942) (xy 198.7804 -55.1942)
			)
		)
		(polygon
			(pts
				(xy 198.7804 -54.1274) (xy 198.5772 -54.1274) (xy 198.5772 -54.3306) (xy 198.7804 -54.3306)
			)
		)
		(polygon
			(pts
				(xy 205.18374 -54.08676) (xy 204.98054 -54.08676) (xy 204.98054 -54.28996) (xy 205.18374 -54.28996)
			)
		)
		(polygon
			(pts
				(xy 204.2795 -54.08422) (xy 204.0763 -54.08422) (xy 204.0763 -54.28742) (xy 204.2795 -54.28742)
				(xy 204.37094 -54.28996) (xy 204.57414 -54.28996) (xy 204.57414 -54.08676) (xy 204.37094 -54.08676)
			)
		)
		(polygon
			(pts
				(xy 203.6699 -54.08422) (xy 203.4667 -54.08422) (xy 203.4032 -54.0893) (xy 203.2 -54.0893) (xy 203.2 -54.2925)
				(xy 203.4032 -54.2925) (xy 203.4667 -54.28742) (xy 203.6699 -54.28742)
			)
		)
		(polygon
			(pts
				(xy 202.519026 -54.082696) (xy 202.315826 -54.082696) (xy 202.315826 -54.285896) (xy 202.519026 -54.285896)
				(xy 202.5904 -54.2925) (xy 202.7936 -54.2925) (xy 202.7936 -54.0893) (xy 202.5904 -54.0893)
			)
		)
		(polygon
			(pts
				(xy 201.642726 -54.075076) (xy 201.439526 -54.075076) (xy 201.439526 -54.278276) (xy 201.642726 -54.278276)
				(xy 201.706226 -54.285896) (xy 201.909426 -54.285896) (xy 201.909426 -54.082696) (xy 201.706226 -54.082696)
			)
		)
		(polygon
			(pts
				(xy 201.033126 -54.075076) (xy 200.829926 -54.075076) (xy 200.829926 -54.278276) (xy 201.033126 -54.278276)
			)
		)
		(polygon
			(pts
				(xy 197.1802 -53.086) (xy 196.977 -53.086) (xy 196.977 -53.2892) (xy 197.1802 -53.2892)
			)
		)
		(polygon
			(pts
				(xy 200.711308 -53.045868) (xy 200.508108 -53.045868) (xy 200.508108 -53.249068) (xy 200.711308 -53.249068)
			)
		)
		(polygon
			(pts
				(xy 204.382624 -53.000402) (xy 204.179424 -53.000402) (xy 204.179424 -53.203602) (xy 204.382624 -53.203602)
			)
		)
		(polygon
			(pts
				(xy 197.1802 -52.5272) (xy 196.977 -52.5272) (xy 196.977 -52.9336) (xy 197.1802 -52.9336)
			)
		)
		(polygon
			(pts
				(xy 204.397864 -52.41163) (xy 204.194664 -52.41163) (xy 204.194664 -52.61483) (xy 204.179424 -52.644802)
				(xy 204.179424 -52.848002) (xy 204.382624 -52.848002) (xy 204.382624 -52.644802) (xy 204.397864 -52.61483)
			)
		)
		(polygon
			(pts
				(xy 200.711308 -52.410868) (xy 200.508108 -52.410868) (xy 200.508108 -52.893468) (xy 200.711308 -52.893468)
			)
		)
		(polygon
			(pts
				(xy 197.1802 -52.1716) (xy 196.977 -52.1716) (xy 196.977 -52.3748) (xy 197.1802 -52.3748)
			)
		)
		(polygon
			(pts
				(xy 204.397864 -52.05603) (xy 204.194664 -52.05603) (xy 204.194664 -52.25923) (xy 204.397864 -52.25923)
			)
		)
		(polygon
			(pts
				(xy 200.711308 -52.055268) (xy 200.508108 -52.055268) (xy 200.508108 -52.258468) (xy 200.711308 -52.258468)
			)
		)
		(polygon
			(pts
				(xy 200.135998 -51.769772) (xy 199.932798 -51.769772) (xy 199.932798 -51.972972) (xy 200.135998 -51.972972)
			)
		)
		(polygon
			(pts
				(xy 197.3834 -51.7652) (xy 197.1802 -51.7652) (xy 197.1802 -51.9684) (xy 197.3834 -51.9684)
			)
		)
		(polygon
			(pts
				(xy 196.5198 -51.7652) (xy 196.3166 -51.7652) (xy 196.3166 -51.9684) (xy 196.5198 -51.9684)
			)
		)
		(polygon
			(pts
				(xy 200.135998 -50.906172) (xy 199.932798 -50.906172) (xy 199.932798 -51.109372) (xy 200.135998 -51.109372)
			)
		)
		(polygon
			(pts
				(xy 197.3834 -50.9016) (xy 197.1802 -50.9016) (xy 197.1802 -51.1048) (xy 197.3834 -51.1048)
			)
		)
		(polygon
			(pts
				(xy 196.5198 -50.9016) (xy 196.3166 -50.9016) (xy 196.3166 -51.1048) (xy 196.5198 -51.1048)
			)
		)
	)
	(zone
		(layer "B.Cu")
		(hatch none 0.5)
		(connect_pads
			(clearance 0)
		)
		(min_thickness 0.25)
		(keepout
			(tracks not_allowed)
			(vias allowed)
			(pads allowed)
			(copperpour not_allowed)
			(footprints allowed)
		)
		(placement
			(enabled no)
			(sheetname "")
		)
		(fill
			(thermal_gap 0.5)
			(thermal_bridge_width 0.5)
			(island_removal_mode 0)
		)
		(polygon
			(pts
				(xy 180.059584 -22.389592) (xy 179.83581 -22.165818) (xy 179.822602 -22.159214) (xy 179.821332 -22.159722)
				(xy 179.79517 -22.145498) (xy 179.768246 -22.132036) (xy 179.767992 -22.130766) (xy 179.766722 -22.130004)
				(xy 179.75834 -22.101302) (xy 179.748942 -22.073108) (xy 179.74945 -22.071838) (xy 179.707794 -21.932392)
				(xy 179.698904 -21.902674) (xy 179.699158 -21.902674) (xy 179.698904 -21.90242) (xy 179.713636 -21.875242)
				(arc
					(start 179.757324 -21.793962)
					(mid 180.179932 -21.164241)
					(end 179.889404 -21.864828)
				)
				(xy 179.860194 -21.91893) (xy 179.892198 -22.026626) (xy 179.89804 -22.02942) (xy 179.911248 -22.02942)
				(xy 179.92471 -22.042882) (xy 179.941728 -22.051264) (xy 179.945792 -22.063964) (xy 180.133498 -22.251416)
				(arc
					(start 180.416454 -21.723096)
					(mid 180.222906 -21.083524)
					(end 179.583334 -21.277072)
				)
				(arc
					(start 178.836574 -22.671278)
					(mid 179.024276 -23.31492)
					(end 179.666646 -23.12289)
				)
				(xy 179.797964 -22.87778) (xy 179.797964 -22.702774)
				(arc
					(start 179.596034 -22.500844)
					(mid 179.561922 -22.501616)
					(end 179.536344 -22.524212)
				)
				(arc
					(start 179.492656 -22.606)
					(mid 179.070048 -23.235721)
					(end 179.360576 -22.535134)
				)
				(xy 179.404264 -22.4536) (xy 179.418996 -22.426168)
				(arc
					(start 179.422806 -22.424898)
					(mid 179.521749 -22.356951)
					(end 179.641754 -22.358096)
				)
				(xy 179.644802 -22.35708) (xy 179.657248 -22.36343) (xy 179.670456 -22.36343) (xy 179.683918 -22.376892)
				(xy 179.700682 -22.385274) (xy 179.705 -22.397974) (xy 179.760626 -22.4536) (xy 179.932838 -22.625812)
			)
		)
	)
	(zone
		(layer "B.Cu")
		(hatch none 0.5)
		(connect_pads
			(clearance 0)
		)
		(min_thickness 0.25)
		(keepout
			(tracks not_allowed)
			(vias allowed)
			(pads allowed)
			(copperpour not_allowed)
			(footprints allowed)
		)
		(placement
			(enabled no)
			(sheetname "")
		)
		(fill
			(thermal_gap 0.5)
			(thermal_bridge_width 0.5)
			(island_removal_mode 0)
		)
		(polygon
			(pts
				(arc
					(start 198.429118 -81.0641)
					(mid 198.40072 -81.057396)
					(end 198.378318 -81.0387)
				)
				(arc
					(start 198.378318 -81.2673)
					(mid 198.40072 -81.248604)
					(end 198.429118 -81.2419)
				)
				(arc
					(start 198.632318 -81.2419)
					(mid 198.660716 -81.248604)
					(end 198.683118 -81.2673)
				)
				(arc
					(start 198.683118 -81.0387)
					(mid 198.660716 -81.057396)
					(end 198.632318 -81.0641)
				)
			)
		)
	)
	(zone
		(net "P12V_STBY")
		(layer "B.Cu")
		(hatch none 0.5)
		(connect_pads
			(clearance 0.5)
		)
		(min_thickness 0.25)
		(fill yes
			(thermal_gap 0.5)
			(thermal_bridge_width 0.5)
			(island_removal_mode 0)
		)
		(polygon
			(pts
				(xy 125.0823 -7.2771) (xy 124.98578 -7.37362) (xy 124.98578 -10.3886) (xy 125.59538 -10.9982) (xy 127.8382 -10.9982)
				(xy 128.35128 -11.51128) (xy 133.54304 -11.51128) (xy 133.5532 -11.50112) (xy 134.765288 -11.50112)
				(xy 135.019034 -11.247374) (xy 135.019034 -8.004302) (xy 134.291832 -7.2771)
			)
		)
		(polygon
			(pts
				(xy 125.6538 -9.9568) (xy 125.4506 -9.9568) (xy 125.4506 -10.16) (xy 125.6538 -10.16)
			)
		)
		(polygon
			(pts
				(xy 125.6538 -9.398) (xy 125.4506 -9.398) (xy 125.4506 -9.6012) (xy 125.6538 -9.6012)
			)
		)
		(polygon
			(pts
				(xy 125.652276 -8.92937) (xy 125.449076 -8.92937) (xy 125.449076 -9.13257) (xy 125.652276 -9.13257)
			)
		)
	)
	(zone
		(layer "B.Cu")
		(hatch none 0.5)
		(connect_pads
			(clearance 0)
		)
		(min_thickness 0.25)
		(keepout
			(tracks not_allowed)
			(vias allowed)
			(pads allowed)
			(copperpour not_allowed)
			(footprints allowed)
		)
		(placement
			(enabled no)
			(sheetname "")
		)
		(fill
			(thermal_gap 0.5)
			(thermal_bridge_width 0.5)
			(island_removal_mode 0)
		)
		(polygon
			(pts
				(xy 131.814824 -37.429948) (xy 131.814824 -37.568632) (xy 131.846066 -37.569648) (xy 131.850638 -37.569648)
				(xy 132.123942 -37.569648) (xy 132.128514 -37.569648) (xy 132.136642 -37.569648) (xy 132.164074 -37.569648)
				(arc
					(start 132.166868 -37.572442)
					(mid 132.244598 -37.597206)
					(end 132.310632 -37.645086)
				)
				(arc
					(start 132.310632 -37.645086)
					(mid 132.358283 -37.710921)
					(end 132.383022 -37.788342)
				)
				(xy 132.385816 -37.791136)
				(arc
					(start 132.385816 -37.815774)
					(mid 132.300865 -38.593795)
					(end 132.21335 -37.816028)
				)
				(arc
					(start 132.21335 -37.816028)
					(mid 132.20537 -37.789279)
					(end 132.18922 -37.766498)
				)
				(arc
					(start 132.18922 -37.766498)
					(mid 132.161368 -37.747888)
					(end 132.128514 -37.741352)
				)
				(xy 132.123942 -37.741352) (xy 131.850638 -37.741352) (xy 131.846066 -37.741352) (xy 131.832858 -37.741352)
				(xy 131.814824 -37.741352)
				(arc
					(start 131.814824 -38.200076)
					(mid 132.299964 -38.685216)
					(end 132.785104 -38.200076)
				)
				(arc
					(start 132.785104 -36.800282)
					(mid 132.300091 -36.314888)
					(end 131.814824 -36.800028)
				)
				(arc
					(start 131.814824 -37.256212)
					(mid 131.830401 -37.257951)
					(end 131.846066 -37.258498)
				)
				(xy 131.850638 -37.258752) (xy 132.069586 -37.258752)
				(arc
					(start 132.074158 -37.258498)
					(mid 132.127619 -37.247864)
					(end 132.172964 -37.217604)
				)
				(arc
					(start 132.172964 -37.217604)
					(mid 132.187662 -37.200259)
					(end 132.19938 -37.180774)
				)
				(arc
					(start 132.19938 -37.180774)
					(mid 132.310799 -36.406441)
					(end 132.37845 -37.185854)
				)
				(arc
					(start 132.37845 -37.185854)
					(mid 132.347365 -37.26845)
					(end 132.294376 -37.339016)
				)
				(arc
					(start 132.294376 -37.339016)
					(mid 132.21052 -37.398793)
					(end 132.11175 -37.427916)
				)
				(xy 132.109718 -37.429948) (xy 132.083048 -37.429948) (xy 132.074158 -37.430202) (xy 132.069586 -37.429948)
				(xy 131.850638 -37.429948) (xy 131.846066 -37.430202) (xy 131.836414 -37.429948)
			)
		)
	)
	(zone
		(net "GND")
		(layer "B.Cu")
		(hatch none 0.5)
		(connect_pads
			(clearance 0.5)
		)
		(min_thickness 0.25)
		(fill yes
			(thermal_gap 0.5)
			(thermal_bridge_width 0.5)
			(island_removal_mode 0)
		)
		(polygon
			(pts
				(xy 184.6707 -114.7953) (xy 184.2516 -115.2144) (xy 184.2516 -119.253) (xy 184.023 -119.4816) (xy 184.023 -120.5484)
				(xy 184.1754 -120.7008) (xy 186.6138 -120.7008) (xy 186.944 -121.031) (xy 186.944 -122.843544) (xy 187.155328 -123.054872)
				(xy 187.341002 -123.2408) (xy 189.992 -123.2408) (xy 190.1952 -123.0376) (xy 190.1952 -115.9002)
				(xy 189.6618 -115.3668) (xy 187.6044 -115.3668) (xy 187.071 -114.8334) (xy 184.7088 -114.8334)
			)
		)
	)
	(zone
		(net "GND")
		(layer "B.Cu")
		(hatch none 0.5)
		(connect_pads
			(clearance 0.5)
		)
		(min_thickness 0.25)
		(fill yes
			(thermal_gap 0.5)
			(thermal_bridge_width 0.5)
			(island_removal_mode 0)
		)
		(polygon
			(pts
				(arc
					(start 0.999998 -0.763016)
					(mid 0.832426 -0.832426)
					(end 0.763016 -0.999998)
				)
				(arc
					(start 0.763016 -183.76392)
					(mid 0.769411 -183.818347)
					(end 0.788162 -183.869838)
				)
				(arc
					(start 5.406136 -193.10604)
					(mid 5.493436 -193.201687)
					(end 5.617972 -193.237104)
				)
				(arc
					(start 98.0821 -193.237104)
					(mid 98.206591 -193.201614)
					(end 98.293936 -193.10604)
				)
				(arc
					(start 102.91191 -183.869838)
					(mid 102.930633 -183.818341)
					(end 102.937056 -183.76392)
				)
				(xy 102.937056 -183.403748) (xy 100.874322 -183.403748) (xy 96.97339 -191.20612) (xy 6.726682 -191.20612)
				(xy 2.82575 -183.403748) (xy 2.767584 -183.403748) (xy 2.7305 -183.366664) (xy 2.7305 -183.313832)
				(xy 2.767584 -183.276748) (xy 2.794 -183.276748) (xy 2.794 -2.794) (xy 27.736038 -2.794)
				(arc
					(start 27.736038 -109.051344)
					(mid 27.753964 -109.418963)
					(end 27.807412 -109.783118)
				)
				(arc
					(start 29.926534 -109.783118)
					(mid 29.807392 -109.425427)
					(end 29.767022 -109.050582)
				)
				(arc
					(start 29.767022 -0.999998)
					(mid 29.697612 -0.832426)
					(end 29.53004 -0.763016)
				)
			)
		)
	)
	(zone
		(layer "B.Cu")
		(hatch none 0.5)
		(connect_pads
			(clearance 0)
		)
		(min_thickness 0.25)
		(keepout
			(tracks allowed)
			(vias allowed)
			(pads allowed)
			(copperpour allowed)
			(footprints allowed)
		)
		(placement
			(enabled no)
			(sheetname "")
		)
		(fill
			(thermal_gap 0.5)
			(thermal_bridge_width 0.5)
			(island_removal_mode 0)
		)
		(polygon
			(pts
				(xy 108.340652 -33.911032) (xy 108.340652 -31.454344) (xy 109.416342 -31.454344) (xy 109.416342 -33.911032)
			)
		)
	)
	(zone
		(layer "B.Cu")
		(hatch none 0.5)
		(connect_pads
			(clearance 0)
		)
		(min_thickness 0.25)
		(keepout
			(tracks allowed)
			(vias allowed)
			(pads allowed)
			(copperpour allowed)
			(footprints not_allowed)
		)
		(placement
			(enabled no)
			(sheetname "")
		)
		(fill
			(thermal_gap 0.5)
			(thermal_bridge_width 0.5)
			(island_removal_mode 0)
		)
		(polygon
			(pts
				(arc
					(start 222.79991 -84.479892)
					(mid 219.799916 -81.479898)
					(end 216.799922 -84.479892)
				)
				(arc
					(start 216.799922 -84.479892)
					(mid 219.799916 -87.479886)
					(end 222.79991 -84.479892)
				)
			)
		)
	)
	(zone
		(layer "B.Cu")
		(hatch none 0.5)
		(connect_pads
			(clearance 0)
		)
		(min_thickness 0.25)
		(keepout
			(tracks not_allowed)
			(vias allowed)
			(pads allowed)
			(copperpour not_allowed)
			(footprints allowed)
		)
		(placement
			(enabled no)
			(sheetname "")
		)
		(fill
			(thermal_gap 0.5)
			(thermal_bridge_width 0.5)
			(island_removal_mode 0)
		)
		(polygon
			(pts
				(xy 162.338004 -22.34184) (xy 162.300666 -22.281642) (xy 162.166554 -22.210014) (xy 162.139122 -22.195282)
				(xy 162.111944 -22.181058) (xy 162.111944 -22.180804) (xy 162.095434 -22.171914) (xy 162.078924 -22.163024)
				(xy 162.077654 -22.163532) (xy 162.061652 -22.154388) (xy 162.049714 -22.154388) (xy 162.036252 -22.140926)
				(xy 162.0266 -22.1361) (xy 162.019742 -22.132544)
				(arc
					(start 162.018218 -22.127972)
					(mid 161.948939 -22.028195)
					(end 161.9504 -21.906738)
				)
				(xy 161.94913 -21.902674) (xy 161.963862 -21.875496)
				(arc
					(start 162.00755 -21.793962)
					(mid 162.430158 -21.164241)
					(end 162.13963 -21.864828)
				)
				(arc
					(start 162.095942 -21.946362)
					(mid 162.090594 -21.976815)
					(end 162.104324 -22.004528)
				)
				(xy 162.111944 -22.004528) (xy 162.125406 -22.01799) (xy 162.14725 -22.028912) (xy 162.153092 -22.03196)
				(xy 162.1536 -22.032976) (xy 162.166046 -22.039834) (xy 162.20821 -22.062186) (xy 162.235642 -22.076918)
				(xy 162.26282 -22.091142) (xy 162.26282 -22.091396) (xy 162.380422 -22.154388) (xy 162.40125 -22.159214)
				(xy 162.406838 -22.168358) (xy 162.41649 -22.173438) (xy 162.420554 -22.187408) (xy 162.668712 -21.72462)
				(xy 162.668458 -21.724366)
				(arc
					(start 162.666426 -21.72335)
					(mid 162.473287 -21.083725)
					(end 161.833814 -21.277072)
				)
				(xy 161.831528 -21.275802) (xy 161.081466 -22.675596)
				(arc
					(start 161.083752 -22.676866)
					(mid 161.277046 -23.316184)
					(end 161.916364 -23.12289)
				)
				(xy 161.91865 -23.12416) (xy 162.116008 -22.756114) (xy 162.012376 -22.588728) (xy 161.900362 -22.528784)
				(xy 161.886646 -22.521418) (xy 161.884106 -22.52218) (xy 161.881566 -22.520656) (xy 161.881312 -22.520656)
				(xy 161.876994 -22.517862) (xy 161.874708 -22.51837) (xy 161.854388 -22.504908)
				(arc
					(start 161.845752 -22.50059)
					(mid 161.811812 -22.501481)
					(end 161.786316 -22.523958)
				)
				(arc
					(start 161.742374 -22.606)
					(mid 161.319755 -23.235239)
					(end 161.610294 -22.535134)
				)
				(xy 161.668968 -22.425914)
				(arc
					(start 161.672778 -22.424644)
					(mid 161.772875 -22.356348)
					(end 161.894012 -22.358604)
				)
				(xy 161.896298 -22.357842) (xy 161.899092 -22.359366) (xy 161.90468 -22.35835) (xy 161.926016 -22.372574)
				(xy 161.929572 -22.374606) (xy 161.953194 -22.386544) (xy 161.955988 -22.388068) (xy 161.962846 -22.391624)
				(xy 161.9631 -22.392386) (xy 161.970974 -22.396704) (xy 161.998152 -22.411182) (xy 162.092132 -22.461474)
				(xy 162.11296 -22.4663) (xy 162.118548 -22.475444) (xy 162.1282 -22.480524) (xy 162.134296 -22.500844)
				(xy 162.197796 -22.60346)
			)
		)
	)
	(zone
		(net "SAS0_VDDH")
		(layer "B.Cu")
		(hatch none 0.5)
		(connect_pads
			(clearance 0.5)
		)
		(min_thickness 0.25)
		(fill yes
			(thermal_gap 0.5)
			(thermal_bridge_width 0.5)
			(island_removal_mode 0)
		)
		(polygon
			(pts
				(xy 209.8548 -83.947) (xy 208.165192 -85.636608) (xy 208.165192 -88.226392) (xy 209.9564 -90.0176)
				(xy 211.5566 -90.0176) (xy 211.6709 -89.9033) (xy 211.6709 -89.3445) (xy 211.455 -89.1286) (xy 211.455 -85.0138)
				(xy 211.6074 -84.8614) (xy 211.6074 -84.074) (xy 211.4804 -83.947)
			)
		)
		(polygon
			(pts
				(xy 211.2264 -89.281) (xy 211.0232 -89.281) (xy 211.0232 -89.4842) (xy 211.2264 -89.4842)
			)
		)
		(polygon
			(pts
				(xy 210.7946 -84.7852) (xy 210.5914 -84.7852) (xy 210.5914 -84.9884) (xy 210.7946 -84.9884)
			)
		)
	)
	(zone
		(layer "B.Cu")
		(hatch none 0.5)
		(connect_pads
			(clearance 0)
		)
		(min_thickness 0.25)
		(keepout
			(tracks not_allowed)
			(vias allowed)
			(pads allowed)
			(copperpour not_allowed)
			(footprints allowed)
		)
		(placement
			(enabled no)
			(sheetname "")
		)
		(fill
			(thermal_gap 0.5)
			(thermal_bridge_width 0.5)
			(island_removal_mode 0)
		)
		(polygon
			(pts
				(arc
					(start 27.55011 -60.550044)
					(mid 22.800056 -55.79999)
					(end 18.050002 -60.550044)
				)
				(arc
					(start 18.050002 -60.550044)
					(mid 22.800056 -65.300098)
					(end 27.55011 -60.550044)
				)
			)
		)
	)
	(zone
		(layer "B.Cu")
		(hatch none 0.5)
		(connect_pads
			(clearance 0)
		)
		(min_thickness 0.25)
		(keepout
			(tracks not_allowed)
			(vias allowed)
			(pads allowed)
			(copperpour not_allowed)
			(footprints allowed)
		)
		(placement
			(enabled no)
			(sheetname "")
		)
		(fill
			(thermal_gap 0.5)
			(thermal_bridge_width 0.5)
			(island_removal_mode 0)
		)
		(polygon
			(pts
				(xy 182.304944 -18.598134) (xy 182.13578 -18.416524)
				(arc
					(start 182.03926 -18.342356)
					(mid 181.953127 -18.240534)
					(end 181.95036 -18.107152)
				)
				(xy 181.94909 -18.103088)
				(arc
					(start 182.007764 -17.993868)
					(mid 182.430383 -17.364629)
					(end 182.139844 -18.064734)
				)
				(arc
					(start 182.095902 -18.146522)
					(mid 182.090284 -18.174747)
					(end 182.101236 -18.201386)
				)
				(xy 182.101744 -18.201386) (xy 182.212996 -18.286984) (xy 182.220108 -18.287238) (xy 182.236872 -18.305272)
				(xy 182.256684 -18.320512) (xy 182.257446 -18.32737) (xy 182.37962 -18.458688)
				(arc
					(start 182.663592 -17.92859)
					(mid 182.47589 -17.284948)
					(end 181.83352 -17.476978)
				)
				(arc
					(start 181.083458 -18.877026)
					(mid 181.277006 -19.516598)
					(end 181.916578 -19.32305)
				)
				(xy 182.101998 -18.976848)
				(arc
					(start 181.844442 -18.700242)
					(mid 181.811103 -18.701806)
					(end 181.786276 -18.724118)
				)
				(arc
					(start 181.742334 -18.80616)
					(mid 181.319715 -19.435399)
					(end 181.610254 -18.735294)
				)
				(xy 181.668928 -18.626074)
				(arc
					(start 181.672738 -18.624804)
					(mid 181.779493 -18.554644)
					(end 181.906926 -18.56359)
				)
				(xy 181.922674 -18.564352) (xy 182.176674 -18.837148)
			)
		)
	)
	(zone
		(net "P1V8")
		(layer "B.Cu")
		(hatch none 0.5)
		(connect_pads
			(clearance 0.5)
		)
		(min_thickness 0.25)
		(fill yes
			(thermal_gap 0.5)
			(thermal_bridge_width 0.5)
			(island_removal_mode 0)
		)
		(polygon
			(pts
				(xy 185.36158 -55.9943) (xy 185.1533 -56.20258) (xy 185.1533 -58.91276) (xy 185.21172 -58.97118)
				(xy 185.7502 -58.97118) (xy 185.81878 -58.9026) (xy 185.81878 -57.5691) (xy 185.81624 -57.56656)
				(xy 185.81624 -56.49722) (xy 185.8772 -56.43626) (xy 185.8772 -56.11876) (xy 185.75274 -55.9943)
			)
		)
	)
	(zone
		(layer "B.Cu")
		(hatch none 0.5)
		(connect_pads
			(clearance 0)
		)
		(min_thickness 0.25)
		(keepout
			(tracks allowed)
			(vias allowed)
			(pads allowed)
			(copperpour allowed)
			(footprints allowed)
		)
		(placement
			(enabled no)
			(sheetname "")
		)
		(fill
			(thermal_gap 0.5)
			(thermal_bridge_width 0.5)
			(island_removal_mode 0)
		)
		(polygon
			(pts
				(xy 208.0514 -63.3984) (xy 208.0514 -61.5188) (xy 208.0514 -59.5376) (xy 208.4578 -59.1312) (xy 210.6422 -59.1312)
				(xy 211.0486 -59.5376) (xy 211.0486 -62.0776) (xy 209.7278 -63.3984)
			)
		)
	)
	(zone
		(layer "B.Cu")
		(hatch none 0.5)
		(connect_pads
			(clearance 0)
		)
		(min_thickness 0.25)
		(keepout
			(tracks not_allowed)
			(vias allowed)
			(pads allowed)
			(copperpour not_allowed)
			(footprints allowed)
		)
		(placement
			(enabled no)
			(sheetname "")
		)
		(fill
			(thermal_gap 0.5)
			(thermal_bridge_width 0.5)
			(island_removal_mode 0)
		)
		(polygon
			(pts
				(arc
					(start 77.667358 -73.708768)
					(mid 77.283818 -73.325228)
					(end 76.900278 -73.708768)
				)
				(arc
					(start 76.900278 -74.597514)
					(mid 77.283691 -74.981308)
					(end 77.667358 -74.597768)
				)
				(xy 77.667358 -74.394568) (xy 77.5208 -74.394568)
				(arc
					(start 77.516228 -74.394568)
					(mid 77.490959 -74.396718)
					(end 77.466444 -74.403204)
				)
				(arc
					(start 77.466444 -74.403204)
					(mid 77.18881 -74.847129)
					(end 77.27696 -74.331068)
				)
				(arc
					(start 77.27696 -74.331068)
					(mid 77.367991 -74.259429)
					(end 77.478636 -74.22515)
				)
				(xy 77.480668 -74.222864) (xy 77.507338 -74.222864) (xy 77.516228 -74.222864) (xy 77.5208 -74.222864)
				(xy 77.667358 -74.222864) (xy 77.667358 -74.083164) (xy 77.5208 -74.083164) (xy 77.516228 -74.083418)
				(xy 77.507338 -74.083164) (xy 77.480668 -74.083164)
				(arc
					(start 77.478636 -74.081132)
					(mid 77.368162 -74.046912)
					(end 77.277214 -73.975468)
				)
				(arc
					(start 77.277214 -73.975468)
					(mid 77.188177 -73.459629)
					(end 77.466444 -73.903078)
				)
				(arc
					(start 77.466444 -73.903078)
					(mid 77.490962 -73.909552)
					(end 77.516228 -73.911714)
				)
				(xy 77.5208 -73.911968) (xy 77.667358 -73.911968)
			)
		)
	)
	(zone
		(layer "B.Cu")
		(hatch none 0.5)
		(connect_pads
			(clearance 0)
		)
		(min_thickness 0.25)
		(keepout
			(tracks allowed)
			(vias allowed)
			(pads allowed)
			(copperpour allowed)
			(footprints not_allowed)
		)
		(placement
			(enabled no)
			(sheetname "")
		)
		(fill
			(thermal_gap 0.5)
			(thermal_bridge_width 0.5)
			(island_removal_mode 0)
		)
		(polygon
			(pts
				(arc
					(start 150.750016 -187.999878)
					(mid 155.50007 -192.749932)
					(end 160.250124 -187.999878)
				)
				(arc
					(start 160.250124 -187.999878)
					(mid 155.50007 -183.249824)
					(end 150.750016 -187.999878)
				)
			)
		)
	)
	(zone
		(net "GND")
		(layer "B.Cu")
		(hatch none 0.5)
		(connect_pads
			(clearance 0.5)
		)
		(min_thickness 0.25)
		(fill yes
			(thermal_gap 0.5)
			(thermal_bridge_width 0.5)
			(island_removal_mode 0)
		)
		(polygon
			(pts
				(xy 80.482948 -45.957236) (xy 80.335628 -46.104556) (xy 80.335628 -50.085244) (xy 80.260952 -50.15992)
				(xy 80.11541 -50.305716) (xy 78.364588 -50.305716) (xy 77.870304 -50.8) (xy 77.389228 -50.8) (xy 77.135228 -51.054)
				(xy 77.135228 -52.139596) (xy 77.140816 -52.145184) (xy 77.140816 -52.502816) (xy 77.2922 -52.6542)
				(xy 77.8764 -52.6542) (xy 78.8035 -51.7271) (xy 80.4037 -51.7271) (xy 80.997298 -51.133502) (xy 80.997298 -50.652426)
				(xy 80.997298 -49.763426) (xy 81.237328 -49.523396) (xy 82.062828 -49.523396) (xy 82.128868 -49.457356)
				(xy 82.128868 -46.122336) (xy 81.963768 -45.957236)
			)
		)
	)
	(zone
		(layer "B.Cu")
		(hatch none 0.5)
		(connect_pads
			(clearance 0)
		)
		(min_thickness 0.25)
		(keepout
			(tracks not_allowed)
			(vias allowed)
			(pads allowed)
			(copperpour not_allowed)
			(footprints allowed)
		)
		(placement
			(enabled no)
			(sheetname "")
		)
		(fill
			(thermal_gap 0.5)
			(thermal_bridge_width 0.5)
			(island_removal_mode 0)
		)
		(polygon
			(pts
				(arc
					(start 22.750018 -24.99995)
					(mid 17.999964 -20.249896)
					(end 13.24991 -24.99995)
				)
				(arc
					(start 13.24991 -24.99995)
					(mid 17.999964 -29.750004)
					(end 22.750018 -24.99995)
				)
			)
		)
	)
	(zone
		(layer "B.Cu")
		(hatch none 0.5)
		(connect_pads
			(clearance 0)
		)
		(min_thickness 0.25)
		(keepout
			(tracks allowed)
			(vias allowed)
			(pads allowed)
			(copperpour allowed)
			(footprints not_allowed)
		)
		(placement
			(enabled no)
			(sheetname "")
		)
		(fill
			(thermal_gap 0.5)
			(thermal_bridge_width 0.5)
			(island_removal_mode 0)
		)
		(polygon
			(pts
				(arc
					(start 162.80003 -45.72)
					(mid 165.800024 -48.719994)
					(end 168.800018 -45.72)
				)
				(arc
					(start 168.800018 -45.72)
					(mid 165.800024 -42.720006)
					(end 162.80003 -45.72)
				)
			)
		)
	)
	(zone
		(net "GND")
		(layer "B.Cu")
		(hatch none 0.5)
		(connect_pads
			(clearance 0.5)
		)
		(min_thickness 0.25)
		(fill yes
			(thermal_gap 0.5)
			(thermal_bridge_width 0.5)
			(island_removal_mode 0)
		)
		(polygon
			(pts
				(xy 76.166472 -160.553654) (xy 76.166472 -163.84524) (xy 79.438246 -163.84524) (xy 79.438246 -160.553654)
			)
		)
	)
	(zone
		(layer "B.Cu")
		(hatch none 0.5)
		(connect_pads
			(clearance 0)
		)
		(min_thickness 0.25)
		(keepout
			(tracks allowed)
			(vias allowed)
			(pads allowed)
			(copperpour allowed)
			(footprints allowed)
		)
		(placement
			(enabled no)
			(sheetname "")
		)
		(fill
			(thermal_gap 0.5)
			(thermal_bridge_width 0.5)
			(island_removal_mode 0)
		)
		(polygon
			(pts
				(xy 119.140732 -33.911032) (xy 119.140732 -31.454344) (xy 120.216422 -31.454344) (xy 120.216422 -33.911032)
			)
		)
	)
	(zone
		(layer "B.Cu")
		(hatch none 0.5)
		(connect_pads
			(clearance 0)
		)
		(min_thickness 0.25)
		(keepout
			(tracks allowed)
			(vias allowed)
			(pads allowed)
			(copperpour allowed)
			(footprints not_allowed)
		)
		(placement
			(enabled no)
			(sheetname "")
		)
		(fill
			(thermal_gap 0.5)
			(thermal_bridge_width 0.5)
			(island_removal_mode 0)
		)
		(polygon
			(pts
				(arc
					(start 227.24999 -187.999878)
					(mid 222.499936 -183.249824)
					(end 217.749882 -187.999878)
				)
				(arc
					(start 217.749882 -187.999878)
					(mid 222.499936 -192.749932)
					(end 227.24999 -187.999878)
				)
			)
		)
	)
	(zone
		(layer "B.Cu")
		(hatch none 0.5)
		(connect_pads
			(clearance 0)
		)
		(min_thickness 0.25)
		(keepout
			(tracks not_allowed)
			(vias allowed)
			(pads allowed)
			(copperpour not_allowed)
			(footprints allowed)
		)
		(placement
			(enabled no)
			(sheetname "")
		)
		(fill
			(thermal_gap 0.5)
			(thermal_bridge_width 0.5)
			(island_removal_mode 0)
		)
		(polygon
			(pts
				(arc
					(start 200.257918 -81.0641)
					(mid 200.22952 -81.057396)
					(end 200.207118 -81.0387)
				)
				(arc
					(start 200.207118 -81.2673)
					(mid 200.22952 -81.248604)
					(end 200.257918 -81.2419)
				)
				(arc
					(start 200.461118 -81.2419)
					(mid 200.489516 -81.248604)
					(end 200.511918 -81.2673)
				)
				(arc
					(start 200.511918 -81.0387)
					(mid 200.489516 -81.057396)
					(end 200.461118 -81.0641)
				)
			)
		)
	)
	(zone
		(layer "B.Cu")
		(hatch none 0.5)
		(connect_pads
			(clearance 0)
		)
		(min_thickness 0.25)
		(keepout
			(tracks not_allowed)
			(vias allowed)
			(pads allowed)
			(copperpour not_allowed)
			(footprints allowed)
		)
		(placement
			(enabled no)
			(sheetname "")
		)
		(fill
			(thermal_gap 0.5)
			(thermal_bridge_width 0.5)
			(island_removal_mode 0)
		)
		(polygon
			(pts
				(arc
					(start 77.667358 -92.911168)
					(mid 77.283818 -92.527628)
					(end 76.900278 -92.911168)
				)
				(arc
					(start 76.900278 -93.799914)
					(mid 77.283691 -94.183708)
					(end 77.667358 -93.800168)
				)
				(xy 77.667358 -93.596968) (xy 77.5208 -93.596968)
				(arc
					(start 77.516228 -93.596968)
					(mid 77.490959 -93.599118)
					(end 77.466444 -93.605604)
				)
				(arc
					(start 77.466444 -93.605604)
					(mid 77.18881 -94.049529)
					(end 77.27696 -93.533468)
				)
				(arc
					(start 77.27696 -93.533468)
					(mid 77.367991 -93.461829)
					(end 77.478636 -93.42755)
				)
				(xy 77.480668 -93.425264) (xy 77.507338 -93.425264) (xy 77.516228 -93.425264) (xy 77.5208 -93.425264)
				(xy 77.667358 -93.425264) (xy 77.667358 -93.285564) (xy 77.5208 -93.285564) (xy 77.516228 -93.285818)
				(xy 77.507338 -93.285564) (xy 77.480668 -93.285564)
				(arc
					(start 77.478636 -93.283532)
					(mid 77.368162 -93.249312)
					(end 77.277214 -93.177868)
				)
				(arc
					(start 77.277214 -93.177868)
					(mid 77.188177 -92.662029)
					(end 77.466444 -93.105478)
				)
				(arc
					(start 77.466444 -93.105478)
					(mid 77.490962 -93.111952)
					(end 77.516228 -93.114114)
				)
				(xy 77.5208 -93.114368) (xy 77.667358 -93.114368)
			)
		)
	)
	(zone
		(net "GND")
		(layer "B.Cu")
		(hatch none 0.5)
		(connect_pads
			(clearance 0.5)
		)
		(min_thickness 0.25)
		(fill yes
			(thermal_gap 0.5)
			(thermal_bridge_width 0.5)
			(island_removal_mode 0)
		)
		(polygon
			(pts
				(xy 43.85056 -153.9748) (xy 43.80611 -154.01925) (xy 43.38955 -154.01925) (xy 42.9387 -154.4701)
				(xy 42.9387 -156.78912) (xy 42.94632 -156.79674) (xy 44.68622 -156.79674) (xy 44.7802 -156.70276)
				(xy 44.7802 -156.5656) (xy 44.76242 -156.54782) (xy 44.76242 -155.75788) (xy 44.95038 -155.56992)
				(xy 44.95038 -154.06116) (xy 44.86402 -153.9748)
			)
		)
		(polygon
			(pts
				(xy 43.98264 -155.77312) (xy 43.77944 -155.77312) (xy 43.77944 -155.97632) (xy 43.98264 -155.97632)
			)
		)
		(polygon
			(pts
				(xy 44.41444 -155.44292) (xy 44.21124 -155.44292) (xy 44.21124 -155.64612) (xy 44.41444 -155.64612)
			)
		)
		(polygon
			(pts
				(xy 44.41444 -154.83332) (xy 44.21124 -154.83332) (xy 44.21124 -155.03652) (xy 44.41444 -155.03652)
			)
		)
		(polygon
			(pts
				(xy 44.41444 -154.50312) (xy 44.21124 -154.50312) (xy 44.21124 -154.70632) (xy 44.41444 -154.70632)
			)
		)
	)
	(zone
		(net "P3V3_STBY")
		(layer "B.Cu")
		(hatch none 0.5)
		(connect_pads
			(clearance 0.5)
		)
		(min_thickness 0.25)
		(fill yes
			(thermal_gap 0.5)
			(thermal_bridge_width 0.5)
			(island_removal_mode 0)
		)
		(polygon
			(pts
				(xy 84.498688 -54.504336) (xy 84.323428 -54.679596) (xy 84.323428 -56.127396) (xy 84.249768 -56.201056)
				(xy 82.748628 -56.201056) (xy 82.426048 -56.523636) (xy 82.426048 -59.492896) (xy 82.525108 -59.591956)
				(xy 83.942428 -59.591956) (xy 84.191348 -59.343036) (xy 84.191348 -58.093356) (xy 84.465668 -58.093356)
				(xy 84.485988 -58.113676) (xy 85.308948 -58.113676) (xy 85.560408 -57.862216) (xy 85.560408 -54.532276)
				(xy 85.532468 -54.504336)
			)
		)
	)
	(zone
		(layer "B.Cu")
		(hatch none 0.5)
		(connect_pads
			(clearance 0)
		)
		(min_thickness 0.25)
		(keepout
			(tracks not_allowed)
			(vias allowed)
			(pads allowed)
			(copperpour not_allowed)
			(footprints allowed)
		)
		(placement
			(enabled no)
			(sheetname "")
		)
		(fill
			(thermal_gap 0.5)
			(thermal_bridge_width 0.5)
			(island_removal_mode 0)
		)
		(polygon
			(pts
				(xy 137.214864 -36.230052) (xy 137.214864 -36.368736) (xy 137.246106 -36.369752) (xy 137.250678 -36.369752)
				(xy 137.523982 -36.369752) (xy 137.528554 -36.369752) (xy 137.536682 -36.369752) (xy 137.564114 -36.369752)
				(arc
					(start 137.566908 -36.372546)
					(mid 137.644638 -36.39731)
					(end 137.710672 -36.44519)
				)
				(arc
					(start 137.710672 -36.44519)
					(mid 137.758323 -36.511025)
					(end 137.783062 -36.588446)
				)
				(xy 137.785856 -36.59124)
				(arc
					(start 137.785856 -36.615878)
					(mid 137.700905 -37.393899)
					(end 137.61339 -36.616132)
				)
				(arc
					(start 137.61339 -36.616132)
					(mid 137.60541 -36.589383)
					(end 137.58926 -36.566602)
				)
				(arc
					(start 137.58926 -36.566602)
					(mid 137.561408 -36.547992)
					(end 137.528554 -36.541456)
				)
				(xy 137.523982 -36.541456) (xy 137.250678 -36.541456) (xy 137.246106 -36.541456) (xy 137.232898 -36.541456)
				(xy 137.214864 -36.541456)
				(arc
					(start 137.214864 -37.00018)
					(mid 137.700004 -37.48532)
					(end 138.185144 -37.00018)
				)
				(arc
					(start 138.185144 -35.600386)
					(mid 137.700131 -35.114992)
					(end 137.214864 -35.600132)
				)
				(arc
					(start 137.214864 -36.056316)
					(mid 137.230441 -36.058055)
					(end 137.246106 -36.058602)
				)
				(xy 137.250678 -36.058856) (xy 137.469626 -36.058856)
				(arc
					(start 137.474198 -36.058602)
					(mid 137.527659 -36.047968)
					(end 137.573004 -36.017708)
				)
				(arc
					(start 137.573004 -36.017708)
					(mid 137.587702 -36.000363)
					(end 137.59942 -35.980878)
				)
				(arc
					(start 137.59942 -35.980878)
					(mid 137.710839 -35.206545)
					(end 137.77849 -35.985958)
				)
				(arc
					(start 137.77849 -35.985958)
					(mid 137.747405 -36.068554)
					(end 137.694416 -36.13912)
				)
				(arc
					(start 137.694416 -36.13912)
					(mid 137.61056 -36.198897)
					(end 137.51179 -36.22802)
				)
				(xy 137.509758 -36.230052) (xy 137.483088 -36.230052) (xy 137.474198 -36.230306) (xy 137.469626 -36.230052)
				(xy 137.250678 -36.230052) (xy 137.246106 -36.230306) (xy 137.236454 -36.230052)
			)
		)
	)
	(zone
		(layer "B.Cu")
		(hatch none 0.5)
		(connect_pads
			(clearance 0)
		)
		(min_thickness 0.25)
		(keepout
			(tracks not_allowed)
			(vias allowed)
			(pads allowed)
			(copperpour not_allowed)
			(footprints allowed)
		)
		(placement
			(enabled no)
			(sheetname "")
		)
		(fill
			(thermal_gap 0.5)
			(thermal_bridge_width 0.5)
			(island_removal_mode 0)
		)
		(polygon
			(pts
				(xy 128.214882 -37.429948) (xy 128.214882 -37.568632) (xy 128.246124 -37.569648) (xy 128.250696 -37.569648)
				(xy 128.524 -37.569648) (xy 128.528572 -37.569648) (xy 128.5367 -37.569648) (xy 128.564132 -37.569648)
				(arc
					(start 128.566926 -37.572442)
					(mid 128.644656 -37.597206)
					(end 128.71069 -37.645086)
				)
				(arc
					(start 128.71069 -37.645086)
					(mid 128.758341 -37.710921)
					(end 128.78308 -37.788342)
				)
				(xy 128.78562 -37.791136)
				(arc
					(start 128.78562 -37.815774)
					(mid 128.700545 -38.593795)
					(end 128.613408 -37.816028)
				)
				(arc
					(start 128.613408 -37.816028)
					(mid 128.605428 -37.789279)
					(end 128.589278 -37.766498)
				)
				(arc
					(start 128.589278 -37.766498)
					(mid 128.561426 -37.747888)
					(end 128.528572 -37.741352)
				)
				(xy 128.524 -37.741352) (xy 128.250696 -37.741352) (xy 128.246124 -37.741352) (xy 128.232916 -37.741352)
				(xy 128.214882 -37.741352)
				(arc
					(start 128.214882 -38.200076)
					(mid 128.700022 -38.685216)
					(end 129.185162 -38.200076)
				)
				(arc
					(start 129.185162 -36.800282)
					(mid 128.700149 -36.314888)
					(end 128.214882 -36.800028)
				)
				(arc
					(start 128.214882 -37.256212)
					(mid 128.230459 -37.257951)
					(end 128.246124 -37.258498)
				)
				(xy 128.250696 -37.258752) (xy 128.469644 -37.258752)
				(arc
					(start 128.474216 -37.258498)
					(mid 128.527677 -37.247864)
					(end 128.573022 -37.217604)
				)
				(arc
					(start 128.573022 -37.217604)
					(mid 128.58772 -37.200259)
					(end 128.599438 -37.180774)
				)
				(arc
					(start 128.599438 -37.180774)
					(mid 128.710857 -36.406441)
					(end 128.778508 -37.185854)
				)
				(arc
					(start 128.778508 -37.185854)
					(mid 128.747423 -37.26845)
					(end 128.694434 -37.339016)
				)
				(arc
					(start 128.694434 -37.339016)
					(mid 128.610578 -37.398793)
					(end 128.511808 -37.427916)
				)
				(xy 128.509776 -37.429948) (xy 128.483106 -37.429948) (xy 128.474216 -37.430202) (xy 128.469644 -37.429948)
				(xy 128.250696 -37.429948) (xy 128.246124 -37.430202) (xy 128.236472 -37.429948)
			)
		)
	)
	(zone
		(net "P3V3_STBY")
		(layer "B.Cu")
		(hatch none 0.5)
		(connect_pads
			(clearance 0.5)
		)
		(min_thickness 0.25)
		(fill yes
			(thermal_gap 0.5)
			(thermal_bridge_width 0.5)
			(island_removal_mode 0)
		)
		(polygon
			(pts
				(xy 57.19064 -155.49372) (xy 57.12714 -155.55722) (xy 57.12714 -157.00756) (xy 57.23636 -157.11678)
				(xy 59.20994 -157.11678) (xy 59.95924 -157.86608) (xy 63.66764 -157.86608) (xy 63.73368 -157.93212)
				(xy 64.40424 -157.93212) (xy 64.83096 -157.5054) (xy 66.11366 -157.5054) (xy 66.34988 -157.26918)
				(xy 66.34988 -156.51988) (xy 66.26352 -156.43352) (xy 62.9412 -156.43352) (xy 62.48908 -155.9814)
				(xy 61.5696 -155.9814) (xy 61.56706 -155.97886) (xy 61.3283 -156.21762) (xy 59.06008 -156.21762)
				(xy 58.33618 -155.49372)
			)
		)
		(polygon
			(pts
				(xy 64.58458 -157.184598) (xy 64.38138 -157.184598) (xy 64.38138 -157.387798) (xy 64.58458 -157.387798)
			)
		)
		(polygon
			(pts
				(xy 63.97498 -157.184598) (xy 63.77178 -157.184598) (xy 63.77178 -157.387798) (xy 63.97498 -157.387798)
			)
		)
	)
	(zone
		(net "P3V3_STBY")
		(layer "B.Cu")
		(hatch none 0.5)
		(connect_pads
			(clearance 0.5)
		)
		(min_thickness 0.25)
		(fill yes
			(thermal_gap 0.5)
			(thermal_bridge_width 0.5)
			(island_removal_mode 0)
		)
		(polygon
			(pts
				(xy 45.373544 -130.130042) (xy 45.16882 -130.334766) (xy 45.16882 -130.561842) (xy 45.6184 -131.011422)
				(xy 45.6184 -131.7625) (xy 45.26915 -132.11175) (xy 45.26915 -132.88264) (xy 44.043854 -134.107936)
				(xy 44.043854 -135.466074) (xy 44.106592 -135.528812) (xy 44.538392 -135.528812) (xy 44.623736 -135.443468)
				(xy 44.623736 -134.655814) (xy 44.745656 -134.533894) (xy 44.745656 -134.207504) (xy 45.217334 -133.735826)
				(xy 45.711618 -133.735826) (xy 45.916342 -133.531102) (xy 45.916342 -132.707126) (xy 46.726094 -131.897374)
				(xy 46.726094 -130.255264) (xy 46.600872 -130.130042)
			)
		)
	)
	(zone
		(layer "B.Cu")
		(hatch none 0.5)
		(connect_pads
			(clearance 0)
		)
		(min_thickness 0.25)
		(keepout
			(tracks not_allowed)
			(vias allowed)
			(pads allowed)
			(copperpour not_allowed)
			(footprints allowed)
		)
		(placement
			(enabled no)
			(sheetname "")
		)
		(fill
			(thermal_gap 0.5)
			(thermal_bridge_width 0.5)
			(island_removal_mode 0)
		)
		(polygon
			(pts
				(arc
					(start 77.658214 -67.322446)
					(mid 77.274801 -66.938652)
					(end 76.891134 -67.322192)
				)
				(xy 76.891134 -67.525392) (xy 76.981304 -67.525392)
				(arc
					(start 76.985876 -67.525138)
					(mid 77.033443 -67.519485)
					(end 77.078332 -67.502786)
				)
				(arc
					(start 77.078332 -67.502786)
					(mid 77.393059 -67.083133)
					(end 77.250036 -67.587876)
				)
				(arc
					(start 77.250036 -67.587876)
					(mid 77.145852 -67.660979)
					(end 77.023214 -67.695064)
				)
				(xy 77.021436 -67.696588) (xy 76.995528 -67.696588) (xy 76.985876 -67.696842) (xy 76.981304 -67.696588)
				(xy 76.891134 -67.696588) (xy 76.891134 -67.836288) (xy 76.98105 -67.836288) (xy 76.985622 -67.836288)
				(xy 76.995274 -67.836288) (xy 77.021182 -67.836288)
				(arc
					(start 77.02296 -67.838066)
					(mid 77.145891 -67.872177)
					(end 77.25029 -67.945508)
				)
				(arc
					(start 77.25029 -67.945508)
					(mid 77.393321 -68.449775)
					(end 77.078586 -68.030598)
				)
				(arc
					(start 77.078586 -68.030598)
					(mid 77.033455 -68.01373)
					(end 76.985622 -68.007992)
				)
				(xy 76.98105 -68.007992) (xy 76.891134 -68.007992)
				(arc
					(start 76.891134 -68.211192)
					(mid 77.274674 -68.594732)
					(end 77.658214 -68.211192)
				)
			)
		)
	)
	(zone
		(layer "B.Cu")
		(hatch none 0.5)
		(connect_pads
			(clearance 0)
		)
		(min_thickness 0.25)
		(keepout
			(tracks allowed)
			(vias allowed)
			(pads allowed)
			(copperpour allowed)
			(footprints allowed)
		)
		(placement
			(enabled no)
			(sheetname "")
		)
		(fill
			(thermal_gap 0.5)
			(thermal_bridge_width 0.5)
			(island_removal_mode 0)
		)
		(polygon
			(pts
				(xy 129.940558 -37.511228) (xy 129.940558 -35.05454) (xy 131.016248 -35.05454) (xy 131.016248 -37.511228)
			)
		)
	)
	(zone
		(layer "B.Cu")
		(hatch none 0.5)
		(connect_pads
			(clearance 0)
		)
		(min_thickness 0.25)
		(keepout
			(tracks allowed)
			(vias allowed)
			(pads allowed)
			(copperpour allowed)
			(footprints not_allowed)
		)
		(placement
			(enabled no)
			(sheetname "")
		)
		(fill
			(thermal_gap 0.5)
			(thermal_bridge_width 0.5)
			(island_removal_mode 0)
		)
		(polygon
			(pts
				(arc
					(start 160.250124 -187.999878)
					(mid 155.50007 -183.249824)
					(end 150.750016 -187.999878)
				)
				(arc
					(start 150.750016 -187.999878)
					(mid 155.50007 -192.749932)
					(end 160.250124 -187.999878)
				)
			)
		)
	)
	(zone
		(layer "B.Cu")
		(hatch none 0.5)
		(connect_pads
			(clearance 0)
		)
		(min_thickness 0.25)
		(keepout
			(tracks not_allowed)
			(vias allowed)
			(pads allowed)
			(copperpour not_allowed)
			(footprints allowed)
		)
		(placement
			(enabled no)
			(sheetname "")
		)
		(fill
			(thermal_gap 0.5)
			(thermal_bridge_width 0.5)
			(island_removal_mode 0)
		)
		(polygon
			(pts
				(arc
					(start 197.159118 -81.0641)
					(mid 197.13072 -81.057396)
					(end 197.108318 -81.0387)
				)
				(arc
					(start 197.108318 -81.2673)
					(mid 197.13072 -81.248604)
					(end 197.159118 -81.2419)
				)
				(arc
					(start 197.362318 -81.2419)
					(mid 197.390716 -81.248604)
					(end 197.413118 -81.2673)
				)
				(arc
					(start 197.413118 -81.0387)
					(mid 197.390716 -81.057396)
					(end 197.362318 -81.0641)
				)
			)
		)
	)
	(zone
		(layer "B.Cu")
		(hatch none 0.5)
		(connect_pads
			(clearance 0)
		)
		(min_thickness 0.25)
		(keepout
			(tracks allowed)
			(vias allowed)
			(pads allowed)
			(copperpour allowed)
			(footprints not_allowed)
		)
		(placement
			(enabled no)
			(sheetname "")
		)
		(fill
			(thermal_gap 0.5)
			(thermal_bridge_width 0.5)
			(island_removal_mode 0)
		)
		(polygon
			(pts
				(arc
					(start 98.249994 -9.99998)
					(mid 103.000048 -14.750034)
					(end 107.750102 -9.99998)
				)
				(arc
					(start 107.750102 -9.99998)
					(mid 103.000048 -5.249926)
					(end 98.249994 -9.99998)
				)
			)
		)
	)
	(zone
		(net "PCE_AVDD")
		(layer "B.Cu")
		(hatch none 0.5)
		(connect_pads
			(clearance 0.5)
		)
		(min_thickness 0.25)
		(fill yes
			(thermal_gap 0.5)
			(thermal_bridge_width 0.5)
			(island_removal_mode 0)
		)
		(polygon
			(pts
				(xy 191.5795 -70.4342) (xy 191.4906 -70.5231) (xy 191.4906 -71.3359) (xy 191.9732 -71.8185) (xy 192.8495 -71.8185)
				(xy 193.1035 -71.5645) (xy 193.1035 -71.1835) (xy 193.0908 -71.1835) (xy 192.3415 -70.4342)
			)
		)
		(polygon
			(pts
				(xy 192.2018 -70.7009) (xy 191.7954 -70.7009) (xy 191.7954 -70.9041) (xy 192.2018 -70.9041)
			)
		)
	)
	(zone
		(layer "B.Cu")
		(hatch none 0.5)
		(connect_pads
			(clearance 0)
		)
		(min_thickness 0.25)
		(keepout
			(tracks allowed)
			(vias allowed)
			(pads allowed)
			(copperpour allowed)
			(footprints allowed)
		)
		(placement
			(enabled no)
			(sheetname "")
		)
		(fill
			(thermal_gap 0.5)
			(thermal_bridge_width 0.5)
			(island_removal_mode 0)
		)
		(polygon
			(pts
				(xy 111.940594 -33.911032) (xy 111.940594 -31.454344) (xy 113.016284 -31.454344) (xy 113.016284 -33.911032)
			)
		)
	)
	(zone
		(layer "B.Cu")
		(hatch none 0.5)
		(connect_pads
			(clearance 0)
		)
		(min_thickness 0.25)
		(keepout
			(tracks allowed)
			(vias allowed)
			(pads allowed)
			(copperpour allowed)
			(footprints allowed)
		)
		(placement
			(enabled no)
			(sheetname "")
		)
		(fill
			(thermal_gap 0.5)
			(thermal_bridge_width 0.5)
			(island_removal_mode 0)
		)
		(polygon
			(pts
				(xy 117.340634 -35.111182) (xy 117.340634 -32.654494) (xy 118.416324 -32.654494) (xy 118.416324 -35.111182)
			)
		)
	)
	(zone
		(layer "B.Cu")
		(hatch none 0.5)
		(connect_pads
			(clearance 0)
		)
		(min_thickness 0.25)
		(keepout
			(tracks not_allowed)
			(vias allowed)
			(pads allowed)
			(copperpour not_allowed)
			(footprints allowed)
		)
		(placement
			(enabled no)
			(sheetname "")
		)
		(fill
			(thermal_gap 0.5)
			(thermal_bridge_width 0.5)
			(island_removal_mode 0)
		)
		(polygon
			(pts
				(xy 182.337964 -22.34184) (xy 182.300626 -22.281642) (xy 182.166514 -22.210014) (xy 182.16626 -22.210014)
				(xy 182.139082 -22.195282) (xy 182.111904 -22.181058) (xy 182.111904 -22.180804) (xy 182.078884 -22.163024)
				(xy 182.077614 -22.163532) (xy 182.061612 -22.154388) (xy 182.049674 -22.154388) (xy 182.036212 -22.140926)
				(xy 182.02656 -22.1361) (xy 182.019702 -22.132544)
				(arc
					(start 182.018178 -22.127972)
					(mid 181.948899 -22.028195)
					(end 181.95036 -21.906738)
				)
				(xy 181.94909 -21.902674) (xy 181.963822 -21.875496)
				(arc
					(start 182.00751 -21.793962)
					(mid 182.430118 -21.164241)
					(end 182.13959 -21.864828)
				)
				(arc
					(start 182.095902 -21.946362)
					(mid 182.090554 -21.976815)
					(end 182.104284 -22.004528)
				)
				(xy 182.111904 -22.004528) (xy 182.125366 -22.01799) (xy 182.14721 -22.028912) (xy 182.153052 -22.03196)
				(xy 182.15356 -22.032976) (xy 182.20817 -22.062186) (xy 182.235602 -22.076918) (xy 182.26278 -22.091142)
				(xy 182.26278 -22.091396) (xy 182.380382 -22.154388) (xy 182.40121 -22.159214) (xy 182.406798 -22.168358)
				(xy 182.41645 -22.173438) (xy 182.420514 -22.187408) (xy 182.668672 -21.72462) (xy 182.668418 -21.724366)
				(arc
					(start 182.666386 -21.72335)
					(mid 182.473247 -21.083725)
					(end 181.833774 -21.277072)
				)
				(xy 181.831488 -21.275802) (xy 181.081426 -22.675596)
				(arc
					(start 181.083712 -22.676866)
					(mid 181.277006 -23.316184)
					(end 181.916324 -23.12289)
				)
				(xy 181.91861 -23.12416) (xy 182.115968 -22.756114) (xy 182.012336 -22.588728) (xy 181.900322 -22.528784)
				(xy 181.886606 -22.521418) (xy 181.884066 -22.52218) (xy 181.881526 -22.520656) (xy 181.881272 -22.520656)
				(xy 181.876954 -22.517862) (xy 181.874668 -22.51837) (xy 181.854348 -22.504908)
				(arc
					(start 181.845712 -22.50059)
					(mid 181.811772 -22.501481)
					(end 181.786276 -22.523958)
				)
				(arc
					(start 181.742334 -22.606)
					(mid 181.319715 -23.235239)
					(end 181.610254 -22.535134)
				)
				(xy 181.668928 -22.425914)
				(arc
					(start 181.672738 -22.424644)
					(mid 181.772835 -22.356348)
					(end 181.893972 -22.358604)
				)
				(xy 181.896258 -22.357842) (xy 181.899052 -22.359366) (xy 181.90464 -22.35835) (xy 181.925976 -22.372574)
				(xy 181.929532 -22.374606) (xy 181.953154 -22.386544) (xy 181.955948 -22.388068) (xy 181.962806 -22.391624)
				(xy 181.96306 -22.392386) (xy 181.970934 -22.396704) (xy 181.998112 -22.411182) (xy 182.092092 -22.461474)
				(xy 182.11292 -22.4663) (xy 182.118508 -22.475444) (xy 182.12816 -22.480524) (xy 182.134256 -22.500844)
				(xy 182.197756 -22.60346)
			)
		)
	)
	(zone
		(layer "B.Cu")
		(hatch none 0.5)
		(connect_pads
			(clearance 0)
		)
		(min_thickness 0.25)
		(keepout
			(tracks not_allowed)
			(vias allowed)
			(pads allowed)
			(copperpour not_allowed)
			(footprints allowed)
		)
		(placement
			(enabled no)
			(sheetname "")
		)
		(fill
			(thermal_gap 0.5)
			(thermal_bridge_width 0.5)
			(island_removal_mode 0)
		)
		(polygon
			(pts
				(arc
					(start 191.571118 -81.0641)
					(mid 191.54272 -81.057396)
					(end 191.520318 -81.0387)
				)
				(arc
					(start 191.520318 -81.2673)
					(mid 191.54272 -81.248604)
					(end 191.571118 -81.2419)
				)
				(arc
					(start 191.774318 -81.2419)
					(mid 191.802716 -81.248604)
					(end 191.825118 -81.2673)
				)
				(arc
					(start 191.825118 -81.0387)
					(mid 191.802716 -81.057396)
					(end 191.774318 -81.0641)
				)
			)
		)
	)
	(zone
		(layer "B.Cu")
		(hatch none 0.5)
		(connect_pads
			(clearance 0)
		)
		(min_thickness 0.25)
		(keepout
			(tracks allowed)
			(vias allowed)
			(pads allowed)
			(copperpour allowed)
			(footprints allowed)
		)
		(placement
			(enabled no)
			(sheetname "")
		)
		(fill
			(thermal_gap 0.5)
			(thermal_bridge_width 0.5)
			(island_removal_mode 0)
		)
		(polygon
			(pts
				(xy 90.182954 -136.135618) (xy 91.695524 -136.135618) (xy 91.764358 -136.066784) (xy 91.764358 -135.717788)
				(xy 91.683332 -135.636762) (xy 90.171016 -135.636762) (xy 90.077544 -135.730234) (xy 90.077544 -136.030208)
			)
		)
	)
	(zone
		(net "GND")
		(layer "B.Cu")
		(hatch none 0.5)
		(connect_pads
			(clearance 0.5)
		)
		(min_thickness 0.25)
		(fill yes
			(thermal_gap 0.5)
			(thermal_bridge_width 0.5)
			(island_removal_mode 0)
		)
		(polygon
			(pts
				(xy 55.5244 -153.3398) (xy 55.3847 -153.4795) (xy 55.3847 -153.97988) (xy 55.46598 -154.06116) (xy 55.84444 -154.06116)
				(xy 56.03748 -154.2542) (xy 56.03748 -155.14066) (xy 56.13146 -155.23464) (xy 56.98744 -155.23464)
				(xy 57.14238 -155.0797) (xy 57.14238 -153.9367) (xy 56.54548 -153.3398)
			)
		)
	)
	(zone
		(layer "B.Cu")
		(hatch none 0.5)
		(connect_pads
			(clearance 0)
		)
		(min_thickness 0.25)
		(keepout
			(tracks not_allowed)
			(vias allowed)
			(pads allowed)
			(copperpour not_allowed)
			(footprints allowed)
		)
		(placement
			(enabled no)
			(sheetname "")
		)
		(fill
			(thermal_gap 0.5)
			(thermal_bridge_width 0.5)
			(island_removal_mode 0)
		)
		(polygon
			(pts
				(arc
					(start 191.575436 -25.1206)
					(mid 191.594132 -25.143002)
					(end 191.600836 -25.1714)
				)
				(arc
					(start 191.600836 -25.3746)
					(mid 191.594132 -25.402998)
					(end 191.575436 -25.4254)
				)
				(arc
					(start 191.804036 -25.4254)
					(mid 191.78534 -25.402998)
					(end 191.778636 -25.3746)
				)
				(arc
					(start 191.778636 -25.1714)
					(mid 191.78534 -25.143002)
					(end 191.804036 -25.1206)
				)
			)
		)
	)
	(zone
		(layer "B.Cu")
		(hatch none 0.5)
		(connect_pads
			(clearance 0)
		)
		(min_thickness 0.25)
		(keepout
			(tracks not_allowed)
			(vias allowed)
			(pads allowed)
			(copperpour not_allowed)
			(footprints allowed)
		)
		(placement
			(enabled no)
			(sheetname "")
		)
		(fill
			(thermal_gap 0.5)
			(thermal_bridge_width 0.5)
			(island_removal_mode 0)
		)
		(polygon
			(pts
				(arc
					(start 189.539118 -81.0641)
					(mid 189.51072 -81.057396)
					(end 189.488318 -81.0387)
				)
				(arc
					(start 189.488318 -81.2673)
					(mid 189.51072 -81.248604)
					(end 189.539118 -81.2419)
				)
				(arc
					(start 189.742318 -81.2419)
					(mid 189.770716 -81.248604)
					(end 189.793118 -81.2673)
				)
				(arc
					(start 189.793118 -81.0387)
					(mid 189.770716 -81.057396)
					(end 189.742318 -81.0641)
				)
			)
		)
	)
	(zone
		(net "GND")
		(layer "B.Cu")
		(hatch none 0.5)
		(connect_pads
			(clearance 0.5)
		)
		(min_thickness 0.25)
		(fill yes
			(thermal_gap 0.5)
			(thermal_bridge_width 0.5)
			(island_removal_mode 0)
		)
		(polygon
			(pts
				(xy 188.568838 -0.763016) (xy 188.568838 -2.794) (xy 232.206038 -2.794) (xy 232.206038 -183.340248)
				(xy 228.273356 -191.20612) (xy 151.026622 -191.20612) (xy 147.09394 -183.340248) (xy 147.09394 -147.757642)
				(xy 145.062956 -147.757642)
				(arc
					(start 145.062956 -183.76392)
					(mid 145.069351 -183.818347)
					(end 145.088102 -183.869838)
				)
				(arc
					(start 149.706076 -193.10604)
					(mid 149.793376 -193.201687)
					(end 149.917912 -193.237104)
				)
				(arc
					(start 229.382066 -193.237104)
					(mid 229.506557 -193.201614)
					(end 229.593902 -193.10604)
				)
				(arc
					(start 234.211876 -183.869838)
					(mid 234.230599 -183.818341)
					(end 234.237022 -183.76392)
				)
				(arc
					(start 234.237022 -0.999998)
					(mid 234.167612 -0.832426)
					(end 234.00004 -0.763016)
				)
			)
		)
	)
	(zone
		(layer "B.Cu")
		(hatch none 0.5)
		(connect_pads
			(clearance 0)
		)
		(min_thickness 0.25)
		(keepout
			(tracks allowed)
			(vias allowed)
			(pads allowed)
			(copperpour allowed)
			(footprints not_allowed)
		)
		(placement
			(enabled no)
			(sheetname "")
		)
		(fill
			(thermal_gap 0.5)
			(thermal_bridge_width 0.5)
			(island_removal_mode 0)
		)
		(polygon
			(pts
				(arc
					(start 7.750048 -187.999878)
					(mid 12.500102 -192.749932)
					(end 17.249902 -187.999878)
				)
				(arc
					(start 17.249902 -187.999878)
					(mid 12.500102 -183.250078)
					(end 7.750048 -187.999878)
				)
			)
		)
	)
	(zone
		(layer "B.Cu")
		(hatch none 0.5)
		(connect_pads
			(clearance 0)
		)
		(min_thickness 0.25)
		(keepout
			(tracks not_allowed)
			(vias allowed)
			(pads allowed)
			(copperpour not_allowed)
			(footprints allowed)
		)
		(placement
			(enabled no)
			(sheetname "")
		)
		(fill
			(thermal_gap 0.5)
			(thermal_bridge_width 0.5)
			(island_removal_mode 0)
		)
		(polygon
			(pts
				(arc
					(start 17.249902 -187.999878)
					(mid 12.500102 -183.250078)
					(end 7.750048 -187.999878)
				)
				(arc
					(start 7.750048 -187.999878)
					(mid 12.500102 -192.749932)
					(end 17.249902 -187.999878)
				)
			)
		)
	)
	(zone
		(layer "B.Cu")
		(hatch none 0.5)
		(connect_pads
			(clearance 0)
		)
		(min_thickness 0.25)
		(keepout
			(tracks not_allowed)
			(vias allowed)
			(pads allowed)
			(copperpour not_allowed)
			(footprints allowed)
		)
		(placement
			(enabled no)
			(sheetname "")
		)
		(fill
			(thermal_gap 0.5)
			(thermal_bridge_width 0.5)
			(island_removal_mode 0)
		)
		(polygon
			(pts
				(arc
					(start 27.649932 -105.050082)
					(mid 22.900132 -100.300282)
					(end 18.150078 -105.050082)
				)
				(arc
					(start 18.150078 -105.050082)
					(mid 22.900132 -109.800136)
					(end 27.649932 -105.050082)
				)
			)
		)
	)
	(zone
		(layer "B.Cu")
		(hatch none 0.5)
		(connect_pads
			(clearance 0)
		)
		(min_thickness 0.25)
		(keepout
			(tracks not_allowed)
			(vias allowed)
			(pads allowed)
			(copperpour not_allowed)
			(footprints allowed)
		)
		(placement
			(enabled no)
			(sheetname "")
		)
		(fill
			(thermal_gap 0.5)
			(thermal_bridge_width 0.5)
			(island_removal_mode 0)
		)
		(polygon
			(pts
				(xy 160.068514 -18.57248) (xy 159.970216 -18.43659) (xy 159.928814 -18.415762) (xy 159.927544 -18.41627)
				(xy 159.901128 -18.402046) (xy 159.874458 -18.388584) (xy 159.87395 -18.387314) (xy 159.811974 -18.354294)
				(xy 159.799528 -18.354294) (xy 159.78505 -18.339816) (xy 159.768032 -18.330926)
				(arc
					(start 159.767016 -18.327116)
					(mid 159.69855 -18.227499)
					(end 159.700214 -18.106644)
				)
				(xy 159.698944 -18.10258) (xy 159.713676 -18.075402)
				(arc
					(start 159.757364 -17.993868)
					(mid 160.179972 -17.364147)
					(end 159.889444 -18.064734)
				)
				(arc
					(start 159.845756 -18.146268)
					(mid 159.840408 -18.176721)
					(end 159.854138 -18.204434)
				)
				(xy 159.861758 -18.204434) (xy 159.875982 -18.218404) (xy 159.920686 -18.24228) (xy 159.947864 -18.257012)
				(xy 159.973264 -18.270474) (xy 160.043622 -18.30578) (xy 160.062672 -18.308828) (xy 160.070292 -18.319242)
				(xy 160.081468 -18.32483) (xy 160.087818 -18.343372) (xy 160.147254 -18.425668)
				(arc
					(start 160.413446 -17.92859)
					(mid 160.225744 -17.284948)
					(end 159.583374 -17.476978)
				)
				(arc
					(start 158.833566 -18.877026)
					(mid 159.027114 -19.516598)
					(end 159.666686 -19.32305)
				)
				(xy 159.855154 -18.97126) (xy 159.699198 -18.755614) (xy 159.687514 -18.749772) (xy 159.68726 -18.74901)
				(xy 159.681164 -18.745962) (xy 159.68091 -18.745454)
				(arc
					(start 159.603186 -18.703798)
					(mid 159.565616 -18.700241)
					(end 159.536384 -18.724118)
				)
				(arc
					(start 159.492442 -18.80616)
					(mid 159.069823 -19.435399)
					(end 159.360362 -18.735294)
				)
				(xy 159.419036 -18.626074)
				(arc
					(start 159.422846 -18.624804)
					(mid 159.522443 -18.556658)
					(end 159.643064 -18.55851)
				)
				(xy 159.646874 -18.55724) (xy 159.673798 -18.571718) (xy 159.674306 -18.571972) (xy 159.754316 -18.614644)
				(xy 159.75838 -18.613882) (xy 159.775652 -18.625312) (xy 159.791654 -18.627852) (xy 159.799274 -18.638266)
				(xy 159.81045 -18.643854) (xy 159.810704 -18.644616) (xy 159.810958 -18.644616) (xy 159.813752 -18.653252)
				(xy 159.8168 -18.662396) (xy 159.933894 -18.824194)
			)
		)
	)
	(zone
		(layer "B.Cu")
		(hatch none 0.5)
		(connect_pads
			(clearance 0)
		)
		(min_thickness 0.25)
		(keepout
			(tracks allowed)
			(vias allowed)
			(pads allowed)
			(copperpour allowed)
			(footprints allowed)
		)
		(placement
			(enabled no)
			(sheetname "")
		)
		(fill
			(thermal_gap 0.5)
			(thermal_bridge_width 0.5)
			(island_removal_mode 0)
		)
		(polygon
			(pts
				(xy 198.2724 -81.788) (xy 198.2724 -80.4926) (xy 199.3646 -80.4926) (xy 199.3646 -81.788)
			)
		)
	)
	(zone
		(net "P3V3_STBY")
		(layer "B.Cu")
		(hatch none 0.5)
		(connect_pads
			(clearance 0.5)
		)
		(min_thickness 0.25)
		(fill yes
			(thermal_gap 0.5)
			(thermal_bridge_width 0.5)
			(island_removal_mode 0)
		)
		(polygon
			(pts
				(xy 49.194466 -141.452346) (xy 49.001934 -141.644878) (xy 49.001934 -142.322296) (xy 49.168304 -142.488666)
				(xy 51.35626 -142.488666) (xy 51.50358 -142.341346) (xy 51.8668 -142.341346) (xy 52.0446 -142.519146)
				(xy 52.0446 -144.228566) (xy 52.34178 -144.525746) (xy 52.7558 -144.525746) (xy 52.959 -144.322546)
				(xy 52.959 -141.782546) (xy 52.6288 -141.452346)
			)
		)
		(polygon
			(pts
				(xy 51.41214 -141.80566) (xy 51.20894 -141.80566) (xy 51.20894 -142.00886) (xy 51.41214 -142.00886)
			)
		)
		(polygon
			(pts
				(xy 50.85334 -141.80566) (xy 50.65014 -141.80566) (xy 50.65014 -142.00886) (xy 50.85334 -142.00886)
			)
		)
	)
	(zone
		(layer "B.Cu")
		(hatch none 0.5)
		(connect_pads
			(clearance 0)
		)
		(min_thickness 0.25)
		(keepout
			(tracks allowed)
			(vias allowed)
			(pads allowed)
			(copperpour allowed)
			(footprints not_allowed)
		)
		(placement
			(enabled no)
			(sheetname "")
		)
		(fill
			(thermal_gap 0.5)
			(thermal_bridge_width 0.5)
			(island_removal_mode 0)
		)
		(polygon
			(pts
				(arc
					(start 18.050002 -60.550044)
					(mid 22.800056 -65.300098)
					(end 27.55011 -60.550044)
				)
				(arc
					(start 27.55011 -60.550044)
					(mid 22.800056 -55.79999)
					(end 18.050002 -60.550044)
				)
			)
		)
	)
	(zone
		(layer "B.Cu")
		(hatch none 0.5)
		(connect_pads
			(clearance 0)
		)
		(min_thickness 0.25)
		(keepout
			(tracks allowed)
			(vias allowed)
			(pads allowed)
			(copperpour allowed)
			(footprints allowed)
		)
		(placement
			(enabled no)
			(sheetname "")
		)
		(fill
			(thermal_gap 0.5)
			(thermal_bridge_width 0.5)
			(island_removal_mode 0)
		)
		(polygon
			(pts
				(xy 167.7162 -37.7698) (xy 168.8084 -37.7698) (xy 168.8084 -39.1414) (xy 167.7162 -39.1414)
			)
		)
	)
	(zone
		(layer "B.Cu")
		(hatch none 0.5)
		(connect_pads
			(clearance 0)
		)
		(min_thickness 0.25)
		(keepout
			(tracks allowed)
			(vias allowed)
			(pads allowed)
			(copperpour allowed)
			(footprints allowed)
		)
		(placement
			(enabled no)
			(sheetname "")
		)
		(fill
			(thermal_gap 0.5)
			(thermal_bridge_width 0.5)
			(island_removal_mode 0)
		)
		(polygon
			(pts
				(xy 137.140696 -37.511228) (xy 137.140696 -35.05454) (xy 138.216386 -35.05454) (xy 138.216386 -37.511228)
			)
		)
	)
	(zone
		(layer "B.Cu")
		(hatch none 0.5)
		(connect_pads
			(clearance 0)
		)
		(min_thickness 0.25)
		(keepout
			(tracks allowed)
			(vias allowed)
			(pads allowed)
			(copperpour allowed)
			(footprints not_allowed)
		)
		(placement
			(enabled no)
			(sheetname "")
		)
		(fill
			(thermal_gap 0.5)
			(thermal_bridge_width 0.5)
			(island_removal_mode 0)
		)
		(polygon
			(pts
				(arc
					(start 227.24999 -110.000034)
					(mid 222.499936 -105.24998)
					(end 217.749882 -110.000034)
				)
				(arc
					(start 217.749882 -110.000034)
					(mid 222.499936 -114.750088)
					(end 227.24999 -110.000034)
				)
			)
		)
	)
	(zone
		(layer "B.Cu")
		(hatch none 0.5)
		(connect_pads
			(clearance 0)
		)
		(min_thickness 0.25)
		(keepout
			(tracks allowed)
			(vias allowed)
			(pads allowed)
			(copperpour allowed)
			(footprints allowed)
		)
		(placement
			(enabled no)
			(sheetname "")
		)
		(fill
			(thermal_gap 0.5)
			(thermal_bridge_width 0.5)
			(island_removal_mode 0)
		)
		(polygon
			(pts
				(xy 63.213996 -161.23666) (xy 63.213996 -159.728408) (xy 63.919608 -159.728408) (xy 63.919608 -161.23666)
			)
		)
	)
	(zone
		(layer "B.Cu")
		(hatch none 0.5)
		(connect_pads
			(clearance 0)
		)
		(min_thickness 0.25)
		(keepout
			(tracks not_allowed)
			(vias allowed)
			(pads allowed)
			(copperpour not_allowed)
			(footprints allowed)
		)
		(placement
			(enabled no)
			(sheetname "")
		)
		(fill
			(thermal_gap 0.5)
			(thermal_bridge_width 0.5)
			(island_removal_mode 0)
		)
		(polygon
			(pts
				(arc
					(start 78.505558 -89.710768)
					(mid 78.122018 -89.327228)
					(end 77.738478 -89.710768)
				)
				(arc
					(start 77.738478 -90.599514)
					(mid 78.121891 -90.983308)
					(end 78.505558 -90.599768)
				)
				(xy 78.505558 -90.396568) (xy 78.415642 -90.396568)
				(arc
					(start 78.41107 -90.396568)
					(mid 78.363245 -90.402338)
					(end 78.318106 -90.419174)
				)
				(arc
					(start 78.318106 -90.419174)
					(mid 78.003361 -90.838372)
					(end 78.146402 -90.334084)
				)
				(arc
					(start 78.146402 -90.334084)
					(mid 78.25079 -90.260729)
					(end 78.373732 -90.226642)
				)
				(xy 78.37551 -90.224864) (xy 78.401418 -90.224864) (xy 78.41107 -90.224864) (xy 78.415642 -90.224864)
				(xy 78.505558 -90.224864) (xy 78.505558 -90.085164) (xy 78.415388 -90.085164) (xy 78.410816 -90.085418)
				(xy 78.401164 -90.085164) (xy 78.375256 -90.085164)
				(arc
					(start 78.373478 -90.08364)
					(mid 78.250807 -90.049626)
					(end 78.146656 -89.976452)
				)
				(arc
					(start 78.146656 -89.976452)
					(mid 78.003607 -89.471657)
					(end 78.31836 -89.891362)
				)
				(arc
					(start 78.31836 -89.891362)
					(mid 78.363263 -89.908002)
					(end 78.410816 -89.913714)
				)
				(xy 78.415388 -89.913968) (xy 78.505558 -89.913968)
			)
		)
	)
	(zone
		(net "P3V3_STBY")
		(layer "B.Cu")
		(hatch none 0.5)
		(connect_pads
			(clearance 0.5)
		)
		(min_thickness 0.25)
		(fill yes
			(thermal_gap 0.5)
			(thermal_bridge_width 0.5)
			(island_removal_mode 0)
		)
		(polygon
			(pts
				(xy 88.3158 -158.4706) (xy 88.011 -158.7754) (xy 88.011 -161.0614) (xy 88.1126 -161.163) (xy 90.3732 -161.163)
				(xy 90.678 -160.8582) (xy 90.678 -159.0802) (xy 90.0684 -158.4706)
			)
		)
		(polygon
			(pts
				(xy 90.4494 -160.02) (xy 90.2462 -160.02) (xy 90.2462 -160.2232) (xy 90.4494 -160.2232)
			)
		)
		(polygon
			(pts
				(xy 89.5858 -160.02) (xy 89.3826 -160.02) (xy 89.3826 -160.2232) (xy 89.5858 -160.2232)
			)
		)
		(polygon
			(pts
				(xy 89.2302 -160.02) (xy 89.027 -160.02) (xy 89.027 -160.2232) (xy 89.2302 -160.2232)
			)
		)
		(polygon
			(pts
				(xy 88.3666 -160.02) (xy 88.1634 -160.02) (xy 88.1634 -160.2232) (xy 88.3666 -160.2232)
			)
		)
	)
	(zone
		(layer "B.Cu")
		(hatch none 0.5)
		(connect_pads
			(clearance 0)
		)
		(min_thickness 0.25)
		(keepout
			(tracks not_allowed)
			(vias allowed)
			(pads allowed)
			(copperpour not_allowed)
			(footprints allowed)
		)
		(placement
			(enabled no)
			(sheetname "")
		)
		(fill
			(thermal_gap 0.5)
			(thermal_bridge_width 0.5)
			(island_removal_mode 0)
		)
		(polygon
			(pts
				(arc
					(start 201.527918 -81.0641)
					(mid 201.49952 -81.057396)
					(end 201.477118 -81.0387)
				)
				(arc
					(start 201.477118 -81.2673)
					(mid 201.49952 -81.248604)
					(end 201.527918 -81.2419)
				)
				(arc
					(start 201.731118 -81.2419)
					(mid 201.759516 -81.248604)
					(end 201.781918 -81.2673)
				)
				(arc
					(start 201.781918 -81.0387)
					(mid 201.759516 -81.057396)
					(end 201.731118 -81.0641)
				)
			)
		)
	)
	(zone
		(layer "B.Cu")
		(hatch none 0.5)
		(connect_pads
			(clearance 0)
		)
		(min_thickness 0.25)
		(keepout
			(tracks allowed)
			(vias allowed)
			(pads allowed)
			(copperpour allowed)
			(footprints allowed)
		)
		(placement
			(enabled no)
			(sheetname "")
		)
		(fill
			(thermal_gap 0.5)
			(thermal_bridge_width 0.5)
			(island_removal_mode 0)
		)
		(polygon
			(pts
				(xy 157.9372 -73.6346) (xy 163.703 -73.6346) (xy 164.719 -74.6506) (xy 166.497 -74.6506) (xy 167.513 -73.6346)
				(xy 171.2722 -73.6346) (xy 171.6786 -73.2282) (xy 171.6786 -71.5264) (xy 170.5356 -70.3834) (xy 163.4236 -70.3834)
				(xy 162.7378 -69.6976) (xy 160.1216 -69.6976) (xy 157.8864 -71.9328) (xy 157.8864 -73.5838)
			)
		)
	)
	(zone
		(net "GND")
		(layer "B.Cu")
		(hatch none 0.5)
		(connect_pads
			(clearance 0.5)
		)
		(min_thickness 0.25)
		(fill yes
			(thermal_gap 0.5)
			(thermal_bridge_width 0.5)
			(island_removal_mode 0)
		)
		(polygon
			(pts
				(xy 171.8056 -78.1812) (xy 171.8056 -80.264) (xy 172.0342 -80.4926) (xy 174.2948 -80.4926) (xy 175.9966 -78.7908)
				(xy 175.9966 -78.314042) (xy 175.863758 -78.1812)
			)
		)
		(polygon
			(pts
				(xy 174.7012 -78.9686) (xy 174.498 -78.9686) (xy 174.498 -79.1718) (xy 174.7012 -79.1718)
			)
		)
		(polygon
			(pts
				(xy 173.8376 -78.9686) (xy 173.6344 -78.9686) (xy 173.6344 -79.1718) (xy 173.8376 -79.1718)
			)
		)
		(polygon
			(pts
				(xy 175.6918 -78.359) (xy 175.2092 -78.359) (xy 175.2092 -78.5622) (xy 175.6918 -78.5622)
			)
		)
		(polygon
			(pts
				(xy 175.0568 -78.359) (xy 174.8536 -78.359) (xy 174.8536 -78.5622) (xy 175.0568 -78.5622)
			)
		)
	)
	(zone
		(layer "B.Cu")
		(hatch none 0.5)
		(connect_pads
			(clearance 0)
		)
		(min_thickness 0.25)
		(keepout
			(tracks allowed)
			(vias allowed)
			(pads allowed)
			(copperpour allowed)
			(footprints allowed)
		)
		(placement
			(enabled no)
			(sheetname "")
		)
		(fill
			(thermal_gap 0.5)
			(thermal_bridge_width 0.5)
			(island_removal_mode 0)
		)
		(polygon
			(pts
				(xy 199.5424 -81.788) (xy 199.5424 -80.4926) (xy 200.6346 -80.4926) (xy 200.6346 -81.788)
			)
		)
	)
	(zone
		(layer "B.Cu")
		(hatch none 0.5)
		(connect_pads
			(clearance 0)
		)
		(min_thickness 0.25)
		(keepout
			(tracks allowed)
			(vias allowed)
			(pads allowed)
			(copperpour allowed)
			(footprints not_allowed)
		)
		(placement
			(enabled no)
			(sheetname "")
		)
		(fill
			(thermal_gap 0.5)
			(thermal_bridge_width 0.5)
			(island_removal_mode 0)
		)
		(polygon
			(pts
				(arc
					(start 75.25004 -120.000014)
					(mid 80.000094 -124.750068)
					(end 84.749894 -120.000014)
				)
				(arc
					(start 84.749894 -120.000014)
					(mid 80.000094 -115.250214)
					(end 75.25004 -120.000014)
				)
			)
		)
	)
	(zone
		(net "GND")
		(layer "B.Cu")
		(hatch none 0.5)
		(connect_pads
			(clearance 0.5)
		)
		(min_thickness 0.25)
		(fill yes
			(thermal_gap 0.5)
			(thermal_bridge_width 0.5)
			(island_removal_mode 0)
		)
		(polygon
			(pts
				(xy 196.215 -114.3762) (xy 195.9102 -114.681) (xy 195.9102 -116.8146) (xy 196.2912 -117.1956) (xy 201.3204 -117.1956)
				(xy 201.6252 -116.8908) (xy 201.6252 -114.681) (xy 201.3204 -114.3762)
			)
		)
	)
	(zone
		(layer "B.Cu")
		(hatch none 0.5)
		(connect_pads
			(clearance 0)
		)
		(min_thickness 0.25)
		(keepout
			(tracks not_allowed)
			(vias allowed)
			(pads allowed)
			(copperpour not_allowed)
			(footprints allowed)
		)
		(placement
			(enabled no)
			(sheetname "")
		)
		(fill
			(thermal_gap 0.5)
			(thermal_bridge_width 0.5)
			(island_removal_mode 0)
		)
		(polygon
			(pts
				(arc
					(start 227.24999 -187.999878)
					(mid 222.499936 -183.249824)
					(end 217.749882 -187.999878)
				)
				(arc
					(start 217.749882 -187.999878)
					(mid 222.499936 -192.749932)
					(end 227.24999 -187.999878)
				)
			)
		)
	)
	(zone
		(layer "B.Cu")
		(hatch none 0.5)
		(connect_pads
			(clearance 0)
		)
		(min_thickness 0.25)
		(keepout
			(tracks not_allowed)
			(vias allowed)
			(pads allowed)
			(copperpour not_allowed)
			(footprints allowed)
		)
		(placement
			(enabled no)
			(sheetname "")
		)
		(fill
			(thermal_gap 0.5)
			(thermal_bridge_width 0.5)
			(island_removal_mode 0)
		)
		(polygon
			(pts
				(arc
					(start 200.969118 -81.0641)
					(mid 200.94072 -81.057396)
					(end 200.918318 -81.0387)
				)
				(arc
					(start 200.918318 -81.2673)
					(mid 200.94072 -81.248604)
					(end 200.969118 -81.2419)
				)
				(arc
					(start 201.172318 -81.2419)
					(mid 201.200716 -81.248604)
					(end 201.223118 -81.2673)
				)
				(arc
					(start 201.223118 -81.0387)
					(mid 201.200716 -81.057396)
					(end 201.172318 -81.0641)
				)
			)
		)
	)
	(zone
		(layer "B.Cu")
		(hatch none 0.5)
		(connect_pads
			(clearance 0)
		)
		(min_thickness 0.25)
		(keepout
			(tracks allowed)
			(vias allowed)
			(pads allowed)
			(copperpour allowed)
			(footprints allowed)
		)
		(placement
			(enabled no)
			(sheetname "")
		)
		(fill
			(thermal_gap 0.5)
			(thermal_bridge_width 0.5)
			(island_removal_mode 0)
		)
		(polygon
			(pts
				(xy 192.6844 -81.8134) (xy 192.6844 -80.518) (xy 193.7766 -80.518) (xy 193.7766 -81.8134)
			)
		)
	)
	(zone
		(net "P1V15_STBY")
		(layer "B.Cu")
		(hatch none 0.5)
		(connect_pads
			(clearance 0.5)
		)
		(min_thickness 0.25)
		(fill yes
			(thermal_gap 0.5)
			(thermal_bridge_width 0.5)
			(island_removal_mode 0)
		)
		(polygon
			(pts
				(xy 45.18533 -146.989546) (xy 45.085762 -147.089114) (xy 45.085762 -149.174708) (xy 45.2882 -149.377146)
				(xy 46.0248 -149.377146) (xy 46.8122 -148.589746) (xy 47.8917 -148.589746) (xy 47.96028 -148.521166)
				(xy 47.96028 -147.210526) (xy 47.7393 -146.989546)
			)
		)
		(polygon
			(pts
				(xy 46.63567 -148.003514) (xy 46.43247 -148.003514) (xy 46.43247 -148.206714) (xy 46.63567 -148.206714)
			)
		)
		(polygon
			(pts
				(xy 45.77207 -148.003514) (xy 45.56887 -148.003514) (xy 45.56887 -148.206714) (xy 45.77207 -148.206714)
			)
		)
		(polygon
			(pts
				(xy 47.038006 -147.45335) (xy 46.834806 -147.45335) (xy 46.834806 -147.65655) (xy 47.038006 -147.65655)
			)
		)
		(polygon
			(pts
				(xy 46.63567 -147.139914) (xy 46.43247 -147.139914) (xy 46.43247 -147.343114) (xy 46.63567 -147.343114)
			)
		)
		(polygon
			(pts
				(xy 45.77207 -147.139914) (xy 45.56887 -147.139914) (xy 45.56887 -147.343114) (xy 45.77207 -147.343114)
			)
		)
	)
	(zone
		(net "GND")
		(layer "B.Cu")
		(hatch none 0.5)
		(connect_pads
			(clearance 0.5)
		)
		(min_thickness 0.25)
		(fill yes
			(thermal_gap 0.5)
			(thermal_bridge_width 0.5)
			(island_removal_mode 0)
		)
		(polygon
			(pts
				(xy 165.856412 -103.426514) (xy 164.993574 -104.289352) (xy 164.993574 -112.38865) (xy 165.673278 -113.068354)
				(xy 167.94861 -113.068354) (xy 168.536366 -112.480598) (xy 168.536366 -103.970836) (xy 167.992044 -103.426514)
			)
		)
		(polygon
			(pts
				(xy 167.9956 -108.4072) (xy 167.7924 -108.4072) (xy 167.7924 -108.6104) (xy 167.9956 -108.6104)
			)
		)
		(polygon
			(pts
				(xy 167.9956 -107.7976) (xy 167.7924 -107.7976) (xy 167.7924 -108.0008) (xy 167.9956 -108.0008)
			)
		)
		(polygon
			(pts
				(xy 167.9956 -107.2642) (xy 167.7924 -107.2642) (xy 167.7924 -107.4674) (xy 167.9956 -107.4674)
			)
		)
		(polygon
			(pts
				(xy 167.9956 -106.6546) (xy 167.7924 -106.6546) (xy 167.7924 -106.8578) (xy 167.9956 -106.8578)
			)
		)
		(polygon
			(pts
				(xy 167.9956 -106.2482) (xy 167.7924 -106.2482) (xy 167.7924 -106.4514) (xy 167.9956 -106.4514)
			)
		)
		(polygon
			(pts
				(xy 167.9956 -105.6386) (xy 167.7924 -105.6386) (xy 167.7924 -105.8418) (xy 167.9956 -105.8418)
			)
		)
		(polygon
			(pts
				(xy 167.9956 -105.2322) (xy 167.7924 -105.2322) (xy 167.7924 -105.4354) (xy 167.9956 -105.4354)
			)
		)
		(polygon
			(pts
				(xy 167.9956 -104.6226) (xy 167.7924 -104.6226) (xy 167.7924 -104.8258) (xy 167.9956 -104.8258)
			)
		)
	)
	(zone
		(net "GND")
		(layer "B.Cu")
		(hatch none 0.5)
		(connect_pads
			(clearance 0.5)
		)
		(min_thickness 0.25)
		(fill yes
			(thermal_gap 0.5)
			(thermal_bridge_width 0.5)
			(island_removal_mode 0)
		)
		(polygon
			(pts
				(xy 15.0876 -167.500808) (xy 15.0876 -170.761914) (xy 18.301208 -170.761914) (xy 18.301208 -167.500808)
			)
		)
	)
	(zone
		(net "AGND_CURRENT_MON")
		(layer "B.Cu")
		(hatch none 0.5)
		(connect_pads
			(clearance 0.5)
		)
		(min_thickness 0.25)
		(fill yes
			(thermal_gap 0.5)
			(thermal_bridge_width 0.5)
			(island_removal_mode 0)
		)
		(polygon
			(pts
				(xy 125.179836 -11.6078) (xy 125.114558 -11.673078) (xy 125.114558 -13.048996) (xy 125.298962 -13.2334)
				(xy 127.4064 -13.2334) (xy 128.6002 -14.4272) (xy 129.3876 -14.4272) (xy 129.7432 -14.0716) (xy 130.3782 -14.0716)
				(xy 130.4798 -13.97) (xy 130.4798 -13.589) (xy 129.3368 -12.446) (xy 128.9812 -12.446) (xy 128.143 -11.6078)
			)
		)
		(polygon
			(pts
				(xy 129.94386 -13.404342) (xy 129.74066 -13.404342) (xy 129.74066 -13.607542) (xy 129.94386 -13.607542)
			)
		)
		(polygon
			(pts
				(xy 129.53873 -13.385038) (xy 129.33553 -13.385038) (xy 129.33553 -13.588238) (xy 129.53873 -13.588238)
			)
		)
		(polygon
			(pts
				(xy 128.67513 -13.385038) (xy 128.47193 -13.385038) (xy 128.47193 -13.588238) (xy 128.67513 -13.588238)
			)
		)
		(polygon
			(pts
				(xy 127.485394 -12.79271) (xy 127.282194 -12.79271) (xy 127.282194 -12.99591) (xy 127.485394 -12.99591)
			)
		)
		(polygon
			(pts
				(xy 126.926594 -12.79271) (xy 126.723394 -12.79271) (xy 126.723394 -12.99591) (xy 126.926594 -12.99591)
			)
		)
		(polygon
			(pts
				(xy 126.5174 -12.32281) (xy 126.3142 -12.32281) (xy 126.3142 -12.52601) (xy 126.5174 -12.52601)
			)
		)
		(polygon
			(pts
				(xy 125.6538 -12.32281) (xy 125.4506 -12.32281) (xy 125.4506 -12.52601) (xy 125.6538 -12.52601)
			)
		)
	)
	(zone
		(net "GND")
		(layer "B.Cu")
		(hatch none 0.5)
		(connect_pads
			(clearance 0.5)
		)
		(min_thickness 0.25)
		(fill yes
			(thermal_gap 0.5)
			(thermal_bridge_width 0.5)
			(island_removal_mode 0)
		)
		(polygon
			(pts
				(xy 154.559 -118.237) (xy 153.797 -118.999) (xy 153.797 -122.936) (xy 154.051 -123.19) (xy 156.591 -123.19)
				(xy 156.845 -122.936) (xy 156.845 -118.618) (xy 156.464 -118.237)
			)
		)
	)
	(zone
		(layer "B.Cu")
		(hatch none 0.5)
		(connect_pads
			(clearance 0)
		)
		(min_thickness 0.25)
		(keepout
			(tracks not_allowed)
			(vias allowed)
			(pads allowed)
			(copperpour not_allowed)
			(footprints allowed)
		)
		(placement
			(enabled no)
			(sheetname "")
		)
		(fill
			(thermal_gap 0.5)
			(thermal_bridge_width 0.5)
			(island_removal_mode 0)
		)
		(polygon
			(pts
				(arc
					(start 227.24999 -14.99997)
					(mid 222.499936 -10.249916)
					(end 217.749882 -14.99997)
				)
				(arc
					(start 217.749882 -14.99997)
					(mid 222.499936 -19.750024)
					(end 227.24999 -14.99997)
				)
			)
		)
	)
	(zone
		(layer "B.Cu")
		(hatch none 0.5)
		(connect_pads
			(clearance 0)
		)
		(min_thickness 0.25)
		(keepout
			(tracks not_allowed)
			(vias allowed)
			(pads allowed)
			(copperpour not_allowed)
			(footprints allowed)
		)
		(placement
			(enabled no)
			(sheetname "")
		)
		(fill
			(thermal_gap 0.5)
			(thermal_bridge_width 0.5)
			(island_removal_mode 0)
		)
		(polygon
			(pts
				(arc
					(start 45.200062 -169.999914)
					(mid 41.450006 -166.249858)
					(end 37.69995 -169.999914)
				)
				(arc
					(start 37.69995 -169.999914)
					(mid 41.450006 -173.74997)
					(end 45.200062 -169.999914)
				)
			)
		)
	)
	(zone
		(layer "B.Cu")
		(hatch none 0.5)
		(connect_pads
			(clearance 0)
		)
		(min_thickness 0.25)
		(keepout
			(tracks allowed)
			(vias allowed)
			(pads allowed)
			(copperpour allowed)
			(footprints allowed)
		)
		(placement
			(enabled no)
			(sheetname "")
		)
		(fill
			(thermal_gap 0.5)
			(thermal_bridge_width 0.5)
			(island_removal_mode 0)
		)
		(polygon
			(pts
				(xy 191.4144 -81.8134) (xy 191.4144 -80.518) (xy 192.5066 -80.518) (xy 192.5066 -81.8134)
			)
		)
	)
	(zone
		(layer "B.Cu")
		(hatch none 0.5)
		(connect_pads
			(clearance 0)
		)
		(min_thickness 0.25)
		(keepout
			(tracks allowed)
			(vias allowed)
			(pads allowed)
			(copperpour allowed)
			(footprints allowed)
		)
		(placement
			(enabled no)
			(sheetname "")
		)
		(fill
			(thermal_gap 0.5)
			(thermal_bridge_width 0.5)
			(island_removal_mode 0)
		)
		(polygon
			(pts
				(xy 169.1132 -37.7698) (xy 170.2054 -37.7698) (xy 170.2054 -39.1414) (xy 169.1132 -39.1414)
			)
		)
	)
	(zone
		(layer "B.Cu")
		(hatch none 0.5)
		(connect_pads
			(clearance 0)
		)
		(min_thickness 0.25)
		(keepout
			(tracks not_allowed)
			(vias allowed)
			(pads allowed)
			(copperpour not_allowed)
			(footprints allowed)
		)
		(placement
			(enabled no)
			(sheetname "")
		)
		(fill
			(thermal_gap 0.5)
			(thermal_bridge_width 0.5)
			(island_removal_mode 0)
		)
		(polygon
			(pts
				(xy 139.014708 -37.429948) (xy 139.014708 -37.568632) (xy 139.04595 -37.569648) (xy 139.050522 -37.569648)
				(xy 139.323826 -37.569648) (xy 139.328398 -37.569648) (xy 139.336526 -37.569648) (xy 139.363958 -37.569648)
				(arc
					(start 139.366752 -37.572442)
					(mid 139.444482 -37.597206)
					(end 139.510516 -37.645086)
				)
				(arc
					(start 139.510516 -37.645086)
					(mid 139.558167 -37.710921)
					(end 139.582906 -37.788342)
				)
				(xy 139.5857 -37.791136)
				(arc
					(start 139.5857 -37.815774)
					(mid 139.500749 -38.593795)
					(end 139.413234 -37.816028)
				)
				(arc
					(start 139.413234 -37.816028)
					(mid 139.405254 -37.789279)
					(end 139.389104 -37.766498)
				)
				(arc
					(start 139.389104 -37.766498)
					(mid 139.361252 -37.747888)
					(end 139.328398 -37.741352)
				)
				(xy 139.323826 -37.741352) (xy 139.050522 -37.741352) (xy 139.04595 -37.741352) (xy 139.032742 -37.741352)
				(xy 139.014708 -37.741352)
				(arc
					(start 139.014708 -38.200076)
					(mid 139.499848 -38.685216)
					(end 139.984988 -38.200076)
				)
				(arc
					(start 139.984988 -36.800282)
					(mid 139.499975 -36.314888)
					(end 139.014708 -36.800028)
				)
				(arc
					(start 139.014708 -37.256212)
					(mid 139.030285 -37.257951)
					(end 139.04595 -37.258498)
				)
				(xy 139.050522 -37.258752) (xy 139.26947 -37.258752)
				(arc
					(start 139.274042 -37.258498)
					(mid 139.327503 -37.247864)
					(end 139.372848 -37.217604)
				)
				(arc
					(start 139.372848 -37.217604)
					(mid 139.387546 -37.200259)
					(end 139.399264 -37.180774)
				)
				(arc
					(start 139.399264 -37.180774)
					(mid 139.510683 -36.406441)
					(end 139.578334 -37.185854)
				)
				(arc
					(start 139.578334 -37.185854)
					(mid 139.547249 -37.26845)
					(end 139.49426 -37.339016)
				)
				(arc
					(start 139.49426 -37.339016)
					(mid 139.410404 -37.398793)
					(end 139.311634 -37.427916)
				)
				(xy 139.309602 -37.429948) (xy 139.282932 -37.429948) (xy 139.274042 -37.430202) (xy 139.26947 -37.429948)
				(xy 139.050522 -37.429948) (xy 139.04595 -37.430202) (xy 139.036298 -37.429948)
			)
		)
	)
	(zone
		(net "GND")
		(layer "B.Cu")
		(hatch none 0.5)
		(connect_pads
			(clearance 0.5)
		)
		(min_thickness 0.25)
		(fill yes
			(thermal_gap 0.5)
			(thermal_bridge_width 0.5)
			(island_removal_mode 0)
		)
		(polygon
			(pts
				(xy 32.639 -178.7906) (xy 32.639 -184.3532) (xy 35.9664 -184.3532) (xy 35.9664 -178.7906)
			)
		)
	)
	(zone
		(layer "B.Cu")
		(hatch none 0.5)
		(connect_pads
			(clearance 0)
		)
		(min_thickness 0.25)
		(keepout
			(tracks allowed)
			(vias allowed)
			(pads allowed)
			(copperpour allowed)
			(footprints not_allowed)
		)
		(placement
			(enabled no)
			(sheetname "")
		)
		(fill
			(thermal_gap 0.5)
			(thermal_bridge_width 0.5)
			(island_removal_mode 0)
		)
		(polygon
			(pts
				(arc
					(start 22.750018 -24.99995)
					(mid 17.999964 -20.249896)
					(end 13.24991 -24.99995)
				)
				(arc
					(start 13.24991 -24.99995)
					(mid 17.999964 -29.750004)
					(end 22.750018 -24.99995)
				)
			)
		)
	)
	(zone
		(layer "B.Cu")
		(hatch none 0.5)
		(connect_pads
			(clearance 0)
		)
		(min_thickness 0.25)
		(keepout
			(tracks allowed)
			(vias allowed)
			(pads allowed)
			(copperpour allowed)
			(footprints not_allowed)
		)
		(placement
			(enabled no)
			(sheetname "")
		)
		(fill
			(thermal_gap 0.5)
			(thermal_bridge_width 0.5)
			(island_removal_mode 0)
		)
		(polygon
			(pts
				(arc
					(start 216.799922 -84.479892)
					(mid 219.799916 -87.479886)
					(end 222.79991 -84.479892)
				)
				(arc
					(start 222.79991 -84.479892)
					(mid 219.799916 -81.479898)
					(end 216.799922 -84.479892)
				)
			)
		)
	)
	(zone
		(layer "B.Cu")
		(hatch none 0.5)
		(connect_pads
			(clearance 0)
		)
		(min_thickness 0.25)
		(keepout
			(tracks allowed)
			(vias allowed)
			(pads allowed)
			(copperpour allowed)
			(footprints not_allowed)
		)
		(placement
			(enabled no)
			(sheetname "")
		)
		(fill
			(thermal_gap 0.5)
			(thermal_bridge_width 0.5)
			(island_removal_mode 0)
		)
		(polygon
			(pts
				(arc
					(start 84.749894 -120.000014)
					(mid 80.000094 -115.250214)
					(end 75.25004 -120.000014)
				)
				(arc
					(start 75.25004 -120.000014)
					(mid 80.000094 -124.750068)
					(end 84.749894 -120.000014)
				)
			)
		)
	)
	(zone
		(layer "B.Cu")
		(hatch none 0.5)
		(connect_pads
			(clearance 0)
		)
		(min_thickness 0.25)
		(keepout
			(tracks allowed)
			(vias allowed)
			(pads allowed)
			(copperpour allowed)
			(footprints not_allowed)
		)
		(placement
			(enabled no)
			(sheetname "")
		)
		(fill
			(thermal_gap 0.5)
			(thermal_bridge_width 0.5)
			(island_removal_mode 0)
		)
		(polygon
			(pts
				(arc
					(start 97.249996 -187.999878)
					(mid 92.499942 -183.249824)
					(end 87.749888 -187.999878)
				)
				(arc
					(start 87.749888 -187.999878)
					(mid 92.499942 -192.749932)
					(end 97.249996 -187.999878)
				)
			)
		)
	)
	(zone
		(layer "B.Cu")
		(hatch none 0.5)
		(connect_pads
			(clearance 0)
		)
		(min_thickness 0.25)
		(keepout
			(tracks allowed)
			(vias allowed)
			(pads allowed)
			(copperpour allowed)
			(footprints not_allowed)
		)
		(placement
			(enabled no)
			(sheetname "")
		)
		(fill
			(thermal_gap 0.5)
			(thermal_bridge_width 0.5)
			(island_removal_mode 0)
		)
		(polygon
			(pts
				(arc
					(start 107.750102 -9.99998)
					(mid 103.000048 -5.249926)
					(end 98.249994 -9.99998)
				)
				(arc
					(start 98.249994 -9.99998)
					(mid 103.000048 -14.750034)
					(end 107.750102 -9.99998)
				)
			)
		)
	)
	(zone
		(layer "B.Cu")
		(hatch none 0.5)
		(connect_pads
			(clearance 0)
		)
		(min_thickness 0.25)
		(keepout
			(tracks allowed)
			(vias allowed)
			(pads allowed)
			(copperpour allowed)
			(footprints not_allowed)
		)
		(placement
			(enabled no)
			(sheetname "")
		)
		(fill
			(thermal_gap 0.5)
			(thermal_bridge_width 0.5)
			(island_removal_mode 0)
		)
		(polygon
			(pts
				(arc
					(start 87.749888 -187.999878)
					(mid 92.499942 -192.749932)
					(end 97.249996 -187.999878)
				)
				(arc
					(start 97.249996 -187.999878)
					(mid 92.499942 -183.249824)
					(end 87.749888 -187.999878)
				)
			)
		)
	)
	(zone
		(layer "B.Cu")
		(hatch none 0.5)
		(connect_pads
			(clearance 0)
		)
		(min_thickness 0.25)
		(keepout
			(tracks allowed)
			(vias allowed)
			(pads allowed)
			(copperpour allowed)
			(footprints allowed)
		)
		(placement
			(enabled no)
			(sheetname "")
		)
		(fill
			(thermal_gap 0.5)
			(thermal_bridge_width 0.5)
			(island_removal_mode 0)
		)
		(polygon
			(pts
				(xy 77.414628 -134.198106) (xy 77.414628 -133.56971) (xy 79.052928 -133.56971) (xy 79.052928 -134.198106)
			)
		)
	)
	(zone
		(layer "B.Cu")
		(hatch none 0.5)
		(connect_pads
			(clearance 0)
		)
		(min_thickness 0.25)
		(keepout
			(tracks allowed)
			(vias allowed)
			(pads allowed)
			(copperpour allowed)
			(footprints not_allowed)
		)
		(placement
			(enabled no)
			(sheetname "")
		)
		(fill
			(thermal_gap 0.5)
			(thermal_bridge_width 0.5)
			(island_removal_mode 0)
		)
		(polygon
			(pts
				(arc
					(start 83.300062 -105.050082)
					(mid 78.550008 -100.300028)
					(end 73.799954 -105.050082)
				)
				(arc
					(start 73.799954 -105.050082)
					(mid 78.550008 -109.800136)
					(end 83.300062 -105.050082)
				)
			)
		)
	)
	(zone
		(net "GND")
		(layer "B.Cu")
		(hatch none 0.5)
		(connect_pads
			(clearance 0.5)
		)
		(min_thickness 0.25)
		(fill yes
			(thermal_gap 0.5)
			(thermal_bridge_width 0.5)
			(island_removal_mode 0)
		)
		(polygon
			(pts
				(xy 212.1916 -83.9724) (xy 212.09 -84.074) (xy 212.09 -86.741) (xy 212.217 -86.868) (xy 214.5284 -86.868)
				(xy 214.7316 -86.6648) (xy 214.7316 -84.3788) (xy 214.3252 -83.9724)
			)
		)
		(polygon
			(pts
				(xy 213.0806 -84.7852) (xy 212.8774 -84.7852) (xy 212.8774 -84.9884) (xy 213.0806 -84.9884)
			)
		)
	)
	(zone
		(net "P0V975")
		(layer "B.Cu")
		(hatch none 0.5)
		(connect_pads
			(clearance 0.5)
		)
		(min_thickness 0.25)
		(fill yes
			(thermal_gap 0.5)
			(thermal_bridge_width 0.5)
			(island_removal_mode 0)
		)
		(polygon
			(pts
				(xy 179.078636 -81.271364) (xy 178.9938 -81.3562) (xy 178.9938 -82.7786) (xy 179.3748 -83.1596)
				(xy 184.277 -83.1596) (xy 184.90946 -82.52714) (xy 184.90946 -81.71434) (xy 184.83834 -81.64322)
				(xy 182.17388 -81.64322) (xy 182.030878 -81.786222) (xy 180.422042 -81.786222) (xy 179.907184 -81.271364)
			)
		)
		(polygon
			(pts
				(xy 183.94426 -82.15884) (xy 183.74106 -82.15884) (xy 183.74106 -82.36204) (xy 183.94426 -82.36204)
				(xy 184.0357 -82.36712) (xy 184.2389 -82.36712) (xy 184.2389 -82.16392) (xy 184.0357 -82.16392)
			)
		)
		(polygon
			(pts
				(xy 183.23306 -82.15884) (xy 182.77586 -82.15884) (xy 182.77586 -82.36204) (xy 183.23306 -82.36204)
			)
		)
		(polygon
			(pts
				(xy 182.26786 -82.15884) (xy 182.06466 -82.15884) (xy 182.06466 -82.36204) (xy 182.26786 -82.36204)
			)
		)
		(polygon
			(pts
				(xy 180.00472 -82.02676) (xy 179.80152 -82.02676) (xy 179.80152 -82.22996) (xy 180.00472 -82.22996)
			)
		)
	)
	(zone
		(layer "B.Cu")
		(hatch none 0.5)
		(connect_pads
			(clearance 0)
		)
		(min_thickness 0.25)
		(keepout
			(tracks not_allowed)
			(vias allowed)
			(pads allowed)
			(copperpour not_allowed)
			(footprints allowed)
		)
		(placement
			(enabled no)
			(sheetname "")
		)
		(fill
			(thermal_gap 0.5)
			(thermal_bridge_width 0.5)
			(island_removal_mode 0)
		)
		(polygon
			(pts
				(xy 160.059624 -22.389592) (xy 159.83585 -22.165818) (xy 159.822642 -22.159214) (xy 159.821372 -22.159722)
				(xy 159.79521 -22.145498) (xy 159.768286 -22.132036) (xy 159.768032 -22.130766) (xy 159.766762 -22.130004)
				(xy 159.75838 -22.101302) (xy 159.748982 -22.073108) (xy 159.74949 -22.071838) (xy 159.707834 -21.932392)
				(xy 159.698944 -21.902674) (xy 159.699198 -21.902674) (xy 159.698944 -21.90242) (xy 159.713676 -21.875242)
				(arc
					(start 159.757364 -21.793962)
					(mid 160.179972 -21.164241)
					(end 159.889444 -21.864828)
				)
				(xy 159.860234 -21.91893) (xy 159.892238 -22.026626) (xy 159.89808 -22.02942) (xy 159.911288 -22.02942)
				(xy 159.92475 -22.042882) (xy 159.941768 -22.051264) (xy 159.945832 -22.063964) (xy 160.133538 -22.251416)
				(arc
					(start 160.416494 -21.723096)
					(mid 160.222946 -21.083524)
					(end 159.583374 -21.277072)
				)
				(arc
					(start 158.836614 -22.671278)
					(mid 159.024316 -23.31492)
					(end 159.666686 -23.12289)
				)
				(xy 159.798004 -22.87778) (xy 159.798004 -22.702774)
				(arc
					(start 159.596074 -22.500844)
					(mid 159.561962 -22.501616)
					(end 159.536384 -22.524212)
				)
				(arc
					(start 159.492696 -22.606)
					(mid 159.070088 -23.235721)
					(end 159.360616 -22.535134)
				)
				(xy 159.404304 -22.4536) (xy 159.419036 -22.426168)
				(arc
					(start 159.422846 -22.424898)
					(mid 159.521789 -22.356951)
					(end 159.641794 -22.358096)
				)
				(xy 159.644842 -22.35708) (xy 159.657288 -22.36343) (xy 159.670496 -22.36343) (xy 159.683958 -22.376892)
				(xy 159.700722 -22.385274) (xy 159.70504 -22.397974) (xy 159.760666 -22.4536) (xy 159.932878 -22.625812)
			)
		)
	)
	(zone
		(layer "B.Cu")
		(hatch none 0.5)
		(connect_pads
			(clearance 0)
		)
		(min_thickness 0.25)
		(keepout
			(tracks allowed)
			(vias allowed)
			(pads allowed)
			(copperpour allowed)
			(footprints not_allowed)
		)
		(placement
			(enabled no)
			(sheetname "")
		)
		(fill
			(thermal_gap 0.5)
			(thermal_bridge_width 0.5)
			(island_removal_mode 0)
		)
		(polygon
			(pts
				(arc
					(start 27.649932 -105.050082)
					(mid 22.900132 -100.300282)
					(end 18.150078 -105.050082)
				)
				(arc
					(start 18.150078 -105.050082)
					(mid 22.900132 -109.800136)
					(end 27.649932 -105.050082)
				)
			)
		)
	)
	(zone
		(layer "B.Cu")
		(hatch none 0.5)
		(connect_pads
			(clearance 0)
		)
		(min_thickness 0.25)
		(keepout
			(tracks not_allowed)
			(vias allowed)
			(pads allowed)
			(copperpour not_allowed)
			(footprints allowed)
		)
		(placement
			(enabled no)
			(sheetname "")
		)
		(fill
			(thermal_gap 0.5)
			(thermal_bridge_width 0.5)
			(island_removal_mode 0)
		)
		(polygon
			(pts
				(arc
					(start 78.505558 -70.508368)
					(mid 78.122018 -70.124828)
					(end 77.738478 -70.508368)
				)
				(arc
					(start 77.738478 -71.397114)
					(mid 78.121891 -71.780908)
					(end 78.505558 -71.397368)
				)
				(xy 78.505558 -71.194168) (xy 78.3844 -71.194168)
				(arc
					(start 78.379828 -71.194168)
					(mid 78.344405 -71.197803)
					(end 78.310486 -71.208646)
				)
				(arc
					(start 78.310486 -71.208646)
					(mid 78.016641 -71.642382)
					(end 78.129384 -71.130668)
				)
				(arc
					(start 78.129384 -71.130668)
					(mid 78.226438 -71.058499)
					(end 78.34249 -71.024496)
				)
				(xy 78.344268 -71.022464) (xy 78.37043 -71.022464) (xy 78.379828 -71.022464) (xy 78.3844 -71.022464)
				(xy 78.505558 -71.022464) (xy 78.505558 -70.882764) (xy 78.3844 -70.882764) (xy 78.379828 -70.883018)
				(xy 78.37043 -70.882764) (xy 78.344268 -70.882764)
				(arc
					(start 78.34249 -70.880986)
					(mid 78.226636 -70.846988)
					(end 78.129638 -70.775068)
				)
				(arc
					(start 78.129638 -70.775068)
					(mid 78.016322 -70.263388)
					(end 78.31074 -70.696836)
				)
				(arc
					(start 78.31074 -70.696836)
					(mid 78.344533 -70.707663)
					(end 78.379828 -70.711314)
				)
				(xy 78.3844 -70.711568) (xy 78.505558 -70.711568)
			)
		)
	)
	(zone
		(layer "B.Cu")
		(hatch none 0.5)
		(connect_pads
			(clearance 0)
		)
		(min_thickness 0.25)
		(keepout
			(tracks allowed)
			(vias allowed)
			(pads allowed)
			(copperpour allowed)
			(footprints not_allowed)
		)
		(placement
			(enabled no)
			(sheetname "")
		)
		(fill
			(thermal_gap 0.5)
			(thermal_bridge_width 0.5)
			(island_removal_mode 0)
		)
		(polygon
			(pts
				(arc
					(start 162.500056 -14.699996)
					(mid 160.000188 -12.200128)
					(end 157.500066 -14.699996)
				)
				(arc
					(start 157.500066 -14.699996)
					(mid 160.000188 -17.200118)
					(end 162.500056 -14.699996)
				)
			)
		)
	)
	(zone
		(net "GND")
		(layer "B.Cu")
		(hatch none 0.5)
		(connect_pads
			(clearance 0.5)
		)
		(min_thickness 0.25)
		(fill yes
			(thermal_gap 0.5)
			(thermal_bridge_width 0.5)
			(island_removal_mode 0)
		)
		(polygon
			(pts
				(xy 95.70085 -5.082794) (xy 95.54083 -5.242814) (xy 95.54083 -8.67283) (xy 95.758 -8.89) (xy 96.774 -8.89)
				(xy 97.917 -7.747) (xy 97.917 -5.318252) (xy 97.681542 -5.082794)
			)
		)
		(polygon
			(pts
				(xy 96.1898 -8.0518) (xy 95.9866 -8.0518) (xy 95.9866 -8.255) (xy 96.1898 -8.255)
			)
		)
		(polygon
			(pts
				(xy 96.1898 -7.493) (xy 95.9866 -7.493) (xy 95.9866 -7.6962) (xy 96.1898 -7.6962)
			)
		)
	)
	(zone
		(layer "B.Cu")
		(hatch none 0.5)
		(connect_pads
			(clearance 0)
		)
		(min_thickness 0.25)
		(keepout
			(tracks not_allowed)
			(vias allowed)
			(pads allowed)
			(copperpour not_allowed)
			(footprints allowed)
		)
		(placement
			(enabled no)
			(sheetname "")
		)
		(fill
			(thermal_gap 0.5)
			(thermal_bridge_width 0.5)
			(island_removal_mode 0)
		)
		(polygon
			(pts
				(arc
					(start 97.249996 -187.999878)
					(mid 92.499942 -183.249824)
					(end 87.749888 -187.999878)
				)
				(arc
					(start 87.749888 -187.999878)
					(mid 92.499942 -192.749932)
					(end 97.249996 -187.999878)
				)
			)
		)
	)
	(zone
		(layer "B.Cu")
		(hatch none 0.5)
		(connect_pads
			(clearance 0)
		)
		(min_thickness 0.25)
		(keepout
			(tracks allowed)
			(vias allowed)
			(pads allowed)
			(copperpour allowed)
			(footprints not_allowed)
		)
		(placement
			(enabled no)
			(sheetname "")
		)
		(fill
			(thermal_gap 0.5)
			(thermal_bridge_width 0.5)
			(island_removal_mode 0)
		)
		(polygon
			(pts
				(arc
					(start 217.749882 -187.999878)
					(mid 222.499936 -192.749932)
					(end 227.24999 -187.999878)
				)
				(arc
					(start 227.24999 -187.999878)
					(mid 222.499936 -183.249824)
					(end 217.749882 -187.999878)
				)
			)
		)
	)
	(zone
		(net "P1V8")
		(layer "B.Cu")
		(hatch none 0.5)
		(connect_pads
			(clearance 0.5)
		)
		(min_thickness 0.25)
		(fill yes
			(thermal_gap 0.5)
			(thermal_bridge_width 0.5)
			(island_removal_mode 0)
		)
		(polygon
			(pts
				(xy 168.86936 -104.704388) (xy 168.76649 -104.807258) (xy 168.76649 -115.7097) (xy 168.98239 -115.9256)
				(xy 172.2501 -115.9256) (xy 172.580808 -115.594892) (xy 172.580808 -105.108502) (xy 172.176694 -104.704388)
			)
		)
		(polygon
			(pts
				(xy 169.5196 -108.4072) (xy 169.3164 -108.4072) (xy 169.3164 -108.6104) (xy 169.5196 -108.6104)
			)
		)
		(polygon
			(pts
				(xy 169.5196 -107.7976) (xy 169.3164 -107.7976) (xy 169.3164 -108.0008) (xy 169.5196 -108.0008)
			)
		)
		(polygon
			(pts
				(xy 169.5196 -107.2642) (xy 169.3164 -107.2642) (xy 169.3164 -107.4674) (xy 169.5196 -107.4674)
			)
		)
		(polygon
			(pts
				(xy 169.5196 -106.6546) (xy 169.3164 -106.6546) (xy 169.3164 -106.8578) (xy 169.5196 -106.8578)
			)
		)
		(polygon
			(pts
				(xy 169.5196 -106.2482) (xy 169.3164 -106.2482) (xy 169.3164 -106.4514) (xy 169.5196 -106.4514)
			)
		)
		(polygon
			(pts
				(xy 169.5196 -105.6386) (xy 169.3164 -105.6386) (xy 169.3164 -105.8418) (xy 169.5196 -105.8418)
			)
		)
		(polygon
			(pts
				(xy 169.5196 -105.2322) (xy 169.3164 -105.2322) (xy 169.3164 -105.4354) (xy 169.5196 -105.4354)
			)
		)
	)
	(zone
		(layer "B.Cu")
		(hatch none 0.5)
		(connect_pads
			(clearance 0)
		)
		(min_thickness 0.25)
		(keepout
			(tracks not_allowed)
			(vias allowed)
			(pads allowed)
			(copperpour not_allowed)
			(footprints allowed)
		)
		(placement
			(enabled no)
			(sheetname "")
		)
		(fill
			(thermal_gap 0.5)
			(thermal_bridge_width 0.5)
			(island_removal_mode 0)
		)
		(polygon
			(pts
				(arc
					(start 77.667358 -86.510368)
					(mid 77.283818 -86.126828)
					(end 76.900278 -86.510368)
				)
				(arc
					(start 76.900278 -87.399114)
					(mid 77.283691 -87.782908)
					(end 77.667358 -87.399368)
				)
				(xy 77.667358 -87.196168) (xy 77.577442 -87.196168)
				(arc
					(start 77.57287 -87.196168)
					(mid 77.525045 -87.201938)
					(end 77.479906 -87.218774)
				)
				(arc
					(start 77.479906 -87.218774)
					(mid 77.165161 -87.637972)
					(end 77.308202 -87.133684)
				)
				(arc
					(start 77.308202 -87.133684)
					(mid 77.41259 -87.060329)
					(end 77.535532 -87.026242)
				)
				(xy 77.53731 -87.024464) (xy 77.563218 -87.024464) (xy 77.57287 -87.024464) (xy 77.577442 -87.024464)
				(xy 77.667358 -87.024464) (xy 77.667358 -86.884764) (xy 77.577188 -86.884764) (xy 77.572616 -86.885018)
				(xy 77.562964 -86.884764) (xy 77.537056 -86.884764)
				(arc
					(start 77.535278 -86.88324)
					(mid 77.412607 -86.849226)
					(end 77.308456 -86.776052)
				)
				(arc
					(start 77.308456 -86.776052)
					(mid 77.165407 -86.271257)
					(end 77.48016 -86.690962)
				)
				(arc
					(start 77.48016 -86.690962)
					(mid 77.525063 -86.707602)
					(end 77.572616 -86.713314)
				)
				(xy 77.577188 -86.713568) (xy 77.667358 -86.713568)
			)
		)
	)
	(zone
		(layer "B.Cu")
		(hatch none 0.5)
		(connect_pads
			(clearance 0)
		)
		(min_thickness 0.25)
		(keepout
			(tracks allowed)
			(vias allowed)
			(pads allowed)
			(copperpour allowed)
			(footprints not_allowed)
		)
		(placement
			(enabled no)
			(sheetname "")
		)
		(fill
			(thermal_gap 0.5)
			(thermal_bridge_width 0.5)
			(island_removal_mode 0)
		)
		(polygon
			(pts
				(arc
					(start 18.150078 -105.050082)
					(mid 22.900132 -109.800136)
					(end 27.649932 -105.050082)
				)
				(arc
					(start 27.649932 -105.050082)
					(mid 22.900132 -100.300282)
					(end 18.150078 -105.050082)
				)
			)
		)
	)
	(zone
		(layer "B.Cu")
		(hatch none 0.5)
		(connect_pads
			(clearance 0)
		)
		(min_thickness 0.25)
		(keepout
			(tracks allowed)
			(vias allowed)
			(pads allowed)
			(copperpour allowed)
			(footprints allowed)
		)
		(placement
			(enabled no)
			(sheetname "")
		)
		(fill
			(thermal_gap 0.5)
			(thermal_bridge_width 0.5)
			(island_removal_mode 0)
		)
		(polygon
			(pts
				(xy 63.0174 -145.161) (xy 63.0174 -144.0688) (xy 64.389 -144.0688) (xy 64.389 -145.161)
			)
		)
	)
	(zone
		(net "GND")
		(layer "B.Cu")
		(hatch none 0.5)
		(connect_pads
			(clearance 0.5)
		)
		(min_thickness 0.25)
		(fill yes
			(thermal_gap 0.5)
			(thermal_bridge_width 0.5)
			(island_removal_mode 0)
		)
		(polygon
			(pts
				(xy 158.46044 -135.821674) (xy 158.46044 -137.50163) (xy 160.135824 -137.50163) (xy 160.135824 -135.821674)
			)
		)
	)
	(zone
		(net "P3V3_STBY")
		(layer "B.Cu")
		(hatch none 0.5)
		(connect_pads
			(clearance 0.5)
		)
		(min_thickness 0.25)
		(fill yes
			(thermal_gap 0.5)
			(thermal_bridge_width 0.5)
			(island_removal_mode 0)
		)
		(polygon
			(pts
				(xy 29.3624 -151.0538) (xy 29.2989 -151.1173) (xy 29.2989 -152.0063) (xy 30.0736 -152.781) (xy 30.0736 -154.2796)
				(xy 30.1752 -154.3812) (xy 31.4706 -154.3812) (xy 31.623 -154.2288) (xy 31.623 -154.05608) (xy 32.05988 -153.6192)
				(xy 32.385 -153.6192) (xy 32.53994 -153.46426) (xy 32.53994 -152.66797) (xy 32.029908 -152.158192)
				(xy 32.029908 -151.257508) (xy 31.8262 -151.0538)
			)
		)
		(polygon
			(pts
				(xy 32.103568 -153.302716) (xy 31.900368 -153.302716) (xy 31.900368 -153.505916) (xy 32.103568 -153.505916)
			)
		)
		(polygon
			(pts
				(xy 32.103568 -152.743916) (xy 31.900368 -152.743916) (xy 31.900368 -152.947116) (xy 32.103568 -152.947116)
			)
		)
	)
	(zone
		(layer "B.Cu")
		(hatch none 0.5)
		(connect_pads
			(clearance 0)
		)
		(min_thickness 0.25)
		(keepout
			(tracks not_allowed)
			(vias allowed)
			(pads allowed)
			(copperpour not_allowed)
			(footprints allowed)
		)
		(placement
			(enabled no)
			(sheetname "")
		)
		(fill
			(thermal_gap 0.5)
			(thermal_bridge_width 0.5)
			(island_removal_mode 0)
		)
		(polygon
			(pts
				(arc
					(start 107.585002 -33.20034)
					(mid 107.099989 -32.714946)
					(end 106.614722 -33.200086)
				)
				(xy 106.614722 -33.658556) (xy 106.93781 -33.658556)
				(arc
					(start 106.942382 -33.658556)
					(mid 106.969876 -33.653069)
					(end 106.993182 -33.637474)
				)
				(arc
					(start 106.993182 -33.637474)
					(mid 107.0086 -33.6144)
					(end 107.01401 -33.587182)
				)
				(arc
					(start 107.01401 -33.584388)
					(mid 107.099862 -32.806311)
					(end 107.185714 -33.584388)
				)
				(xy 107.185714 -33.587182) (xy 107.18546 -33.595056) (xy 107.18546 -33.622742)
				(arc
					(start 107.182666 -33.625536)
					(mid 107.159163 -33.697588)
					(end 107.114594 -33.758886)
				)
				(arc
					(start 107.114594 -33.758886)
					(mid 107.053078 -33.80366)
					(end 106.980736 -33.827212)
				)
				(xy 106.977942 -33.83026) (xy 106.950256 -33.83026) (xy 106.942382 -33.83026) (xy 106.93781 -33.83026)
				(xy 106.614722 -33.83026) (xy 106.614722 -33.96996) (xy 106.90733 -33.96996) (xy 106.911648 -33.969706)
				(xy 106.919776 -33.96996) (xy 106.947462 -33.96996)
				(arc
					(start 106.95051 -33.973008)
					(mid 107.001038 -33.987454)
					(end 107.04703 -34.012886)
				)
				(xy 107.051602 -34.012886) (xy 107.071668 -34.033206) (xy 107.07624 -34.037778) (xy 107.079796 -34.041588)
				(xy 107.093766 -34.055812) (xy 107.096814 -34.058606) (xy 107.104434 -34.06648) (xy 107.12196 -34.08426)
				(arc
					(start 107.12196 -34.087054)
					(mid 107.158515 -34.1474)
					(end 107.180126 -34.214562)
				)
				(arc
					(start 107.180126 -34.214562)
					(mid 107.109235 -34.993814)
					(end 107.002326 -34.218626)
				)
				(arc
					(start 107.002326 -34.218626)
					(mid 106.990603 -34.19811)
					(end 106.975402 -34.180018)
				)
				(xy 106.971846 -34.176208) (xy 106.957876 -34.161984)
				(arc
					(start 106.954828 -34.15919)
					(mid 106.935264 -34.146054)
					(end 106.912156 -34.14141)
				)
				(xy 106.90733 -34.141156) (xy 106.614722 -34.141156)
				(arc
					(start 106.614722 -34.600134)
					(mid 107.099862 -35.085274)
					(end 107.585002 -34.600134)
				)
			)
		)
	)
	(zone
		(layer "B.Cu")
		(hatch none 0.5)
		(connect_pads
			(clearance 0)
		)
		(min_thickness 0.25)
		(keepout
			(tracks allowed)
			(vias allowed)
			(pads allowed)
			(copperpour allowed)
			(footprints allowed)
		)
		(placement
			(enabled no)
			(sheetname "")
		)
		(fill
			(thermal_gap 0.5)
			(thermal_bridge_width 0.5)
			(island_removal_mode 0)
		)
		(polygon
			(pts
				(xy 90.1192 -167.4114) (xy 90.1192 -168.0718) (xy 88.0618 -168.0718) (xy 88.0618 -167.4114)
			)
		)
	)
	(zone
		(layer "B.Cu")
		(hatch none 0.5)
		(connect_pads
			(clearance 0)
		)
		(min_thickness 0.25)
		(keepout
			(tracks allowed)
			(vias allowed)
			(pads allowed)
			(copperpour allowed)
			(footprints allowed)
		)
		(placement
			(enabled no)
			(sheetname "")
		)
		(fill
			(thermal_gap 0.5)
			(thermal_bridge_width 0.5)
			(island_removal_mode 0)
		)
		(polygon
			(pts
				(xy 79.117698 -137.482834) (xy 80.922114 -137.482834) (xy 80.95869 -137.446258) (xy 80.95869 -137.05713)
				(xy 80.934306 -137.032746) (xy 79.121762 -137.032746) (xy 79.040736 -137.113772) (xy 79.040736 -137.405872)
			)
		)
	)
	(zone
		(net "P5V_STBY")
		(layer "B.Cu")
		(hatch none 0.5)
		(connect_pads
			(clearance 0.5)
		)
		(min_thickness 0.25)
		(fill yes
			(thermal_gap 0.5)
			(thermal_bridge_width 0.5)
			(island_removal_mode 0)
		)
		(polygon
			(pts
				(xy 146.221958 -92.300298) (xy 145.705068 -92.817188) (xy 145.705068 -96.925892) (xy 147.144486 -98.36531)
				(xy 147.144486 -136.587738) (xy 156.754576 -146.197828) (xy 156.754576 -153.376376) (xy 169.0878 -165.7096)
				(xy 169.0878 -179.6542) (xy 169.4688 -180.0352) (xy 174.0916 -180.0352) (xy 174.879 -179.2478) (xy 174.879 -163.195)
				(xy 164.465 -152.781) (xy 164.465 -147.200112) (xy 150.074376 -132.809488) (xy 150.074376 -93.25991)
				(xy 149.114764 -92.300298)
			)
		)
	)
	(zone
		(layer "B.Cu")
		(hatch none 0.5)
		(connect_pads
			(clearance 0)
		)
		(min_thickness 0.25)
		(keepout
			(tracks not_allowed)
			(vias allowed)
			(pads allowed)
			(copperpour not_allowed)
			(footprints allowed)
		)
		(placement
			(enabled no)
			(sheetname "")
		)
		(fill
			(thermal_gap 0.5)
			(thermal_bridge_width 0.5)
			(island_removal_mode 0)
		)
		(polygon
			(pts
				(arc
					(start 192.841118 -81.0641)
					(mid 192.81272 -81.057396)
					(end 192.790318 -81.0387)
				)
				(arc
					(start 192.790318 -81.2673)
					(mid 192.81272 -81.248604)
					(end 192.841118 -81.2419)
				)
				(arc
					(start 193.044318 -81.2419)
					(mid 193.072716 -81.248604)
					(end 193.095118 -81.2673)
				)
				(arc
					(start 193.095118 -81.0387)
					(mid 193.072716 -81.057396)
					(end 193.044318 -81.0641)
				)
			)
		)
	)
	(zone
		(net "GND")
		(layer "B.Cu")
		(hatch none 0.5)
		(connect_pads
			(clearance 0.5)
		)
		(min_thickness 0.25)
		(fill yes
			(thermal_gap 0.5)
			(thermal_bridge_width 0.5)
			(island_removal_mode 0)
		)
		(polygon
			(pts
				(xy 81.051908 -54.496716) (xy 80.107028 -55.441596) (xy 80.107028 -55.850536) (xy 80.124808 -55.868316)
				(xy 80.124808 -61.336936) (xy 80.564228 -61.776356) (xy 83.764628 -61.776356) (xy 84.079588 -61.461396)
				(xy 84.079588 -60.295536) (xy 83.972908 -60.188856) (xy 83.426808 -60.188856) (xy 83.421728 -60.193936)
				(xy 82.494628 -60.193936) (xy 82.113628 -59.812936) (xy 82.113628 -56.228996) (xy 82.455258 -55.887366)
				(xy 83.829398 -55.887366) (xy 83.906868 -55.809896) (xy 83.906868 -54.758336) (xy 83.645248 -54.496716)
			)
		)
	)
	(zone
		(layer "B.Cu")
		(hatch none 0.5)
		(connect_pads
			(clearance 0)
		)
		(min_thickness 0.25)
		(keepout
			(tracks not_allowed)
			(vias allowed)
			(pads allowed)
			(copperpour not_allowed)
			(footprints allowed)
		)
		(placement
			(enabled no)
			(sheetname "")
		)
		(fill
			(thermal_gap 0.5)
			(thermal_bridge_width 0.5)
			(island_removal_mode 0)
		)
		(polygon
			(pts
				(arc
					(start 83.250024 -40.049958)
					(mid 78.49997 -35.299904)
					(end 73.749916 -40.049958)
				)
				(arc
					(start 73.749916 -40.049958)
					(mid 78.49997 -44.800012)
					(end 83.250024 -40.049958)
				)
			)
		)
	)
	(zone
		(layer "B.Cu")
		(hatch none 0.5)
		(connect_pads
			(clearance 0)
		)
		(min_thickness 0.25)
		(keepout
			(tracks not_allowed)
			(vias allowed)
			(pads allowed)
			(copperpour not_allowed)
			(footprints allowed)
		)
		(placement
			(enabled no)
			(sheetname "")
		)
		(fill
			(thermal_gap 0.5)
			(thermal_bridge_width 0.5)
			(island_removal_mode 0)
		)
		(polygon
			(pts
				(xy 117.414802 -33.83026) (xy 117.414802 -33.96869) (xy 117.446044 -33.969706) (xy 117.450616 -33.96996)
				(xy 117.72392 -33.96996) (xy 117.728492 -33.969706) (xy 117.73662 -33.96996) (xy 117.764052 -33.96996)
				(arc
					(start 117.766846 -33.9725)
					(mid 117.844576 -33.997264)
					(end 117.91061 -34.045144)
				)
				(arc
					(start 117.91061 -34.045144)
					(mid 117.958261 -34.110979)
					(end 117.983 -34.1884)
				)
				(xy 117.98554 -34.191194)
				(arc
					(start 117.98554 -34.215832)
					(mid 117.900465 -34.993853)
					(end 117.813328 -34.216086)
				)
				(arc
					(start 117.813328 -34.216086)
					(mid 117.805348 -34.189337)
					(end 117.789198 -34.166556)
				)
				(arc
					(start 117.789198 -34.166556)
					(mid 117.761346 -34.147946)
					(end 117.728492 -34.14141)
				)
				(xy 117.72392 -34.141156) (xy 117.450616 -34.141156) (xy 117.446044 -34.14141) (xy 117.432836 -34.141156)
				(xy 117.414802 -34.141156)
				(arc
					(start 117.414802 -34.600134)
					(mid 117.899942 -35.085274)
					(end 118.385082 -34.600134)
				)
				(arc
					(start 118.385082 -33.20034)
					(mid 117.900069 -32.714946)
					(end 117.414802 -33.200086)
				)
				(arc
					(start 117.414802 -33.65627)
					(mid 117.430379 -33.658009)
					(end 117.446044 -33.658556)
				)
				(xy 117.450616 -33.658556) (xy 117.669564 -33.658556)
				(arc
					(start 117.674136 -33.658556)
					(mid 117.727597 -33.647922)
					(end 117.772942 -33.617662)
				)
				(arc
					(start 117.772942 -33.617662)
					(mid 117.78764 -33.600317)
					(end 117.799358 -33.580832)
				)
				(arc
					(start 117.799358 -33.580832)
					(mid 117.910777 -32.806499)
					(end 117.978428 -33.585912)
				)
				(arc
					(start 117.978428 -33.585912)
					(mid 117.947343 -33.668508)
					(end 117.894354 -33.739074)
				)
				(arc
					(start 117.894354 -33.739074)
					(mid 117.810498 -33.798851)
					(end 117.711728 -33.827974)
				)
				(xy 117.709696 -33.83026) (xy 117.683026 -33.83026) (xy 117.674136 -33.83026) (xy 117.669564 -33.83026)
				(xy 117.450616 -33.83026) (xy 117.446044 -33.83026) (xy 117.436392 -33.83026)
			)
		)
	)
	(zone
		(layer "B.Cu")
		(hatch none 0.5)
		(connect_pads
			(clearance 0)
		)
		(min_thickness 0.25)
		(keepout
			(tracks not_allowed)
			(vias allowed)
			(pads allowed)
			(copperpour not_allowed)
			(footprints allowed)
		)
		(placement
			(enabled no)
			(sheetname "")
		)
		(fill
			(thermal_gap 0.5)
			(thermal_bridge_width 0.5)
			(island_removal_mode 0)
		)
		(polygon
			(pts
				(arc
					(start 126.664974 -34.854896)
					(mid 124.165106 -32.355028)
					(end 121.664984 -34.854896)
				)
				(arc
					(start 121.664984 -34.854896)
					(mid 124.165106 -37.355018)
					(end 126.664974 -34.854896)
				)
			)
		)
	)
	(zone
		(layer "B.Cu")
		(hatch none 0.5)
		(connect_pads
			(clearance 0)
		)
		(min_thickness 0.25)
		(keepout
			(tracks not_allowed)
			(vias allowed)
			(pads allowed)
			(copperpour not_allowed)
			(footprints allowed)
		)
		(placement
			(enabled no)
			(sheetname "")
		)
		(fill
			(thermal_gap 0.5)
			(thermal_bridge_width 0.5)
			(island_removal_mode 0)
		)
		(polygon
			(pts
				(arc
					(start 188.446918 -81.0641)
					(mid 188.41852 -81.057396)
					(end 188.396118 -81.0387)
				)
				(arc
					(start 188.396118 -81.2673)
					(mid 188.41852 -81.248604)
					(end 188.446918 -81.2419)
				)
				(arc
					(start 188.650118 -81.2419)
					(mid 188.678516 -81.248604)
					(end 188.700918 -81.2673)
				)
				(arc
					(start 188.700918 -81.0387)
					(mid 188.678516 -81.057396)
					(end 188.650118 -81.0641)
				)
			)
		)
	)
	(zone
		(layer "B.Cu")
		(hatch none 0.5)
		(connect_pads
			(clearance 0)
		)
		(min_thickness 0.25)
		(keepout
			(tracks not_allowed)
			(vias allowed)
			(pads allowed)
			(copperpour not_allowed)
			(footprints allowed)
		)
		(placement
			(enabled no)
			(sheetname "")
		)
		(fill
			(thermal_gap 0.5)
			(thermal_bridge_width 0.5)
			(island_removal_mode 0)
		)
		(polygon
			(pts
				(arc
					(start 199.699118 -81.0641)
					(mid 199.67072 -81.057396)
					(end 199.648318 -81.0387)
				)
				(arc
					(start 199.648318 -81.2673)
					(mid 199.67072 -81.248604)
					(end 199.699118 -81.2419)
				)
				(arc
					(start 199.902318 -81.2419)
					(mid 199.930716 -81.248604)
					(end 199.953118 -81.2673)
				)
				(arc
					(start 199.953118 -81.0387)
					(mid 199.930716 -81.057396)
					(end 199.902318 -81.0641)
				)
			)
		)
	)
	(zone
		(net "SHELL_PLL_VDD")
		(layer "B.Cu")
		(hatch none 0.5)
		(connect_pads
			(clearance 0.5)
		)
		(min_thickness 0.25)
		(fill yes
			(thermal_gap 0.5)
			(thermal_bridge_width 0.5)
			(island_removal_mode 0)
		)
		(polygon
			(pts
				(xy 204.965554 -45.981874) (xy 204.9272 -46.020228) (xy 204.9272 -46.755304) (xy 205.069694 -46.897798)
				(xy 205.069694 -51.841654) (xy 204.862684 -52.048664) (xy 204.862684 -53.07965) (xy 204.900784 -53.11775)
				(xy 205.326488 -53.11775) (xy 205.365096 -53.079142) (xy 206.808832 -53.079142) (xy 207.020922 -52.867052)
				(xy 207.020922 -47.542196) (xy 207.019144 -47.540418) (xy 207.019144 -47.21098) (xy 206.545434 -46.73727)
				(xy 206.215996 -46.73727) (xy 205.4606 -45.981874)
			)
		)
		(polygon
			(pts
				(xy 205.363064 -52.41163) (xy 205.159864 -52.41163) (xy 205.159864 -52.61483) (xy 205.144624 -52.644802)
				(xy 205.144624 -52.848002) (xy 205.347824 -52.848002) (xy 205.347824 -52.644802) (xy 205.363064 -52.61483)
			)
		)
		(polygon
			(pts
				(xy 205.363064 -52.05603) (xy 205.159864 -52.05603) (xy 205.159864 -52.25923) (xy 205.363064 -52.25923)
			)
		)
		(polygon
			(pts
				(xy 206.060548 -51.760882) (xy 205.857348 -51.760882) (xy 205.857348 -51.964082) (xy 206.060548 -51.964082)
			)
		)
		(polygon
			(pts
				(xy 206.060548 -50.897282) (xy 205.857348 -50.897282) (xy 205.857348 -51.100482) (xy 206.060548 -51.100482)
			)
		)
		(polygon
			(pts
				(xy 205.585568 -46.458886) (xy 205.382368 -46.458886) (xy 205.382368 -46.662086) (xy 205.585568 -46.662086)
			)
		)
	)
	(zone
		(layer "B.Cu")
		(hatch none 0.5)
		(connect_pads
			(clearance 0)
		)
		(min_thickness 0.25)
		(keepout
			(tracks not_allowed)
			(vias allowed)
			(pads allowed)
			(copperpour not_allowed)
			(footprints allowed)
		)
		(placement
			(enabled no)
			(sheetname "")
		)
		(fill
			(thermal_gap 0.5)
			(thermal_bridge_width 0.5)
			(island_removal_mode 0)
		)
		(polygon
			(pts
				(arc
					(start 198.987918 -81.0641)
					(mid 198.95952 -81.057396)
					(end 198.937118 -81.0387)
				)
				(arc
					(start 198.937118 -81.2673)
					(mid 198.95952 -81.248604)
					(end 198.987918 -81.2419)
				)
				(arc
					(start 199.191118 -81.2419)
					(mid 199.219516 -81.248604)
					(end 199.241918 -81.2673)
				)
				(arc
					(start 199.241918 -81.0387)
					(mid 199.219516 -81.057396)
					(end 199.191118 -81.0641)
				)
			)
		)
	)
	(zone
		(layer "B.Cu")
		(hatch none 0.5)
		(connect_pads
			(clearance 0)
		)
		(min_thickness 0.25)
		(keepout
			(tracks allowed)
			(vias allowed)
			(pads allowed)
			(copperpour allowed)
			(footprints not_allowed)
		)
		(placement
			(enabled no)
			(sheetname "")
		)
		(fill
			(thermal_gap 0.5)
			(thermal_bridge_width 0.5)
			(island_removal_mode 0)
		)
		(polygon
			(pts
				(arc
					(start 45.200062 -169.999914)
					(mid 41.450006 -166.249858)
					(end 37.69995 -169.999914)
				)
				(arc
					(start 37.69995 -169.999914)
					(mid 41.450006 -173.74997)
					(end 45.200062 -169.999914)
				)
			)
		)
	)
	(zone
		(layer "B.Cu")
		(hatch none 0.5)
		(connect_pads
			(clearance 0)
		)
		(min_thickness 0.25)
		(keepout
			(tracks allowed)
			(vias allowed)
			(pads allowed)
			(copperpour allowed)
			(footprints not_allowed)
		)
		(placement
			(enabled no)
			(sheetname "")
		)
		(fill
			(thermal_gap 0.5)
			(thermal_bridge_width 0.5)
			(island_removal_mode 0)
		)
		(polygon
			(pts
				(arc
					(start 27.55011 -60.550044)
					(mid 22.800056 -55.79999)
					(end 18.050002 -60.550044)
				)
				(arc
					(start 18.050002 -60.550044)
					(mid 22.800056 -65.300098)
					(end 27.55011 -60.550044)
				)
			)
		)
	)
	(zone
		(layer "B.Cu")
		(hatch none 0.5)
		(connect_pads
			(clearance 0)
		)
		(min_thickness 0.25)
		(keepout
			(tracks not_allowed)
			(vias allowed)
			(pads allowed)
			(copperpour not_allowed)
			(footprints allowed)
		)
		(placement
			(enabled no)
			(sheetname "")
		)
		(fill
			(thermal_gap 0.5)
			(thermal_bridge_width 0.5)
			(island_removal_mode 0)
		)
		(polygon
			(pts
				(arc
					(start 222.79991 -84.479892)
					(mid 219.799916 -81.479898)
					(end 216.799922 -84.479892)
				)
				(arc
					(start 216.799922 -84.479892)
					(mid 219.799916 -87.479886)
					(end 222.79991 -84.479892)
				)
			)
		)
	)
	(zone
		(layer "B.Cu")
		(hatch none 0.5)
		(connect_pads
			(clearance 0)
		)
		(min_thickness 0.25)
		(keepout
			(tracks allowed)
			(vias allowed)
			(pads allowed)
			(copperpour allowed)
			(footprints not_allowed)
		)
		(placement
			(enabled no)
			(sheetname "")
		)
		(fill
			(thermal_gap 0.5)
			(thermal_bridge_width 0.5)
			(island_removal_mode 0)
		)
		(polygon
			(pts
				(arc
					(start 160.250124 -110.000034)
					(mid 155.50007 -105.24998)
					(end 150.750016 -110.000034)
				)
				(arc
					(start 150.750016 -110.000034)
					(mid 155.50007 -114.750088)
					(end 160.250124 -110.000034)
				)
			)
		)
	)
	(zone
		(net "GND")
		(layer "B.Cu")
		(hatch none 0.5)
		(connect_pads
			(clearance 0.5)
		)
		(min_thickness 0.25)
		(fill yes
			(thermal_gap 0.5)
			(thermal_bridge_width 0.5)
			(island_removal_mode 0)
		)
		(polygon
			(pts
				(xy 91.0082 -152.9334) (xy 89.7636 -154.178) (xy 89.7636 -156.199332) (xy 91.076018 -157.51175)
				(xy 91.374468 -157.51175) (xy 91.571318 -157.7086) (xy 91.571318 -157.732984) (xy 92.303854 -158.46552)
				(xy 93.560646 -158.46552) (xy 93.630242 -158.395924) (xy 93.630242 -158.391352) (xy 95.471488 -158.391352)
				(xy 95.9358 -157.92704) (xy 95.9358 -152.9334)
			)
		)
		(polygon
			(pts
				(xy 95.254064 -157.785562) (xy 95.050864 -157.785562) (xy 95.050864 -157.988762) (xy 95.254064 -157.988762)
			)
		)
		(polygon
			(pts
				(xy 93.703902 -157.761178) (xy 93.500702 -157.761178) (xy 93.500702 -157.964378) (xy 93.703902 -157.964378)
			)
		)
		(polygon
			(pts
				(xy 92.992702 -157.761178) (xy 92.789502 -157.761178) (xy 92.789502 -157.964378) (xy 92.992702 -157.964378)
			)
		)
		(polygon
			(pts
				(xy 95.254064 -157.226762) (xy 95.050864 -157.226762) (xy 95.050864 -157.429962) (xy 95.254064 -157.429962)
			)
		)
		(polygon
			(pts
				(xy 90.5256 -155.8544) (xy 90.3224 -155.8544) (xy 90.3224 -156.0576) (xy 90.5256 -156.0576)
			)
		)
		(polygon
			(pts
				(xy 90.5256 -155.1432) (xy 90.3224 -155.1432) (xy 90.3224 -155.3464) (xy 90.5256 -155.3464)
			)
		)
		(polygon
			(pts
				(xy 95.0722 -153.797) (xy 94.869 -153.797) (xy 94.869 -154.0002) (xy 95.0722 -154.0002)
			)
		)
		(polygon
			(pts
				(xy 92.3544 -153.4922) (xy 92.1512 -153.4922) (xy 92.1512 -153.6954) (xy 92.3544 -153.6954)
			)
		)
		(polygon
			(pts
				(xy 91.6432 -153.4922) (xy 91.44 -153.4922) (xy 91.44 -153.6954) (xy 91.6432 -153.6954)
			)
		)
		(polygon
			(pts
				(xy 93.83268 -153.406856) (xy 93.62948 -153.406856) (xy 93.62948 -153.610056) (xy 93.83268 -153.610056)
			)
		)
		(polygon
			(pts
				(xy 93.12148 -153.406856) (xy 92.91828 -153.406856) (xy 92.91828 -153.610056) (xy 93.12148 -153.610056)
			)
		)
	)
	(zone
		(net "GND")
		(layer "B.Cu")
		(hatch none 0.5)
		(connect_pads
			(clearance 0.5)
		)
		(min_thickness 0.25)
		(fill yes
			(thermal_gap 0.5)
			(thermal_bridge_width 0.5)
			(island_removal_mode 0)
		)
		(polygon
			(pts
				(xy 51.6128 -130.0734) (xy 51.4096 -130.2766) (xy 51.4096 -130.9116) (xy 51.2572 -131.064) (xy 49.227994 -131.064)
				(xy 49.022 -131.269994) (xy 49.022 -132.3086) (xy 49.149 -132.4356) (xy 56.5404 -132.4356) (xy 56.896 -132.08)
				(xy 56.896 -130.429) (xy 56.5404 -130.0734)
			)
		)
		(polygon
			(pts
				(xy 54.9148 -131.4196) (xy 54.7116 -131.4196) (xy 54.7116 -131.6228) (xy 54.9148 -131.6228)
			)
		)
		(polygon
			(pts
				(xy 54.0512 -131.4196) (xy 53.848 -131.4196) (xy 53.848 -131.6228) (xy 54.0512 -131.6228)
			)
		)
		(polygon
			(pts
				(xy 50.165 -131.4196) (xy 49.9618 -131.4196) (xy 49.9618 -131.6228) (xy 50.165 -131.6228)
			)
		)
		(polygon
			(pts
				(xy 53.73243 -131.406646) (xy 53.52923 -131.406646) (xy 53.52923 -131.609846) (xy 53.73243 -131.609846)
			)
		)
		(polygon
			(pts
				(xy 52.86883 -131.406646) (xy 52.66563 -131.406646) (xy 52.66563 -131.609846) (xy 52.86883 -131.609846)
			)
		)
		(polygon
			(pts
				(xy 52.5272 -131.3942) (xy 52.324 -131.3942) (xy 52.324 -131.5974) (xy 52.5272 -131.5974)
			)
		)
		(polygon
			(pts
				(xy 51.6636 -131.3942) (xy 51.4604 -131.3942) (xy 51.4604 -131.5974) (xy 51.6636 -131.5974)
			)
		)
		(polygon
			(pts
				(xy 51.34737 -131.381754) (xy 51.14417 -131.381754) (xy 51.14417 -131.584954) (xy 51.34737 -131.584954)
			)
		)
		(polygon
			(pts
				(xy 50.48377 -131.381754) (xy 50.28057 -131.381754) (xy 50.28057 -131.584954) (xy 50.48377 -131.584954)
			)
		)
	)
	(zone
		(layer "B.Cu")
		(hatch none 0.5)
		(connect_pads
			(clearance 0)
		)
		(min_thickness 0.25)
		(keepout
			(tracks not_allowed)
			(vias allowed)
			(pads allowed)
			(copperpour not_allowed)
			(footprints allowed)
		)
		(placement
			(enabled no)
			(sheetname "")
		)
		(fill
			(thermal_gap 0.5)
			(thermal_bridge_width 0.5)
			(island_removal_mode 0)
		)
		(polygon
			(pts
				(arc
					(start 192.129918 -81.0641)
					(mid 192.10152 -81.057396)
					(end 192.079118 -81.0387)
				)
				(arc
					(start 192.079118 -81.2673)
					(mid 192.10152 -81.248604)
					(end 192.129918 -81.2419)
				)
				(arc
					(start 192.333118 -81.2419)
					(mid 192.361516 -81.248604)
					(end 192.383918 -81.2673)
				)
				(arc
					(start 192.383918 -81.0387)
					(mid 192.361516 -81.057396)
					(end 192.333118 -81.0641)
				)
			)
		)
	)
	(zone
		(layer "B.Cu")
		(hatch none 0.5)
		(connect_pads
			(clearance 0)
		)
		(min_thickness 0.25)
		(keepout
			(tracks not_allowed)
			(vias allowed)
			(pads allowed)
			(copperpour not_allowed)
			(footprints allowed)
		)
		(placement
			(enabled no)
			(sheetname "")
		)
		(fill
			(thermal_gap 0.5)
			(thermal_bridge_width 0.5)
			(island_removal_mode 0)
		)
		(polygon
			(pts
				(arc
					(start 191.575436 -25.7556)
					(mid 191.594132 -25.778002)
					(end 191.600836 -25.8064)
				)
				(arc
					(start 191.600836 -26.0096)
					(mid 191.594132 -26.037998)
					(end 191.575436 -26.0604)
				)
				(arc
					(start 191.804036 -26.0604)
					(mid 191.78534 -26.037998)
					(end 191.778636 -26.0096)
				)
				(arc
					(start 191.778636 -25.8064)
					(mid 191.78534 -25.778002)
					(end 191.804036 -25.7556)
				)
			)
		)
	)
	(zone
		(net "P3V3")
		(layer "B.Cu")
		(hatch none 0.5)
		(connect_pads
			(clearance 0.5)
		)
		(min_thickness 0.25)
		(fill yes
			(thermal_gap 0.5)
			(thermal_bridge_width 0.5)
			(island_removal_mode 0)
		)
		(polygon
			(pts
				(xy 84.882228 -51.987196) (xy 84.012278 -52.857146) (xy 79.299054 -52.857146) (xy 78.1812 -53.975)
				(xy 78.1812 -54.5592) (xy 77.851 -54.8894) (xy 77.34935 -54.8894) (xy 77.06995 -55.1688) (xy 77.06995 -56.874156)
				(xy 77.38491 -57.189116) (xy 77.937868 -57.189116) (xy 78.266798 -57.518046) (xy 78.266798 -58.716926)
				(xy 78.428088 -58.878216) (xy 79.433928 -58.878216) (xy 79.653638 -58.658506) (xy 79.653638 -55.386986)
				(xy 80.869028 -54.171596) (xy 84.615528 -54.171596) (xy 85.796628 -52.990496) (xy 85.796628 -52.203096)
				(xy 85.580728 -51.987196)
			)
		)
	)
	(zone
		(net "P0V975")
		(layer "B.Cu")
		(hatch none 0.5)
		(connect_pads
			(clearance 0.5)
		)
		(min_thickness 0.25)
		(fill yes
			(thermal_gap 0.5)
			(thermal_bridge_width 0.5)
			(island_removal_mode 0)
		)
		(polygon
			(pts
				(xy 194.9958 -56.8452) (xy 194.8307 -57.0103) (xy 194.8307 -59.944) (xy 195.6435 -60.7568) (xy 195.6435 -62.0776)
				(xy 195.3387 -62.3824) (xy 195.0339 -62.3824) (xy 194.8307 -62.5856) (xy 194.8307 -65.9638) (xy 194.9958 -66.1289)
				(xy 194.9958 -67.2973) (xy 194.8942 -67.3989) (xy 194.8942 -69.1896) (xy 195.0466 -69.342) (xy 196.3674 -69.342)
				(xy 196.44995 -69.25945) (xy 196.44995 -67.96405) (xy 196.42455 -67.93865) (xy 195.82765 -67.93865)
				(xy 195.6181 -67.7291) (xy 195.6181 -67.3354) (xy 195.7959 -67.1576) (xy 195.7959 -66.294) (xy 195.4784 -65.9765)
				(xy 195.4784 -64.5414) (xy 195.56095 -64.45885) (xy 195.56095 -63.02375) (xy 195.6562 -62.9285)
				(xy 196.2531 -62.9285) (xy 196.4563 -63.1317) (xy 196.4563 -64.9478) (xy 196.5452 -65.0367) (xy 196.8754 -65.0367)
				(xy 196.9897 -64.9224) (xy 196.9897 -64.5541) (xy 197.1802 -64.3636) (xy 197.1802 -60.5536) (xy 196.41185 -59.78525)
				(xy 196.41185 -57.04205) (xy 196.215 -56.8452)
			)
		)
		(polygon
			(pts
				(xy 195.1482 -65.4431) (xy 194.945 -65.4431) (xy 194.945 -65.6463) (xy 195.1482 -65.6463)
			)
		)
		(polygon
			(pts
				(xy 195.1482 -64.8843) (xy 194.945 -64.8843) (xy 194.945 -65.2907) (xy 195.1482 -65.2907)
			)
		)
		(polygon
			(pts
				(xy 195.1482 -64.5287) (xy 194.945 -64.5287) (xy 194.945 -64.7319) (xy 195.1482 -64.7319)
			)
		)
		(polygon
			(pts
				(xy 195.2117 -63.86576) (xy 195.0085 -63.86576) (xy 195.0085 -64.06896) (xy 195.2117 -64.06896)
			)
		)
		(polygon
			(pts
				(xy 195.2117 -63.30696) (xy 195.0085 -63.30696) (xy 195.0085 -63.71336) (xy 195.2117 -63.71336)
			)
		)
		(polygon
			(pts
				(xy 195.2117 -62.95136) (xy 195.0085 -62.95136) (xy 195.0085 -63.15456) (xy 195.2117 -63.15456)
			)
		)
		(polygon
			(pts
				(xy 196.59346 -62.50432) (xy 196.39026 -62.50432) (xy 196.39026 -62.70752) (xy 196.59346 -62.70752)
			)
		)
		(polygon
			(pts
				(xy 195.7578 -59.6138) (xy 195.5546 -59.6138) (xy 195.5546 -59.817) (xy 195.7578 -59.817)
			)
		)
		(polygon
			(pts
				(xy 195.7578 -59.0042) (xy 195.5546 -59.0042) (xy 195.5546 -59.2074) (xy 195.7578 -59.2074)
			)
		)
	)
	(zone
		(net "P1V8_STBY")
		(layer "B.Cu")
		(hatch none 0.5)
		(connect_pads
			(clearance 0.5)
		)
		(min_thickness 0.25)
		(fill yes
			(thermal_gap 0.5)
			(thermal_bridge_width 0.5)
			(island_removal_mode 0)
		)
		(polygon
			(pts
				(xy 160.3756 -113.5634) (xy 157.226 -116.713) (xy 157.226 -124.079) (xy 157.607 -124.46) (xy 169.418 -124.46)
				(xy 175.3616 -130.4036) (xy 177.5206 -130.4036) (xy 180.957728 -133.840728) (xy 182.846472 -133.840728)
				(xy 187.435744 -138.43) (xy 210.947 -138.43) (xy 211.836 -137.541) (xy 211.836 -130.937) (xy 211.331302 -130.432302)
				(xy 189.998858 -130.432302) (xy 188.764164 -129.197608) (xy 186.736736 -129.197608) (xy 184.217564 -126.678436)
				(xy 181.301136 -126.678436) (xy 180.2765 -125.6538) (xy 180.2765 -121.7295) (xy 175.387 -116.84)
				(xy 167.972486 -116.84) (xy 164.695886 -113.5634)
			)
		)
	)
	(zone
		(layer "B.Cu")
		(hatch none 0.5)
		(connect_pads
			(clearance 0)
		)
		(min_thickness 0.25)
		(keepout
			(tracks not_allowed)
			(vias allowed)
			(pads allowed)
			(copperpour not_allowed)
			(footprints allowed)
		)
		(placement
			(enabled no)
			(sheetname "")
		)
		(fill
			(thermal_gap 0.5)
			(thermal_bridge_width 0.5)
			(island_removal_mode 0)
		)
		(polygon
			(pts
				(arc
					(start 168.800018 -45.72)
					(mid 165.800024 -42.720006)
					(end 162.80003 -45.72)
				)
				(arc
					(start 162.80003 -45.72)
					(mid 165.800024 -48.719994)
					(end 168.800018 -45.72)
				)
			)
		)
	)
	(zone
		(net "PLL_VDD")
		(layer "B.Cu")
		(hatch none 0.5)
		(connect_pads
			(clearance 0.5)
		)
		(min_thickness 0.25)
		(fill yes
			(thermal_gap 0.5)
			(thermal_bridge_width 0.5)
			(island_removal_mode 0)
		)
		(polygon
			(pts
				(xy 174.173134 -75.179428) (xy 173.635162 -75.7174) (xy 170.18 -75.7174) (xy 170.0784 -75.819) (xy 170.0784 -77.2414)
				(xy 170.1419 -77.3049) (xy 170.4213 -77.3049) (xy 170.7388 -77.6224) (xy 170.7388 -78.3082) (xy 170.7896 -78.359)
				(xy 171.2722 -78.359) (xy 171.323 -78.3082) (xy 171.323 -77.978) (xy 171.5516 -77.7494) (xy 174.8282 -77.7494)
				(xy 174.831756 -77.752956) (xy 175.9712 -77.752956) (xy 176.0855 -77.638656) (xy 176.0855 -75.526646)
				(xy 175.738282 -75.179428)
			)
		)
		(polygon
			(pts
				(xy 175.6918 -77.3938) (xy 175.2092 -77.3938) (xy 175.2092 -77.597) (xy 175.6918 -77.597)
			)
		)
		(polygon
			(pts
				(xy 175.0568 -77.3938) (xy 174.8536 -77.3938) (xy 174.8536 -77.597) (xy 175.0568 -77.597)
			)
		)
		(polygon
			(pts
				(xy 174.7012 -76.6826) (xy 174.498 -76.6826) (xy 174.498 -76.8858) (xy 174.7012 -76.8858)
			)
		)
		(polygon
			(pts
				(xy 173.8376 -76.6826) (xy 173.6344 -76.6826) (xy 173.6344 -76.8858) (xy 173.8376 -76.8858)
			)
		)
	)
	(zone
		(layer "B.Cu")
		(hatch none 0.5)
		(connect_pads
			(clearance 0)
		)
		(min_thickness 0.25)
		(keepout
			(tracks not_allowed)
			(vias allowed)
			(pads allowed)
			(copperpour not_allowed)
			(footprints allowed)
		)
		(placement
			(enabled no)
			(sheetname "")
		)
		(fill
			(thermal_gap 0.5)
			(thermal_bridge_width 0.5)
			(island_removal_mode 0)
		)
		(polygon
			(pts
				(arc
					(start 116.584984 -32.000444)
					(mid 116.099971 -31.51505)
					(end 115.614704 -32.00019)
				)
				(arc
					(start 115.614704 -32.45612)
					(mid 115.630281 -32.457859)
					(end 115.645946 -32.458406)
				)
				(xy 115.650518 -32.45866) (xy 115.869466 -32.45866)
				(arc
					(start 115.874038 -32.458406)
					(mid 115.927499 -32.447772)
					(end 115.972844 -32.417512)
				)
				(arc
					(start 115.972844 -32.417512)
					(mid 115.987553 -32.400305)
					(end 115.99926 -32.380936)
				)
				(arc
					(start 115.99926 -32.380936)
					(mid 116.110679 -31.606603)
					(end 116.17833 -32.386016)
				)
				(arc
					(start 116.17833 -32.386016)
					(mid 116.147159 -32.468437)
					(end 116.094256 -32.538924)
				)
				(arc
					(start 116.094256 -32.538924)
					(mid 116.0104 -32.598701)
					(end 115.91163 -32.627824)
				)
				(xy 115.909598 -32.629856) (xy 115.882928 -32.629856) (xy 115.874038 -32.63011) (xy 115.869466 -32.629856)
				(xy 115.650518 -32.629856) (xy 115.645946 -32.63011) (xy 115.636294 -32.629856) (xy 115.614704 -32.629856)
				(xy 115.614704 -32.76854) (xy 115.645946 -32.769556) (xy 115.650518 -32.769556) (xy 115.923822 -32.769556)
				(xy 115.928394 -32.769556) (xy 115.936522 -32.769556) (xy 115.963954 -32.769556)
				(arc
					(start 115.966748 -32.77235)
					(mid 116.044478 -32.797114)
					(end 116.110512 -32.844994)
				)
				(arc
					(start 116.110512 -32.844994)
					(mid 116.158163 -32.910829)
					(end 116.182902 -32.98825)
				)
				(xy 116.185696 -32.991044)
				(arc
					(start 116.185696 -33.015682)
					(mid 116.100745 -33.793703)
					(end 116.01323 -33.015936)
				)
				(arc
					(start 116.01323 -33.015936)
					(mid 116.00525 -32.989187)
					(end 115.9891 -32.966406)
				)
				(arc
					(start 115.9891 -32.966406)
					(mid 115.961248 -32.947796)
					(end 115.928394 -32.94126)
				)
				(xy 115.923822 -32.94126) (xy 115.650518 -32.94126) (xy 115.645946 -32.94126) (xy 115.632738 -32.94126)
				(xy 115.614704 -32.94126)
				(arc
					(start 115.614704 -33.399984)
					(mid 116.099844 -33.885124)
					(end 116.584984 -33.399984)
				)
			)
		)
	)
	(zone
		(layer "B.Cu")
		(hatch none 0.5)
		(connect_pads
			(clearance 0)
		)
		(min_thickness 0.25)
		(keepout
			(tracks allowed)
			(vias allowed)
			(pads allowed)
			(copperpour allowed)
			(footprints not_allowed)
		)
		(placement
			(enabled no)
			(sheetname "")
		)
		(fill
			(thermal_gap 0.5)
			(thermal_bridge_width 0.5)
			(island_removal_mode 0)
		)
		(polygon
			(pts
				(arc
					(start 157.500066 -14.699996)
					(mid 160.000188 -17.200118)
					(end 162.500056 -14.699996)
				)
				(arc
					(start 162.500056 -14.699996)
					(mid 160.000188 -12.200128)
					(end 157.500066 -14.699996)
				)
			)
		)
	)
	(zone
		(net "HM40ADC_VDDA")
		(layer "B.Cu")
		(hatch none 0.5)
		(connect_pads
			(clearance 0.5)
		)
		(min_thickness 0.25)
		(fill yes
			(thermal_gap 0.5)
			(thermal_bridge_width 0.5)
			(island_removal_mode 0)
		)
		(polygon
			(pts
				(xy 194.1068 -43.688) (xy 194.0814 -43.7134) (xy 194.0814 -45.4406) (xy 193.9544 -45.5676) (xy 193.9544 -46.355)
				(xy 193.7512 -46.5582) (xy 193.4718 -46.5582) (xy 193.3956 -46.6344) (xy 193.3956 -47.3202) (xy 192.786 -47.9298)
				(xy 192.786 -48.006) (xy 192.659 -48.133) (xy 192.659 -51.3334) (xy 192.9384 -51.6128) (xy 192.9384 -52.6034)
				(xy 193.2686 -52.9336) (xy 193.675 -52.9336) (xy 193.86296 -52.74564) (xy 193.86296 -52.29606) (xy 194.2846 -51.87442)
				(xy 194.2846 -47.879) (xy 194.2592 -47.879) (xy 195.5038 -46.6344) (xy 195.5038 -43.9674) (xy 195.2244 -43.688)
			)
		)
		(polygon
			(pts
				(xy 193.4718 -51.9684) (xy 193.2686 -51.9684) (xy 193.2686 -52.1716) (xy 193.4718 -52.1716)
			)
		)
		(polygon
			(pts
				(xy 193.4718 -51.6128) (xy 193.2686 -51.6128) (xy 193.2686 -51.816) (xy 193.4718 -51.816)
			)
		)
		(polygon
			(pts
				(xy 194.3608 -47.371) (xy 194.1576 -47.371) (xy 194.1576 -47.5742) (xy 194.3608 -47.5742)
			)
		)
		(polygon
			(pts
				(xy 194.3608 -46.5074) (xy 194.1576 -46.5074) (xy 194.1576 -46.7106) (xy 194.3608 -46.7106)
			)
		)
		(polygon
			(pts
				(xy 194.6148 -46.101) (xy 194.4116 -46.101) (xy 194.4116 -46.3042) (xy 194.6148 -46.3042)
			)
		)
		(polygon
			(pts
				(xy 194.6148 -45.5422) (xy 194.4116 -45.5422) (xy 194.4116 -45.7454) (xy 194.6148 -45.7454)
			)
		)
	)
	(zone
		(layer "B.Cu")
		(hatch none 0.5)
		(connect_pads
			(clearance 0)
		)
		(min_thickness 0.25)
		(keepout
			(tracks not_allowed)
			(vias allowed)
			(pads allowed)
			(copperpour not_allowed)
			(footprints allowed)
		)
		(placement
			(enabled no)
			(sheetname "")
		)
		(fill
			(thermal_gap 0.5)
			(thermal_bridge_width 0.5)
			(island_removal_mode 0)
		)
		(polygon
			(pts
				(arc
					(start 193.399918 -81.0641)
					(mid 193.37152 -81.057396)
					(end 193.349118 -81.0387)
				)
				(arc
					(start 193.349118 -81.2673)
					(mid 193.37152 -81.248604)
					(end 193.399918 -81.2419)
				)
				(arc
					(start 193.603118 -81.2419)
					(mid 193.631516 -81.248604)
					(end 193.653918 -81.2673)
				)
				(arc
					(start 193.653918 -81.0387)
					(mid 193.631516 -81.057396)
					(end 193.603118 -81.0641)
				)
			)
		)
	)
	(zone
		(layer "B.Cu")
		(hatch none 0.5)
		(connect_pads
			(clearance 0)
		)
		(min_thickness 0.25)
		(keepout
			(tracks not_allowed)
			(vias allowed)
			(pads allowed)
			(copperpour not_allowed)
			(footprints allowed)
		)
		(placement
			(enabled no)
			(sheetname "")
		)
		(fill
			(thermal_gap 0.5)
			(thermal_bridge_width 0.5)
			(island_removal_mode 0)
		)
		(polygon
			(pts
				(xy 162.304984 -18.598134) (xy 162.13582 -18.416524)
				(arc
					(start 162.0393 -18.342356)
					(mid 161.953167 -18.240534)
					(end 161.9504 -18.107152)
				)
				(xy 161.94913 -18.103088)
				(arc
					(start 162.007804 -17.993868)
					(mid 162.430423 -17.364629)
					(end 162.139884 -18.064734)
				)
				(arc
					(start 162.095942 -18.146522)
					(mid 162.090324 -18.174747)
					(end 162.101276 -18.201386)
				)
				(xy 162.101784 -18.201386) (xy 162.213036 -18.286984) (xy 162.220148 -18.287238) (xy 162.236912 -18.305272)
				(xy 162.256724 -18.320512) (xy 162.257486 -18.32737) (xy 162.37966 -18.458688)
				(arc
					(start 162.663632 -17.92859)
					(mid 162.47593 -17.284948)
					(end 161.83356 -17.476978)
				)
				(arc
					(start 161.083498 -18.877026)
					(mid 161.277046 -19.516598)
					(end 161.916618 -19.32305)
				)
				(xy 162.102038 -18.976848)
				(arc
					(start 161.844482 -18.700242)
					(mid 161.811143 -18.701806)
					(end 161.786316 -18.724118)
				)
				(arc
					(start 161.742374 -18.80616)
					(mid 161.319755 -19.435399)
					(end 161.610294 -18.735294)
				)
				(xy 161.668968 -18.626074)
				(arc
					(start 161.672778 -18.624804)
					(mid 161.779533 -18.554644)
					(end 161.906966 -18.56359)
				)
				(xy 161.922714 -18.564352) (xy 162.176714 -18.837148)
			)
		)
	)
	(zone
		(layer "B.Cu")
		(hatch none 0.5)
		(connect_pads
			(clearance 0)
		)
		(min_thickness 0.25)
		(keepout
			(tracks allowed)
			(vias allowed)
			(pads allowed)
			(copperpour allowed)
			(footprints not_allowed)
		)
		(placement
			(enabled no)
			(sheetname "")
		)
		(fill
			(thermal_gap 0.5)
			(thermal_bridge_width 0.5)
			(island_removal_mode 0)
		)
		(polygon
			(pts
				(arc
					(start 227.24999 -14.99997)
					(mid 222.499936 -10.249916)
					(end 217.749882 -14.99997)
				)
				(arc
					(start 217.749882 -14.99997)
					(mid 222.499936 -19.750024)
					(end 227.24999 -14.99997)
				)
			)
		)
	)
	(zone
		(layer "B.Cu")
		(hatch none 0.5)
		(connect_pads
			(clearance 0)
		)
		(min_thickness 0.25)
		(keepout
			(tracks not_allowed)
			(vias allowed)
			(pads allowed)
			(copperpour not_allowed)
			(footprints allowed)
		)
		(placement
			(enabled no)
			(sheetname "")
		)
		(fill
			(thermal_gap 0.5)
			(thermal_bridge_width 0.5)
			(island_removal_mode 0)
		)
		(polygon
			(pts
				(arc
					(start 190.097918 -81.0641)
					(mid 190.06952 -81.057396)
					(end 190.047118 -81.0387)
				)
				(arc
					(start 190.047118 -81.2673)
					(mid 190.06952 -81.248604)
					(end 190.097918 -81.2419)
				)
				(arc
					(start 190.301118 -81.2419)
					(mid 190.329516 -81.248604)
					(end 190.351918 -81.2673)
				)
				(arc
					(start 190.351918 -81.0387)
					(mid 190.329516 -81.057396)
					(end 190.301118 -81.0641)
				)
			)
		)
	)
	(zone
		(net "GND")
		(layer "B.Cu")
		(hatch none 0.5)
		(connect_pads
			(clearance 0.5)
		)
		(min_thickness 0.25)
		(fill yes
			(thermal_gap 0.5)
			(thermal_bridge_width 0.5)
			(island_removal_mode 0)
		)
		(polygon
			(pts
				(xy 56.09717 -158.64459) (xy 55.98922 -158.75254) (xy 55.98922 -160.4645) (xy 56.0578 -160.53308)
				(xy 56.61406 -160.53308) (xy 56.72836 -160.41878) (xy 56.72836 -159.75584) (xy 56.9214 -159.5628)
				(xy 57.5056 -159.5628) (xy 57.75325 -159.81045) (xy 57.96915 -159.81045) (xy 57.98566 -159.82696)
				(xy 58.3692 -159.82696) (xy 58.37682 -159.83458) (xy 58.56478 -159.83458) (xy 58.7502 -160.02) (xy 59.55665 -160.02)
				(xy 59.63285 -159.9438) (xy 59.63285 -159.385) (xy 59.515248 -159.267652) (xy 59.077352 -159.267652)
				(xy 58.7756 -158.9659) (xy 57.83961 -158.9659) (xy 57.5183 -158.64459)
			)
		)
		(polygon
			(pts
				(xy 57.390284 -159.10433) (xy 57.187084 -159.10433) (xy 57.187084 -159.30753) (xy 57.390284 -159.30753)
			)
		)
		(polygon
			(pts
				(xy 56.780684 -159.10433) (xy 56.577484 -159.10433) (xy 56.577484 -159.30753) (xy 56.780684 -159.30753)
			)
		)
	)
	(zone
		(layer "B.Cu")
		(hatch none 0.5)
		(connect_pads
			(clearance 0)
		)
		(min_thickness 0.25)
		(keepout
			(tracks allowed)
			(vias allowed)
			(pads allowed)
			(copperpour allowed)
			(footprints allowed)
		)
		(placement
			(enabled no)
			(sheetname "")
		)
		(fill
			(thermal_gap 0.5)
			(thermal_bridge_width 0.5)
			(island_removal_mode 0)
		)
		(polygon
			(pts
				(xy 133.540754 -37.511228) (xy 133.540754 -35.05454) (xy 134.616444 -35.05454) (xy 134.616444 -37.511228)
			)
		)
	)
	(zone
		(net "P0V975")
		(layer "B.Cu")
		(hatch none 0.5)
		(connect_pads
			(clearance 0.5)
		)
		(min_thickness 0.25)
		(fill yes
			(thermal_gap 0.5)
			(thermal_bridge_width 0.5)
			(island_removal_mode 0)
		)
		(polygon
			(pts
				(xy 215.542368 -98.73869) (xy 207.956658 -106.3244) (xy 189.9793 -106.3244) (xy 189.5856 -106.7181)
				(xy 189.5856 -112.7125) (xy 189.8396 -112.9665) (xy 211.074 -112.9665) (xy 219.837 -104.2035) (xy 224.172272 -104.2035)
				(xy 224.756472 -103.6193) (xy 224.756472 -100.13569) (xy 224.733358 -100.112576) (xy 224.733358 -99.356164)
				(xy 224.115884 -98.73869)
			)
		)
	)
	(zone
		(net "GND")
		(layer "B.Cu")
		(hatch none 0.5)
		(connect_pads
			(clearance 0.5)
		)
		(min_thickness 0.25)
		(fill yes
			(thermal_gap 0.5)
			(thermal_bridge_width 0.5)
			(island_removal_mode 0)
		)
		(polygon
			(pts
				(xy 201.581004 -93.054424) (xy 201.352404 -93.283024) (xy 201.352404 -95.086424) (xy 201.784204 -95.518224)
				(xy 203.790804 -95.518224) (xy 204.349604 -94.959424) (xy 204.349604 -93.359224) (xy 204.044804 -93.054424)
			)
		)
		(polygon
			(pts
				(xy 202.393804 -93.892624) (xy 202.190604 -93.892624) (xy 202.190604 -94.095824) (xy 202.393804 -94.095824)
			)
		)
	)
	(zone
		(layer "B.Cu")
		(hatch none 0.5)
		(connect_pads
			(clearance 0)
		)
		(min_thickness 0.25)
		(keepout
			(tracks allowed)
			(vias allowed)
			(pads allowed)
			(copperpour allowed)
			(footprints not_allowed)
		)
		(placement
			(enabled no)
			(sheetname "")
		)
		(fill
			(thermal_gap 0.5)
			(thermal_bridge_width 0.5)
			(island_removal_mode 0)
		)
		(polygon
			(pts
				(arc
					(start 83.250024 -40.049958)
					(mid 78.49997 -35.299904)
					(end 73.749916 -40.049958)
				)
				(arc
					(start 73.749916 -40.049958)
					(mid 78.49997 -44.800012)
					(end 83.250024 -40.049958)
				)
			)
		)
	)
	(zone
		(layer "B.Cu")
		(hatch none 0.5)
		(connect_pads
			(clearance 0)
		)
		(min_thickness 0.25)
		(keepout
			(tracks allowed)
			(vias allowed)
			(pads allowed)
			(copperpour allowed)
			(footprints allowed)
		)
		(placement
			(enabled no)
			(sheetname "")
		)
		(fill
			(thermal_gap 0.5)
			(thermal_bridge_width 0.5)
			(island_removal_mode 0)
		)
		(polygon
			(pts
				(xy 96.2406 -181.0004) (xy 97.663 -181.0004) (xy 97.79 -180.8734) (xy 97.79 -179.8066) (xy 97.7138 -179.7304)
				(xy 96.3422 -179.7304) (xy 96.2406 -179.832)
			)
		)
	)
	(zone
		(layer "B.Cu")
		(hatch none 0.5)
		(connect_pads
			(clearance 0)
		)
		(min_thickness 0.25)
		(keepout
			(tracks allowed)
			(vias allowed)
			(pads allowed)
			(copperpour allowed)
			(footprints not_allowed)
		)
		(placement
			(enabled no)
			(sheetname "")
		)
		(fill
			(thermal_gap 0.5)
			(thermal_bridge_width 0.5)
			(island_removal_mode 0)
		)
		(polygon
			(pts
				(arc
					(start 230.2764 -193.447162)
					(mid 230.156976 -193.631987)
					(end 230.000048 -193.786252)
				)
				(xy 230.000048 0)
				(arc
					(start 234.00004 0)
					(mid 234.707145 -0.292893)
					(end 235.000038 -0.999998)
				)
				(arc
					(start 235.000038 -183.76392)
					(mid 234.973274 -183.993728)
					(end 234.894374 -184.211214)
				)
			)
		)
	)
	(zone
		(net "P1V2_STBY")
		(layer "B.Cu")
		(hatch none 0.5)
		(connect_pads
			(clearance 0.5)
		)
		(min_thickness 0.25)
		(fill yes
			(thermal_gap 0.5)
			(thermal_bridge_width 0.5)
			(island_removal_mode 0)
		)
		(polygon
			(pts
				(xy 30.02407 -142.179802) (xy 28.236418 -143.967454) (xy 22.640036 -143.967454) (xy 22.565106 -144.042384)
				(xy 22.565106 -144.366996) (xy 22.407118 -144.524984) (xy 21.574506 -144.524984) (xy 21.51634 -144.466818)
				(xy 21.51634 -144.02562) (xy 21.408136 -143.917416) (xy 20.955 -143.917416) (xy 20.91055 -143.961866)
				(xy 20.91055 -144.85112) (xy 21.448776 -145.389346) (xy 23.088092 -145.389346) (xy 23.532846 -145.8341)
				(xy 25.895554 -145.8341) (xy 26.041604 -145.98015) (xy 26.041604 -146.918934) (xy 25.828498 -147.13204)
				(xy 23.465536 -147.13204) (xy 23.324058 -147.273518) (xy 23.324058 -149.412706) (xy 23.330662 -149.41931)
				(xy 23.330662 -150.254462) (xy 23.592028 -150.515828) (xy 26.474928 -150.515828) (xy 28.09494 -148.895816)
				(xy 31.306516 -148.895816) (xy 34.36112 -145.841466) (xy 37.13988 -145.841466) (xy 37.338 -145.643346)
				(xy 38.0492 -145.643346) (xy 38.24859 -145.443956) (xy 38.24859 -144.530572) (xy 38.355524 -144.423638)
				(xy 39.021766 -144.423638) (xy 39.0906 -144.354804) (xy 39.0906 -143.357346) (xy 38.989 -143.255746)
				(xy 33.512506 -143.255746) (xy 32.436562 -142.179802)
			)
		)
		(polygon
			(pts
				(xy 26.75382 -146.622008) (xy 26.55062 -146.622008) (xy 26.55062 -146.825208) (xy 26.75382 -146.825208)
			)
		)
		(polygon
			(pts
				(xy 26.75382 -146.012408) (xy 26.55062 -146.012408) (xy 26.55062 -146.215608) (xy 26.75382 -146.215608)
			)
		)
		(polygon
			(pts
				(xy 24.863298 -145.109946) (xy 24.660098 -145.109946) (xy 24.660098 -145.313146) (xy 24.863298 -145.313146)
			)
		)
		(polygon
			(pts
				(xy 24.253698 -145.109946) (xy 24.050498 -145.109946) (xy 24.050498 -145.313146) (xy 24.253698 -145.313146)
			)
		)
		(polygon
			(pts
				(xy 37.570664 -145.060416) (xy 37.367464 -145.060416) (xy 37.367464 -145.263616) (xy 37.570664 -145.263616)
			)
		)
		(polygon
			(pts
				(xy 23.99538 -144.47901) (xy 23.79218 -144.47901) (xy 23.79218 -144.68221) (xy 23.99538 -144.68221)
			)
		)
		(polygon
			(pts
				(xy 23.38578 -144.47901) (xy 23.18258 -144.47901) (xy 23.18258 -144.68221) (xy 23.38578 -144.68221)
			)
		)
		(polygon
			(pts
				(xy 24.463502 -144.471644) (xy 24.260302 -144.471644) (xy 24.260302 -144.674844) (xy 24.463502 -144.674844)
			)
		)
		(polygon
			(pts
				(xy 25.963626 -144.47139) (xy 25.760426 -144.47139) (xy 25.760426 -144.67459) (xy 25.963626 -144.67459)
			)
		)
		(polygon
			(pts
				(xy 25.354026 -144.47139) (xy 25.150826 -144.47139) (xy 25.073102 -144.471644) (xy 24.869902 -144.471644)
				(xy 24.869902 -144.674844) (xy 25.073102 -144.674844) (xy 25.150826 -144.67459) (xy 25.354026 -144.67459)
			)
		)
		(polygon
			(pts
				(xy 37.570664 -144.450816) (xy 37.367464 -144.450816) (xy 37.367464 -144.654016) (xy 37.570664 -144.654016)
			)
		)
		(polygon
			(pts
				(xy 36.572698 -144.117314) (xy 36.369498 -144.117314) (xy 36.369498 -144.320514) (xy 36.572698 -144.320514)
			)
		)
		(polygon
			(pts
				(xy 35.709098 -144.117314) (xy 35.505898 -144.117314) (xy 35.505898 -144.320514) (xy 35.709098 -144.320514)
			)
		)
		(polygon
			(pts
				(xy 38.952678 -144.100042) (xy 38.749478 -144.100042) (xy 38.749478 -144.303242) (xy 38.952678 -144.303242)
			)
		)
		(polygon
			(pts
				(xy 38.089078 -144.100042) (xy 37.885878 -144.100042) (xy 37.885878 -144.303242) (xy 38.089078 -144.303242)
			)
		)
		(polygon
			(pts
				(xy 37.761418 -144.091914) (xy 37.558218 -144.091914) (xy 37.558218 -144.295114) (xy 37.761418 -144.295114)
			)
		)
		(polygon
			(pts
				(xy 36.897818 -144.091914) (xy 36.694618 -144.091914) (xy 36.694618 -144.295114) (xy 36.897818 -144.295114)
			)
		)
	)
	(zone
		(layer "B.Cu")
		(hatch none 0.5)
		(connect_pads
			(clearance 0)
		)
		(min_thickness 0.25)
		(keepout
			(tracks allowed)
			(vias allowed)
			(pads allowed)
			(copperpour allowed)
			(footprints not_allowed)
		)
		(placement
			(enabled no)
			(sheetname "")
		)
		(fill
			(thermal_gap 0.5)
			(thermal_bridge_width 0.5)
			(island_removal_mode 0)
		)
		(polygon
			(pts
				(arc
					(start 217.749882 -110.000034)
					(mid 222.499936 -114.750088)
					(end 227.24999 -110.000034)
				)
				(arc
					(start 227.24999 -110.000034)
					(mid 222.499936 -105.24998)
					(end 217.749882 -110.000034)
				)
			)
		)
	)
	(zone
		(layer "B.Cu")
		(hatch none 0.5)
		(connect_pads
			(clearance 0)
		)
		(min_thickness 0.25)
		(keepout
			(tracks allowed)
			(vias allowed)
			(pads allowed)
			(copperpour allowed)
			(footprints allowed)
		)
		(placement
			(enabled no)
			(sheetname "")
		)
		(fill
			(thermal_gap 0.5)
			(thermal_bridge_width 0.5)
			(island_removal_mode 0)
		)
		(polygon
			(pts
				(xy 115.540536 -33.911032) (xy 115.540536 -31.454344) (xy 116.616226 -31.454344) (xy 116.616226 -33.911032)
			)
		)
	)
	(zone
		(layer "B.Cu")
		(hatch none 0.5)
		(connect_pads
			(clearance 0)
		)
		(min_thickness 0.25)
		(keepout
			(tracks allowed)
			(vias allowed)
			(pads allowed)
			(copperpour allowed)
			(footprints not_allowed)
		)
		(placement
			(enabled no)
			(sheetname "")
		)
		(fill
			(thermal_gap 0.5)
			(thermal_bridge_width 0.5)
			(island_removal_mode 0)
		)
		(polygon
			(pts
				(arc
					(start 13.24991 -120.000014)
					(mid 17.999964 -124.750068)
					(end 22.750018 -120.000014)
				)
				(arc
					(start 22.750018 -120.000014)
					(mid 17.999964 -115.24996)
					(end 13.24991 -120.000014)
				)
			)
		)
	)
	(zone
		(net "P3V3_STBY")
		(layer "B.Cu")
		(hatch none 0.5)
		(connect_pads
			(clearance 0.5)
		)
		(min_thickness 0.25)
		(fill yes
			(thermal_gap 0.5)
			(thermal_bridge_width 0.5)
			(island_removal_mode 0)
		)
		(polygon
			(pts
				(xy 32.5247 -128.6891) (xy 32.0294 -129.1844) (xy 29.7815 -131.432046) (xy 29.7815 -132.8166) (xy 30.1752 -133.2103)
				(xy 30.169104 -133.216396) (xy 30.169104 -134.3279) (xy 31.007304 -135.1661) (xy 31.496 -135.1661)
				(xy 31.9278 -135.5979) (xy 31.9278 -136.423146) (xy 34.223452 -138.718798) (xy 34.223452 -139.106148)
				(xy 34.384488 -139.267184) (xy 35.864038 -139.267184) (xy 36.1188 -139.521946) (xy 36.1188 -139.92987)
				(xy 36.281868 -140.092938) (xy 39.307008 -140.092938) (xy 39.5478 -139.852146) (xy 39.5478 -138.963146)
				(xy 39.482268 -138.897614) (xy 37.95141 -138.897614) (xy 36.963096 -137.9093) (xy 36.6268 -137.9093)
				(xy 36.1188 -137.4013) (xy 36.1188 -132.7277) (xy 37.8333 -131.0132) (xy 37.8333 -129.3495) (xy 37.337746 -128.853946)
				(xy 35.162236 -128.853946) (xy 34.99739 -128.6891)
			)
		)
		(polygon
			(pts
				(xy 38.65753 -139.056364) (xy 38.45433 -139.056364) (xy 38.45433 -139.259564) (xy 38.65753 -139.259564)
			)
		)
		(polygon
			(pts
				(xy 38.33876 -139.04849) (xy 38.13556 -139.04849) (xy 38.13556 -139.25169) (xy 38.33876 -139.25169)
			)
		)
		(polygon
			(pts
				(xy 37.47516 -139.04849) (xy 37.27196 -139.04849) (xy 37.27196 -139.25169) (xy 37.47516 -139.25169)
			)
		)
		(polygon
			(pts
				(xy 37.118798 -139.036044) (xy 36.915598 -139.036044) (xy 36.915598 -139.239244) (xy 37.118798 -139.239244)
			)
		)
		(polygon
			(pts
				(xy 36.255198 -139.036044) (xy 36.051998 -139.036044) (xy 36.051998 -139.239244) (xy 36.255198 -139.239244)
			)
		)
	)
	(zone
		(layer "B.Cu")
		(hatch none 0.5)
		(connect_pads
			(clearance 0)
		)
		(min_thickness 0.25)
		(keepout
			(tracks not_allowed)
			(vias allowed)
			(pads allowed)
			(copperpour not_allowed)
			(footprints allowed)
		)
		(placement
			(enabled no)
			(sheetname "")
		)
		(fill
			(thermal_gap 0.5)
			(thermal_bridge_width 0.5)
			(island_removal_mode 0)
		)
		(polygon
			(pts
				(arc
					(start 22.750018 -120.000014)
					(mid 17.999964 -115.24996)
					(end 13.24991 -120.000014)
				)
				(arc
					(start 13.24991 -120.000014)
					(mid 17.999964 -124.750068)
					(end 22.750018 -120.000014)
				)
			)
		)
	)
	(zone
		(net "GND")
		(layer "B.Cu")
		(hatch none 0.5)
		(connect_pads
			(clearance 0.5)
		)
		(min_thickness 0.25)
		(fill yes
			(thermal_gap 0.5)
			(thermal_bridge_width 0.5)
			(island_removal_mode 0)
		)
		(polygon
			(pts
				(xy 175.150526 -145.039334) (xy 175.150526 -148.380958) (xy 180.719984 -148.380958) (xy 180.719984 -145.039334)
			)
		)
	)
	(zone
		(layer "B.Cu")
		(hatch none 0.5)
		(connect_pads
			(clearance 0)
		)
		(min_thickness 0.25)
		(keepout
			(tracks not_allowed)
			(vias allowed)
			(pads allowed)
			(copperpour not_allowed)
			(footprints allowed)
		)
		(placement
			(enabled no)
			(sheetname "")
		)
		(fill
			(thermal_gap 0.5)
			(thermal_bridge_width 0.5)
			(island_removal_mode 0)
		)
		(polygon
			(pts
				(arc
					(start 136.385046 -36.800282)
					(mid 135.900033 -36.314888)
					(end 135.414766 -36.800028)
				)
				(xy 135.414766 -37.243004) (xy 135.430514 -37.258752) (xy 135.669528 -37.258752)
				(arc
					(start 135.6741 -37.258498)
					(mid 135.727561 -37.247864)
					(end 135.772906 -37.217604)
				)
				(arc
					(start 135.772906 -37.217604)
					(mid 135.787604 -37.200259)
					(end 135.799322 -37.180774)
				)
				(arc
					(start 135.799322 -37.180774)
					(mid 135.910741 -36.406441)
					(end 135.978392 -37.185854)
				)
				(arc
					(start 135.978392 -37.185854)
					(mid 135.947307 -37.26845)
					(end 135.894318 -37.339016)
				)
				(arc
					(start 135.894318 -37.339016)
					(mid 135.810462 -37.398793)
					(end 135.711692 -37.427916)
				)
				(xy 135.70966 -37.429948) (xy 135.68299 -37.429948) (xy 135.6741 -37.430202) (xy 135.669528 -37.429948)
				(xy 135.414766 -37.429948) (xy 135.414766 -37.569648) (xy 135.723884 -37.569648) (xy 135.728456 -37.569648)
				(xy 135.736584 -37.569648) (xy 135.764016 -37.569648)
				(arc
					(start 135.76681 -37.572442)
					(mid 135.84454 -37.597206)
					(end 135.910574 -37.645086)
				)
				(arc
					(start 135.910574 -37.645086)
					(mid 135.958225 -37.710921)
					(end 135.982964 -37.788342)
				)
				(xy 135.985504 -37.791136)
				(arc
					(start 135.985504 -37.815774)
					(mid 135.900429 -38.593795)
					(end 135.813292 -37.816028)
				)
				(arc
					(start 135.813292 -37.816028)
					(mid 135.805312 -37.789279)
					(end 135.789162 -37.766498)
				)
				(arc
					(start 135.789162 -37.766498)
					(mid 135.76131 -37.747888)
					(end 135.728456 -37.741352)
				)
				(xy 135.723884 -37.741352) (xy 135.414766 -37.741352)
				(arc
					(start 135.414766 -38.200076)
					(mid 135.899906 -38.685216)
					(end 136.385046 -38.200076)
				)
			)
		)
	)
	(zone
		(net "P2V5_STBY")
		(layer "B.Cu")
		(hatch none 0.5)
		(connect_pads
			(clearance 0.5)
		)
		(min_thickness 0.25)
		(fill yes
			(thermal_gap 0.5)
			(thermal_bridge_width 0.5)
			(island_removal_mode 0)
		)
		(polygon
			(pts
				(xy 32.481774 -164.614098) (xy 30.996636 -166.099236) (xy 30.672786 -166.422832) (xy 30.6324 -166.463218)
				(xy 30.6324 -169.7736) (xy 31.0134 -170.1546) (xy 35.824922 -170.1546) (xy 39.761922 -166.2176)
				(xy 42.980864 -166.2176) (xy 47.11954 -170.356276) (xy 47.959264 -170.356276) (xy 48.085248 -170.48226)
				(xy 59.2582 -170.48226) (xy 59.758834 -169.981626) (xy 62.336426 -169.981626) (xy 62.568836 -169.749216)
				(xy 63.59525 -169.749216) (xy 65.813686 -167.53078) (xy 69.578982 -167.53078) (xy 73.787 -171.738798)
				(xy 77.847444 -171.738798) (xy 78.026768 -171.559474) (xy 78.026768 -170.6372) (xy 77.9526 -170.563032)
				(xy 77.9526 -170.561) (xy 73.177654 -165.786054) (xy 65.063878 -165.786054) (xy 64.036448 -166.813484)
				(xy 64.036448 -166.894764) (xy 63.107062 -167.82415) (xy 54.977538 -167.82415) (xy 54.666388 -167.513)
				(xy 53.7972 -167.513) (xy 53.213 -166.9288) (xy 48.8696 -166.9288) (xy 48.5013 -166.5605) (xy 46.6471 -166.5605)
				(xy 46.61916 -166.53256) (xy 45.050456 -166.53256) (xy 43.131994 -164.614098)
			)
		)
	)
	(zone
		(net "P1V5")
		(layer "B.Cu")
		(hatch none 0.5)
		(connect_pads
			(clearance 0.5)
		)
		(min_thickness 0.25)
		(fill yes
			(thermal_gap 0.5)
			(thermal_bridge_width 0.5)
			(island_removal_mode 0)
		)
		(polygon
			(pts
				(xy 206.875634 -92.992194) (xy 206.686404 -93.181424) (xy 204.752194 -93.181424) (xy 204.678788 -93.25483)
				(xy 204.678788 -96.317308) (xy 205.055724 -96.694244) (xy 207.218534 -96.694244) (xy 207.651604 -96.261174)
				(xy 207.651604 -93.232224) (xy 207.411574 -92.992194)
			)
		)
		(polygon
			(pts
				(xy 207.016604 -93.460824) (xy 206.813404 -93.460824) (xy 206.813404 -93.664024) (xy 207.016604 -93.664024)
			)
		)
	)
	(zone
		(net "GND")
		(layer "B.Cu")
		(hatch none 0.5)
		(connect_pads
			(clearance 0.5)
		)
		(min_thickness 0.25)
		(fill yes
			(thermal_gap 0.5)
			(thermal_bridge_width 0.5)
			(island_removal_mode 0)
		)
		(polygon
			(pts
				(xy 9.863074 -126.5682) (xy 6.99135 -129.439924) (xy 6.99135 -146.554444) (xy 10.689844 -150.252938)
				(xy 12.45108 -150.252938) (xy 12.942062 -149.761956) (xy 12.942062 -145.994882) (xy 13.181076 -145.755868)
				(xy 13.181076 -145.32483) (xy 13.172186 -145.32483) (xy 13.172186 -144.964912) (xy 13.040106 -144.832832)
				(xy 11.40968 -144.832832) (xy 11.226292 -144.649444) (xy 11.226292 -143.775938) (xy 10.668254 -143.2179)
				(xy 10.214102 -143.2179) (xy 10.036556 -143.040354) (xy 10.036556 -131.230878) (xy 12.337034 -128.9304)
				(xy 25.1206 -128.9304) (xy 25.4762 -129.286) (xy 25.4762 -129.308098) (xy 26.3398 -130.171698) (xy 26.3398 -141.544294)
				(xy 26.08961 -141.794484) (xy 25.755092 -141.794484) (xy 25.508712 -142.040864) (xy 25.508712 -142.675102)
				(xy 25.298654 -142.88516) (xy 24.64816 -142.88516) (xy 24.571452 -142.808452) (xy 23.433278 -142.808452)
				(xy 23.320248 -142.921482) (xy 22.695916 -142.921482) (xy 22.583648 -143.03375) (xy 22.583648 -143.537432)
				(xy 22.720554 -143.674338) (xy 27.833828 -143.674338) (xy 29.742638 -141.765528) (xy 33.009078 -141.765528)
				(xy 34.071814 -142.828264) (xy 38.78199 -142.828264) (xy 38.873938 -142.736316) (xy 39.141908 -142.736316)
				(xy 39.175436 -142.769844) (xy 40.132 -142.769844) (xy 40.132 -140.914628) (xy 39.577772 -140.3604)
				(xy 35.959796 -140.3604) (xy 35.803332 -140.203936) (xy 35.803332 -139.689332) (xy 35.7886 -139.6746)
				(xy 33.095946 -139.6746) (xy 31.766256 -138.34491) (xy 31.766256 -137.328656) (xy 29.8704 -135.4328)
				(xy 29.8704 -133.3246) (xy 29.464 -132.9182) (xy 29.464 -128.0922) (xy 28.6766 -127.3048) (xy 26.2763 -127.3048)
				(xy 25.5397 -126.5682)
			)
		)
		(polygon
			(pts
				(xy 12.1793 -147.7137) (xy 11.9761 -147.7137) (xy 11.9761 -147.9169) (xy 12.1793 -147.9169)
			)
		)
		(polygon
			(pts
				(xy 12.1793 -146.8501) (xy 11.9761 -146.8501) (xy 11.9761 -147.0533) (xy 12.1793 -147.0533)
			)
		)
		(polygon
			(pts
				(xy 12.714224 -145.41373) (xy 12.511024 -145.41373) (xy 12.511024 -145.61693) (xy 12.714224 -145.61693)
			)
		)
		(polygon
			(pts
				(xy 10.304272 -144.428464) (xy 10.101072 -144.428464) (xy 10.101072 -144.631664) (xy 10.304272 -144.631664)
			)
		)
		(polygon
			(pts
				(xy 10.304272 -143.564864) (xy 10.101072 -143.564864) (xy 10.101072 -143.768064) (xy 10.304272 -143.768064)
			)
		)
		(polygon
			(pts
				(xy 23.99538 -142.95501) (xy 23.79218 -142.95501) (xy 23.79218 -143.15821) (xy 23.99538 -143.15821)
			)
		)
		(polygon
			(pts
				(xy 24.463502 -142.947644) (xy 24.260302 -142.947644) (xy 24.260302 -143.150844) (xy 24.463502 -143.150844)
			)
		)
		(polygon
			(pts
				(xy 25.963626 -142.94739) (xy 25.760426 -142.94739) (xy 25.760426 -143.15059) (xy 25.963626 -143.15059)
			)
		)
		(polygon
			(pts
				(xy 9.5758 -142.6464) (xy 9.3726 -142.6464) (xy 9.3726 -142.8496) (xy 9.5758 -142.8496)
			)
		)
		(polygon
			(pts
				(xy 26.155904 -142.459964) (xy 25.952704 -142.459964) (xy 25.952704 -142.663164) (xy 26.155904 -142.663164)
			)
		)
		(polygon
			(pts
				(xy 9.5758 -142.0876) (xy 9.3726 -142.0876) (xy 9.3726 -142.2908) (xy 9.5758 -142.2908)
			)
		)
		(polygon
			(pts
				(xy 39.573454 -142.079218) (xy 39.370254 -142.079218) (xy 39.370254 -142.282418) (xy 39.573454 -142.282418)
			)
		)
		(polygon
			(pts
				(xy 26.155904 -141.901164) (xy 25.952704 -141.901164) (xy 25.952704 -142.104364) (xy 26.155904 -142.104364)
			)
		)
		(polygon
			(pts
				(xy 36.572698 -141.831314) (xy 36.369498 -141.831314) (xy 36.369498 -142.034514) (xy 36.572698 -142.034514)
			)
		)
		(polygon
			(pts
				(xy 35.709098 -141.831314) (xy 35.505898 -141.831314) (xy 35.505898 -142.034514) (xy 35.709098 -142.034514)
			)
		)
		(polygon
			(pts
				(xy 38.952678 -141.814042) (xy 38.749478 -141.814042) (xy 38.749478 -142.017242) (xy 38.952678 -142.017242)
			)
		)
		(polygon
			(pts
				(xy 38.089078 -141.814042) (xy 37.885878 -141.814042) (xy 37.885878 -142.017242) (xy 38.089078 -142.017242)
			)
		)
		(polygon
			(pts
				(xy 37.761418 -141.805914) (xy 37.558218 -141.805914) (xy 37.558218 -142.009114) (xy 37.761418 -142.009114)
			)
		)
		(polygon
			(pts
				(xy 36.897818 -141.805914) (xy 36.694618 -141.805914) (xy 36.694618 -142.009114) (xy 36.897818 -142.009114)
			)
		)
		(polygon
			(pts
				(xy 39.52113 -141.342364) (xy 39.31793 -141.342364) (xy 39.31793 -141.545564) (xy 39.52113 -141.545564)
			)
		)
		(polygon
			(pts
				(xy 38.65753 -141.342364) (xy 38.45433 -141.342364) (xy 38.45433 -141.545564) (xy 38.65753 -141.545564)
			)
		)
		(polygon
			(pts
				(xy 38.33876 -141.33449) (xy 38.13556 -141.33449) (xy 38.13556 -141.53769) (xy 38.33876 -141.53769)
			)
		)
		(polygon
			(pts
				(xy 37.47516 -141.33449) (xy 37.27196 -141.33449) (xy 37.27196 -141.53769) (xy 37.47516 -141.53769)
			)
		)
		(polygon
			(pts
				(xy 37.118798 -141.322044) (xy 36.915598 -141.322044) (xy 36.915598 -141.525244) (xy 37.118798 -141.525244)
			)
		)
		(polygon
			(pts
				(xy 36.255198 -141.322044) (xy 36.051998 -141.322044) (xy 36.051998 -141.525244) (xy 36.255198 -141.525244)
			)
		)
		(polygon
			(pts
				(xy 9.59739 -141.186662) (xy 9.39419 -141.186662) (xy 9.39419 -141.389862) (xy 9.59739 -141.389862)
			)
		)
		(polygon
			(pts
				(xy 9.59739 -140.627862) (xy 9.39419 -140.627862) (xy 9.39419 -140.831062) (xy 9.59739 -140.831062)
			)
		)
		(polygon
			(pts
				(xy 39.52113 -140.478764) (xy 39.31793 -140.478764) (xy 39.31793 -140.681964) (xy 39.52113 -140.681964)
			)
		)
		(polygon
			(pts
				(xy 38.65753 -140.478764) (xy 38.45433 -140.478764) (xy 38.45433 -140.681964) (xy 38.65753 -140.681964)
			)
		)
		(polygon
			(pts
				(xy 38.33876 -140.47089) (xy 38.13556 -140.47089) (xy 38.13556 -140.67409) (xy 38.33876 -140.67409)
			)
		)
		(polygon
			(pts
				(xy 37.47516 -140.47089) (xy 37.27196 -140.47089) (xy 37.27196 -140.67409) (xy 37.47516 -140.67409)
			)
		)
		(polygon
			(pts
				(xy 9.601962 -139.752832) (xy 9.398762 -139.752832) (xy 9.398762 -139.956032) (xy 9.601962 -139.956032)
			)
		)
		(polygon
			(pts
				(xy 9.601962 -139.194032) (xy 9.398762 -139.194032) (xy 9.398762 -139.397232) (xy 9.601962 -139.397232)
			)
		)
		(polygon
			(pts
				(xy 9.590532 -138.323574) (xy 9.387332 -138.323574) (xy 9.387332 -138.526774) (xy 9.590532 -138.526774)
			)
		)
		(polygon
			(pts
				(xy 9.590532 -137.764774) (xy 9.387332 -137.764774) (xy 9.387332 -137.967974) (xy 9.590532 -137.967974)
			)
		)
		(polygon
			(pts
				(xy 9.565132 -136.894316) (xy 9.361932 -136.894316) (xy 9.361932 -137.097516) (xy 9.565132 -137.097516)
			)
		)
		(polygon
			(pts
				(xy 27.323796 -136.429496) (xy 27.120596 -136.429496) (xy 27.120596 -136.632696) (xy 27.323796 -136.632696)
			)
		)
		(polygon
			(pts
				(xy 9.565132 -136.335516) (xy 9.361932 -136.335516) (xy 9.361932 -136.538716) (xy 9.565132 -136.538716)
			)
		)
		(polygon
			(pts
				(xy 27.323796 -135.565896) (xy 27.120596 -135.565896) (xy 27.120596 -135.769096) (xy 27.323796 -135.769096)
			)
		)
		(polygon
			(pts
				(xy 9.59231 -135.467852) (xy 9.38911 -135.467852) (xy 9.38911 -135.671052) (xy 9.59231 -135.671052)
			)
		)
		(polygon
			(pts
				(xy 9.59231 -134.909052) (xy 9.38911 -134.909052) (xy 9.38911 -135.112252) (xy 9.59231 -135.112252)
			)
		)
		(polygon
			(pts
				(xy 9.59485 -134.03453) (xy 9.39165 -134.03453) (xy 9.39165 -134.23773) (xy 9.59485 -134.23773)
			)
		)
		(polygon
			(pts
				(xy 9.59485 -133.47573) (xy 9.39165 -133.47573) (xy 9.39165 -133.67893) (xy 9.59485 -133.67893)
			)
		)
		(polygon
			(pts
				(xy 9.583928 -132.580634) (xy 9.380728 -132.580634) (xy 9.380728 -132.783834) (xy 9.583928 -132.783834)
			)
		)
		(polygon
			(pts
				(xy 9.583928 -132.021834) (xy 9.380728 -132.021834) (xy 9.380728 -132.225034) (xy 9.583928 -132.225034)
			)
		)
		(polygon
			(pts
				(xy 25.2476 -128.2954) (xy 25.0444 -128.2954) (xy 25.0444 -128.4986) (xy 25.2476 -128.4986)
			)
		)
		(polygon
			(pts
				(xy 24.6888 -128.2954) (xy 24.4856 -128.2954) (xy 24.4856 -128.4986) (xy 24.6888 -128.4986)
			)
		)
		(polygon
			(pts
				(xy 23.818342 -128.2954) (xy 23.615142 -128.2954) (xy 23.615142 -128.4986) (xy 23.818342 -128.4986)
			)
		)
		(polygon
			(pts
				(xy 23.259542 -128.2954) (xy 23.056342 -128.2954) (xy 23.056342 -128.4986) (xy 23.259542 -128.4986)
			)
		)
		(polygon
			(pts
				(xy 22.395942 -128.2954) (xy 22.192742 -128.2954) (xy 22.192742 -128.4986) (xy 22.395942 -128.4986)
			)
		)
		(polygon
			(pts
				(xy 21.837142 -128.2954) (xy 21.633942 -128.2954) (xy 21.633942 -128.4986) (xy 21.837142 -128.4986)
			)
		)
		(polygon
			(pts
				(xy 19.525742 -128.264666) (xy 19.322542 -128.264666) (xy 19.322542 -128.467866) (xy 19.525742 -128.467866)
			)
		)
		(polygon
			(pts
				(xy 18.966942 -128.264666) (xy 18.763742 -128.264666) (xy 18.763742 -128.467866) (xy 18.966942 -128.467866)
			)
		)
		(polygon
			(pts
				(xy 16.700754 -128.264158) (xy 16.497554 -128.264158) (xy 16.497554 -128.467358) (xy 16.700754 -128.467358)
			)
		)
		(polygon
			(pts
				(xy 16.141954 -128.264158) (xy 15.938754 -128.264158) (xy 15.938754 -128.467358) (xy 16.141954 -128.467358)
			)
		)
		(polygon
			(pts
				(xy 20.972272 -128.261364) (xy 20.769072 -128.261364) (xy 20.769072 -128.464564) (xy 20.972272 -128.464564)
			)
		)
		(polygon
			(pts
				(xy 20.413472 -128.261364) (xy 20.210272 -128.261364) (xy 20.210272 -128.464564) (xy 20.413472 -128.464564)
			)
		)
		(polygon
			(pts
				(xy 18.130012 -128.238758) (xy 17.926812 -128.238758) (xy 17.926812 -128.441958) (xy 18.130012 -128.441958)
			)
		)
		(polygon
			(pts
				(xy 17.571212 -128.238758) (xy 17.368012 -128.238758) (xy 17.368012 -128.441958) (xy 17.571212 -128.441958)
			)
		)
	)
	(zone
		(layer "B.Cu")
		(hatch none 0.5)
		(connect_pads
			(clearance 0)
		)
		(min_thickness 0.25)
		(keepout
			(tracks not_allowed)
			(vias allowed)
			(pads allowed)
			(copperpour not_allowed)
			(footprints allowed)
		)
		(placement
			(enabled no)
			(sheetname "")
		)
		(fill
			(thermal_gap 0.5)
			(thermal_bridge_width 0.5)
			(island_removal_mode 0)
		)
		(polygon
			(pts
				(arc
					(start 160.250124 -187.999878)
					(mid 155.50007 -183.249824)
					(end 150.750016 -187.999878)
				)
				(arc
					(start 150.750016 -187.999878)
					(mid 155.50007 -192.749932)
					(end 160.250124 -187.999878)
				)
			)
		)
	)
	(zone
		(net "GND")
		(layer "B.Cu")
		(hatch none 0.5)
		(connect_pads
			(clearance 0.5)
		)
		(min_thickness 0.25)
		(fill yes
			(thermal_gap 0.5)
			(thermal_bridge_width 0.5)
			(island_removal_mode 0)
		)
		(polygon
			(pts
				(xy 21.59 -178.2064) (xy 21.209 -178.5874) (xy 21.209 -179.9844) (xy 21.5646 -180.34) (xy 23.749 -180.34)
				(xy 24.1554 -179.9336) (xy 24.1554 -178.435) (xy 23.9268 -178.2064)
			)
		)
	)
	(zone
		(layer "B.Cu")
		(hatch none 0.5)
		(connect_pads
			(clearance 0)
		)
		(min_thickness 0.25)
		(keepout
			(tracks not_allowed)
			(vias allowed)
			(pads allowed)
			(copperpour not_allowed)
			(footprints allowed)
		)
		(placement
			(enabled no)
			(sheetname "")
		)
		(fill
			(thermal_gap 0.5)
			(thermal_bridge_width 0.5)
			(island_removal_mode 0)
		)
		(polygon
			(pts
				(xy 140.814806 -36.230052) (xy 140.814806 -36.368736) (xy 140.846048 -36.369752) (xy 140.85062 -36.369752)
				(xy 141.123924 -36.369752) (xy 141.128496 -36.369752) (xy 141.136624 -36.369752) (xy 141.164056 -36.369752)
				(arc
					(start 141.16685 -36.372546)
					(mid 141.24458 -36.39731)
					(end 141.310614 -36.44519)
				)
				(arc
					(start 141.310614 -36.44519)
					(mid 141.358265 -36.511025)
					(end 141.383004 -36.588446)
				)
				(xy 141.385544 -36.59124)
				(arc
					(start 141.385544 -36.615878)
					(mid 141.300469 -37.393899)
					(end 141.213332 -36.616132)
				)
				(arc
					(start 141.213332 -36.616132)
					(mid 141.205352 -36.589383)
					(end 141.189202 -36.566602)
				)
				(arc
					(start 141.189202 -36.566602)
					(mid 141.16135 -36.547992)
					(end 141.128496 -36.541456)
				)
				(xy 141.123924 -36.541456) (xy 140.85062 -36.541456) (xy 140.846048 -36.541456) (xy 140.83284 -36.541456)
				(xy 140.814806 -36.541456)
				(arc
					(start 140.814806 -37.00018)
					(mid 141.299946 -37.48532)
					(end 141.785086 -37.00018)
				)
				(arc
					(start 141.785086 -35.600386)
					(mid 141.300073 -35.114992)
					(end 140.814806 -35.600132)
				)
				(arc
					(start 140.814806 -36.056316)
					(mid 140.830383 -36.058055)
					(end 140.846048 -36.058602)
				)
				(xy 140.85062 -36.058856) (xy 141.069568 -36.058856)
				(arc
					(start 141.07414 -36.058602)
					(mid 141.127601 -36.047968)
					(end 141.172946 -36.017708)
				)
				(arc
					(start 141.172946 -36.017708)
					(mid 141.187644 -36.000363)
					(end 141.199362 -35.980878)
				)
				(arc
					(start 141.199362 -35.980878)
					(mid 141.310781 -35.206545)
					(end 141.378432 -35.985958)
				)
				(arc
					(start 141.378432 -35.985958)
					(mid 141.347347 -36.068554)
					(end 141.294358 -36.13912)
				)
				(arc
					(start 141.294358 -36.13912)
					(mid 141.210502 -36.198897)
					(end 141.111732 -36.22802)
				)
				(xy 141.1097 -36.230052) (xy 141.08303 -36.230052) (xy 141.07414 -36.230306) (xy 141.069568 -36.230052)
				(xy 140.85062 -36.230052) (xy 140.846048 -36.230306) (xy 140.836396 -36.230052)
			)
		)
	)
	(zone
		(net "GND")
		(layer "B.Cu")
		(hatch none 0.5)
		(connect_pads
			(clearance 0.5)
		)
		(min_thickness 0.25)
		(fill yes
			(thermal_gap 0.5)
			(thermal_bridge_width 0.5)
			(island_removal_mode 0)
		)
		(polygon
			(pts
				(xy 32.4993 -150.9903) (xy 32.3469 -151.1427) (xy 32.3469 -152.03678) (xy 32.8422 -152.53208) (xy 34.10458 -152.53208)
				(xy 34.8615 -153.289) (xy 34.8615 -153.7843) (xy 33.98774 -154.65806) (xy 33.15716 -154.65806) (xy 33.04413 -154.77109)
				(xy 33.04413 -156.54147) (xy 32.8676 -156.718) (xy 32.0421 -156.718) (xy 31.62554 -156.30144) (xy 30.9245 -156.30144)
				(xy 30.7213 -156.50464) (xy 30.7213 -157.17774) (xy 31.90748 -158.36392) (xy 35.55238 -158.36392)
				(xy 35.80892 -158.10738) (xy 35.80892 -153.2763) (xy 35.81146 -153.27376) (xy 35.81146 -153.17724)
				(xy 36.35121 -152.63749) (xy 36.35121 -151.04491) (xy 36.2966 -150.9903)
			)
		)
		(polygon
			(pts
				(xy 32.8422 -157.1752) (xy 32.639 -157.1752) (xy 32.639 -157.3784) (xy 32.8422 -157.3784)
			)
		)
		(polygon
			(pts
				(xy 32.2834 -157.1752) (xy 32.0802 -157.1752) (xy 32.0802 -157.3784) (xy 32.2834 -157.3784)
			)
		)
		(polygon
			(pts
				(xy 33.3248 -151.9936) (xy 33.1216 -151.9936) (xy 33.1216 -152.1968) (xy 33.3248 -152.1968)
			)
		)
		(polygon
			(pts
				(xy 35.531806 -151.799798) (xy 35.328606 -151.799798) (xy 35.328606 -152.002998) (xy 35.531806 -152.002998)
			)
		)
		(polygon
			(pts
				(xy 35.2298 -151.4856) (xy 35.0266 -151.4856) (xy 35.0266 -151.6888) (xy 35.2298 -151.6888)
			)
		)
		(polygon
			(pts
				(xy 34.6202 -151.4856) (xy 34.1376 -151.4856) (xy 34.1376 -151.6888) (xy 34.6202 -151.6888)
			)
		)
		(polygon
			(pts
				(xy 33.7312 -151.4856) (xy 33.528 -151.4856) (xy 33.528 -151.6888) (xy 33.7312 -151.6888)
			)
		)
		(polygon
			(pts
				(xy 33.3248 -151.13) (xy 33.1216 -151.13) (xy 33.1216 -151.3332) (xy 33.3248 -151.3332)
			)
		)
	)
	(zone
		(layer "B.Cu")
		(hatch none 0.5)
		(connect_pads
			(clearance 0)
		)
		(min_thickness 0.25)
		(keepout
			(tracks allowed)
			(vias allowed)
			(pads allowed)
			(copperpour allowed)
			(footprints not_allowed)
		)
		(placement
			(enabled no)
			(sheetname "")
		)
		(fill
			(thermal_gap 0.5)
			(thermal_bridge_width 0.5)
			(island_removal_mode 0)
		)
		(polygon
			(pts
				(arc
					(start 17.249902 -187.999878)
					(mid 12.500102 -183.250078)
					(end 7.750048 -187.999878)
				)
				(arc
					(start 7.750048 -187.999878)
					(mid 12.500102 -192.749932)
					(end 17.249902 -187.999878)
				)
			)
		)
	)
	(zone
		(layer "B.Cu")
		(hatch none 0.5)
		(connect_pads
			(clearance 0)
		)
		(min_thickness 0.25)
		(keepout
			(tracks allowed)
			(vias allowed)
			(pads allowed)
			(copperpour allowed)
			(footprints not_allowed)
		)
		(placement
			(enabled no)
			(sheetname "")
		)
		(fill
			(thermal_gap 0.5)
			(thermal_bridge_width 0.5)
			(island_removal_mode 0)
		)
		(polygon
			(pts
				(arc
					(start 13.24991 -24.99995)
					(mid 17.999964 -29.750004)
					(end 22.750018 -24.99995)
				)
				(arc
					(start 22.750018 -24.99995)
					(mid 17.999964 -20.249896)
					(end 13.24991 -24.99995)
				)
			)
		)
	)
	(zone
		(net "USB_CONN_GND")
		(layer "B.Cu")
		(hatch none 0.5)
		(connect_pads
			(clearance 0.5)
		)
		(min_thickness 0.25)
		(fill yes
			(thermal_gap 0.5)
			(thermal_bridge_width 0.5)
			(island_removal_mode 0)
		)
		(polygon
			(pts
				(xy 91.186 -4.7752) (xy 84.5312 -11.43) (xy 84.5312 -24.7142) (xy 85.217 -25.4) (xy 92.3798 -25.4)
				(xy 93.2434 -24.5364) (xy 93.2434 -11.557) (xy 95.1992 -9.6012) (xy 95.1992 -5.0038) (xy 94.9706 -4.7752)
			)
		)
		(polygon
			(pts
				(xy 94.7674 -8.0518) (xy 94.5642 -8.0518) (xy 94.5642 -8.255) (xy 94.7674 -8.255)
			)
		)
		(polygon
			(pts
				(xy 94.7674 -7.493) (xy 94.5642 -7.493) (xy 94.5642 -7.6962) (xy 94.7674 -7.6962)
			)
		)
	)
	(zone
		(layer "B.Cu")
		(hatch none 0.5)
		(connect_pads
			(clearance 0)
		)
		(min_thickness 0.25)
		(keepout
			(tracks allowed)
			(vias allowed)
			(pads allowed)
			(copperpour allowed)
			(footprints allowed)
		)
		(placement
			(enabled no)
			(sheetname "")
		)
		(fill
			(thermal_gap 0.5)
			(thermal_bridge_width 0.5)
			(island_removal_mode 0)
		)
		(polygon
			(pts
				(xy 166.3954 -37.7444) (xy 167.4876 -37.7444) (xy 167.4876 -39.116) (xy 166.3954 -39.116)
			)
		)
	)
	(zone
		(net "P12V_IOM")
		(layer "B.Cu")
		(hatch none 0.5)
		(connect_pads
			(clearance 0.5)
		)
		(min_thickness 0.25)
		(fill yes
			(thermal_gap 0.5)
			(thermal_bridge_width 0.5)
			(island_removal_mode 0)
		)
		(polygon
			(pts
				(xy 122.6058 -14.478) (xy 122.4788 -14.605) (xy 122.4788 -16.637) (xy 123.74245 -17.90065) (xy 123.74245 -18.54835)
				(xy 125.10516 -19.91106) (xy 126.846076 -19.91106) (xy 127.496062 -20.561046) (xy 128.925574 -20.561046)
				(xy 130.81254 -18.67408) (xy 133.77926 -18.67408) (xy 133.97992 -18.47342) (xy 133.97992 -16.234156)
				(xy 133.567424 -15.82166) (xy 129.439924 -15.82166) (xy 129.439924 -16.92148) (xy 129.140204 -17.2212)
				(xy 127.762 -17.2212) (xy 126.5682 -16.0274) (xy 124.1044 -16.0274) (xy 123.8377 -15.7607) (xy 123.8377 -14.6431)
				(xy 123.6726 -14.478)
			)
		)
		(polygon
			(pts
				(xy 130.0988 -16.6878) (xy 129.8956 -16.6878) (xy 129.8956 -16.891) (xy 130.0988 -16.891)
			)
		)
		(polygon
			(pts
				(xy 125.006862 -16.468598) (xy 124.803662 -16.468598) (xy 124.803662 -16.671798) (xy 125.006862 -16.671798)
			)
		)
		(polygon
			(pts
				(xy 124.448062 -16.468598) (xy 124.244862 -16.468598) (xy 124.244862 -16.671798) (xy 124.448062 -16.671798)
			)
		)
		(polygon
			(pts
				(xy 123.1392 -16.1544) (xy 122.936 -16.1544) (xy 122.936 -16.3576) (xy 123.1392 -16.3576)
			)
		)
		(polygon
			(pts
				(xy 130.0988 -16.129) (xy 129.8956 -16.129) (xy 129.8956 -16.3322) (xy 130.0988 -16.3322)
			)
		)
		(polygon
			(pts
				(xy 123.1392 -15.5956) (xy 122.936 -15.5956) (xy 122.936 -15.7988) (xy 123.1392 -15.7988)
			)
		)
		(polygon
			(pts
				(xy 123.1392 -15.1384) (xy 122.936 -15.1384) (xy 122.936 -15.3416) (xy 123.1392 -15.3416)
			)
		)
	)
	(zone
		(net "VPLLAV33")
		(layer "B.Cu")
		(hatch none 0.5)
		(connect_pads
			(clearance 0.5)
		)
		(min_thickness 0.25)
		(fill yes
			(thermal_gap 0.5)
			(thermal_bridge_width 0.5)
			(island_removal_mode 0)
		)
		(polygon
			(pts
				(xy 56.1213 -157.3149) (xy 55.9562 -157.48) (xy 55.9562 -158.18104) (xy 56.06796 -158.2928) (xy 57.44718 -158.2928)
				(xy 57.4802 -158.32582) (xy 57.51322 -158.32582) (xy 57.5564 -158.369) (xy 58.81624 -158.369) (xy 59.36107 -158.91383)
				(xy 59.81573 -158.91383) (xy 59.97067 -159.06877) (xy 59.97067 -159.73933) (xy 60.02528 -159.79394)
				(xy 61.1251 -159.79394) (xy 61.15304 -159.766) (xy 61.4172 -159.766) (xy 61.4172 -158.4706) (xy 61.26861 -158.32201)
				(xy 59.82081 -158.32201) (xy 58.8137 -157.3149)
			)
		)
		(polygon
			(pts
				(xy 57.390284 -157.58033) (xy 57.187084 -157.58033) (xy 57.187084 -157.78353) (xy 57.390284 -157.78353)
			)
		)
		(polygon
			(pts
				(xy 56.780684 -157.58033) (xy 56.577484 -157.58033) (xy 56.577484 -157.78353) (xy 56.780684 -157.78353)
			)
		)
	)
	(zone
		(layer "B.Cu")
		(hatch none 0.5)
		(connect_pads
			(clearance 0)
		)
		(min_thickness 0.25)
		(keepout
			(tracks not_allowed)
			(vias allowed)
			(pads allowed)
			(copperpour not_allowed)
			(footprints allowed)
		)
		(placement
			(enabled no)
			(sheetname "")
		)
		(fill
			(thermal_gap 0.5)
			(thermal_bridge_width 0.5)
			(island_removal_mode 0)
		)
		(polygon
			(pts
				(arc
					(start 112.985042 -32.000444)
					(mid 112.500029 -31.51505)
					(end 112.014762 -32.00019)
				)
				(arc
					(start 112.014762 -32.45612)
					(mid 112.030339 -32.457859)
					(end 112.046004 -32.458406)
				)
				(xy 112.050576 -32.45866) (xy 112.269524 -32.45866)
				(arc
					(start 112.274096 -32.458406)
					(mid 112.327557 -32.447772)
					(end 112.372902 -32.417512)
				)
				(arc
					(start 112.372902 -32.417512)
					(mid 112.387611 -32.400305)
					(end 112.399318 -32.380936)
				)
				(arc
					(start 112.399318 -32.380936)
					(mid 112.510737 -31.606603)
					(end 112.578388 -32.386016)
				)
				(arc
					(start 112.578388 -32.386016)
					(mid 112.547217 -32.468437)
					(end 112.494314 -32.538924)
				)
				(arc
					(start 112.494314 -32.538924)
					(mid 112.410458 -32.598701)
					(end 112.311688 -32.627824)
				)
				(xy 112.309656 -32.629856) (xy 112.282986 -32.629856) (xy 112.274096 -32.63011) (xy 112.269524 -32.629856)
				(xy 112.050576 -32.629856) (xy 112.046004 -32.63011) (xy 112.036352 -32.629856) (xy 112.014762 -32.629856)
				(xy 112.014762 -32.76854) (xy 112.046004 -32.769556) (xy 112.050576 -32.769556) (xy 112.32388 -32.769556)
				(xy 112.328452 -32.769556) (xy 112.33658 -32.769556) (xy 112.364012 -32.769556)
				(arc
					(start 112.366806 -32.77235)
					(mid 112.444536 -32.797114)
					(end 112.51057 -32.844994)
				)
				(arc
					(start 112.51057 -32.844994)
					(mid 112.558221 -32.910829)
					(end 112.58296 -32.98825)
				)
				(xy 112.5855 -32.991044)
				(arc
					(start 112.5855 -33.015682)
					(mid 112.500425 -33.793703)
					(end 112.413288 -33.015936)
				)
				(arc
					(start 112.413288 -33.015936)
					(mid 112.405308 -32.989187)
					(end 112.389158 -32.966406)
				)
				(arc
					(start 112.389158 -32.966406)
					(mid 112.361306 -32.947796)
					(end 112.328452 -32.94126)
				)
				(xy 112.32388 -32.94126) (xy 112.050576 -32.94126) (xy 112.046004 -32.94126) (xy 112.032796 -32.94126)
				(xy 112.014762 -32.94126)
				(arc
					(start 112.014762 -33.399984)
					(mid 112.499902 -33.885124)
					(end 112.985042 -33.399984)
				)
			)
		)
	)
	(zone
		(layer "B.Cu")
		(hatch none 0.5)
		(connect_pads
			(clearance 0)
		)
		(min_thickness 0.25)
		(keepout
			(tracks allowed)
			(vias allowed)
			(pads allowed)
			(copperpour allowed)
			(footprints not_allowed)
		)
		(placement
			(enabled no)
			(sheetname "")
		)
		(fill
			(thermal_gap 0.5)
			(thermal_bridge_width 0.5)
			(island_removal_mode 0)
		)
		(polygon
			(pts
				(arc
					(start 121.664984 -34.854896)
					(mid 124.165106 -37.355018)
					(end 126.664974 -34.854896)
				)
				(arc
					(start 126.664974 -34.854896)
					(mid 124.165106 -32.355028)
					(end 121.664984 -34.854896)
				)
			)
		)
	)
	(zone
		(layer "B.Cu")
		(hatch none 0.5)
		(connect_pads
			(clearance 0)
		)
		(min_thickness 0.25)
		(keepout
			(tracks not_allowed)
			(vias allowed)
			(pads allowed)
			(copperpour not_allowed)
			(footprints allowed)
		)
		(placement
			(enabled no)
			(sheetname "")
		)
		(fill
			(thermal_gap 0.5)
			(thermal_bridge_width 0.5)
			(island_removal_mode 0)
		)
		(polygon
			(pts
				(arc
					(start 120.18518 -32.000444)
					(mid 119.700167 -31.51505)
					(end 119.2149 -32.00019)
				)
				(arc
					(start 119.2149 -32.45612)
					(mid 119.230477 -32.457859)
					(end 119.246142 -32.458406)
				)
				(xy 119.250714 -32.45866) (xy 119.469662 -32.45866)
				(arc
					(start 119.474234 -32.458406)
					(mid 119.527695 -32.447772)
					(end 119.57304 -32.417512)
				)
				(arc
					(start 119.57304 -32.417512)
					(mid 119.587749 -32.400305)
					(end 119.599456 -32.380936)
				)
				(arc
					(start 119.599456 -32.380936)
					(mid 119.710875 -31.606603)
					(end 119.778526 -32.386016)
				)
				(arc
					(start 119.778526 -32.386016)
					(mid 119.747355 -32.468437)
					(end 119.694452 -32.538924)
				)
				(arc
					(start 119.694452 -32.538924)
					(mid 119.610596 -32.598701)
					(end 119.511826 -32.627824)
				)
				(xy 119.509794 -32.629856) (xy 119.483124 -32.629856) (xy 119.474234 -32.63011) (xy 119.469662 -32.629856)
				(xy 119.250714 -32.629856) (xy 119.246142 -32.63011) (xy 119.23649 -32.629856) (xy 119.2149 -32.629856)
				(xy 119.2149 -32.76854) (xy 119.246142 -32.769556) (xy 119.250714 -32.769556) (xy 119.524018 -32.769556)
				(xy 119.52859 -32.769556) (xy 119.536718 -32.769556) (xy 119.56415 -32.769556)
				(arc
					(start 119.566944 -32.77235)
					(mid 119.644674 -32.797114)
					(end 119.710708 -32.844994)
				)
				(arc
					(start 119.710708 -32.844994)
					(mid 119.758359 -32.910829)
					(end 119.783098 -32.98825)
				)
				(xy 119.785892 -32.991044)
				(arc
					(start 119.785892 -33.015682)
					(mid 119.700941 -33.793703)
					(end 119.613426 -33.015936)
				)
				(arc
					(start 119.613426 -33.015936)
					(mid 119.605446 -32.989187)
					(end 119.589296 -32.966406)
				)
				(arc
					(start 119.589296 -32.966406)
					(mid 119.561444 -32.947796)
					(end 119.52859 -32.94126)
				)
				(xy 119.524018 -32.94126) (xy 119.250714 -32.94126) (xy 119.246142 -32.94126) (xy 119.232934 -32.94126)
				(xy 119.2149 -32.94126)
				(arc
					(start 119.2149 -33.399984)
					(mid 119.70004 -33.885124)
					(end 120.18518 -33.399984)
				)
			)
		)
	)
	(zone
		(layer "B.Cu")
		(hatch none 0.5)
		(connect_pads
			(clearance 0)
		)
		(min_thickness 0.25)
		(keepout
			(tracks allowed)
			(vias allowed)
			(pads allowed)
			(copperpour allowed)
			(footprints allowed)
		)
		(placement
			(enabled no)
			(sheetname "")
		)
		(fill
			(thermal_gap 0.5)
			(thermal_bridge_width 0.5)
			(island_removal_mode 0)
		)
		(polygon
			(pts
				(xy 191.008 -20.066) (xy 191.008 -18.9738) (xy 192.3796 -18.9738) (xy 192.3796 -20.066)
			)
		)
	)
	(zone
		(net "PCE_VDDH")
		(layer "B.Cu")
		(hatch none 0.5)
		(connect_pads
			(clearance 0.5)
		)
		(min_thickness 0.25)
		(fill yes
			(thermal_gap 0.5)
			(thermal_bridge_width 0.5)
			(island_removal_mode 0)
		)
		(polygon
			(pts
				(xy 201.480166 -88.968834) (xy 200.453244 -89.995756) (xy 200.453244 -92.256864) (xy 200.819004 -92.622624)
				(xy 206.813404 -92.622624) (xy 206.889604 -92.698824) (xy 207.535018 -92.698824) (xy 207.696054 -92.537788)
				(xy 207.696054 -91.927934) (xy 207.582008 -91.813888) (xy 206.938626 -91.813888) (xy 206.197962 -91.073224)
				(xy 204.507592 -91.073224) (xy 204.28712 -90.852752) (xy 204.28712 -90.005154) (xy 204.277722 -89.995756)
				(xy 204.277722 -89.413334) (xy 203.833222 -88.968834)
			)
		)
		(polygon
			(pts
				(xy 207.575404 -92.038424) (xy 207.372204 -92.038424) (xy 207.372204 -92.241624) (xy 207.575404 -92.241624)
			)
		)
		(polygon
			(pts
				(xy 207.016604 -92.038424) (xy 206.813404 -92.038424) (xy 206.813404 -92.241624) (xy 207.016604 -92.241624)
			)
		)
		(polygon
			(pts
				(xy 202.393804 -91.606624) (xy 202.190604 -91.606624) (xy 202.190604 -91.809824) (xy 202.393804 -91.809824)
			)
		)
		(polygon
			(pts
				(xy 201.530204 -91.606624) (xy 201.327004 -91.606624) (xy 201.327004 -91.809824) (xy 201.530204 -91.809824)
			)
		)
	)
	(zone
		(layer "B.Cu")
		(hatch none 0.5)
		(connect_pads
			(clearance 0)
		)
		(min_thickness 0.25)
		(keepout
			(tracks allowed)
			(vias allowed)
			(pads allowed)
			(copperpour allowed)
			(footprints allowed)
		)
		(placement
			(enabled no)
			(sheetname "")
		)
		(fill
			(thermal_gap 0.5)
			(thermal_bridge_width 0.5)
			(island_removal_mode 0)
		)
		(polygon
			(pts
				(xy 191.6811 -75.8444) (xy 190.9953 -75.8444) (xy 190.9064 -75.7555) (xy 190.9064 -74.3331) (xy 191.5541 -73.6854)
				(xy 200.1266 -73.6854) (xy 200.4314 -73.9902) (xy 200.4314 -76.327) (xy 199.4916 -77.2668) (xy 199.1106 -77.2668)
				(xy 198.5899 -76.7461) (xy 198.2851 -76.4413) (xy 197.7009 -76.4413) (xy 197.3834 -76.7588) (xy 196.4817 -76.7588)
				(xy 196.3547 -76.6318) (xy 196.3547 -75.3872) (xy 196.0753 -75.1078) (xy 195.5419 -75.1078) (xy 195.2117 -75.438)
				(xy 195.2117 -77.5081) (xy 195.0212 -77.6986) (xy 194.5132 -77.6986) (xy 194.31 -77.4954) (xy 194.31 -76.6445)
				(xy 194.2338 -76.5683) (xy 193.7639 -76.5683) (xy 193.7258 -76.5302) (xy 193.7258 -75.9841) (xy 193.9163 -75.7936)
				(xy 193.9163 -75.1459) (xy 193.8655 -75.0951) (xy 192.9003 -75.0951) (xy 192.3415 -75.6539) (xy 192.3415 -77.9272)
				(xy 192.2653 -78.0034) (xy 192.0875 -78.0034) (xy 191.8208 -77.7367) (xy 191.8208 -75.9841)
			)
		)
	)
	(zone
		(layer "B.Cu")
		(hatch none 0.5)
		(connect_pads
			(clearance 0)
		)
		(min_thickness 0.25)
		(keepout
			(tracks not_allowed)
			(vias allowed)
			(pads allowed)
			(copperpour not_allowed)
			(footprints allowed)
		)
		(placement
			(enabled no)
			(sheetname "")
		)
		(fill
			(thermal_gap 0.5)
			(thermal_bridge_width 0.5)
			(island_removal_mode 0)
		)
		(polygon
			(pts
				(arc
					(start 77.667358 -80.109568)
					(mid 77.283818 -79.726028)
					(end 76.900278 -80.109568)
				)
				(arc
					(start 76.900278 -80.998314)
					(mid 77.283691 -81.382108)
					(end 77.667358 -80.998568)
				)
				(xy 77.667358 -80.795368) (xy 77.4954 -80.795368)
				(arc
					(start 77.490828 -80.795368)
					(mid 77.475725 -80.796345)
					(end 77.460856 -80.799178)
				)
				(arc
					(start 77.460856 -80.799178)
					(mid 77.19854 -81.251471)
					(end 77.262736 -80.73263)
				)
				(arc
					(start 77.262736 -80.73263)
					(mid 77.347599 -80.661086)
					(end 77.452982 -80.626204)
				)
				(xy 77.455268 -80.623664) (xy 77.482192 -80.623664) (xy 77.490828 -80.623664) (xy 77.4954 -80.623664)
				(xy 77.667358 -80.623664) (xy 77.667358 -80.483964) (xy 77.4954 -80.483964) (xy 77.490828 -80.484218)
				(xy 77.482192 -80.483964) (xy 77.455268 -80.483964)
				(arc
					(start 77.452982 -80.481678)
					(mid 77.347756 -80.446901)
					(end 77.26299 -80.375506)
				)
				(arc
					(start 77.26299 -80.375506)
					(mid 77.198276 -79.856838)
					(end 77.46111 -80.308704)
				)
				(arc
					(start 77.46111 -80.308704)
					(mid 77.47585 -80.311541)
					(end 77.490828 -80.312514)
				)
				(xy 77.4954 -80.312768) (xy 77.667358 -80.312768)
			)
		)
	)
	(zone
		(net "GND")
		(layer "B.Cu")
		(hatch none 0.5)
		(connect_pads
			(clearance 0.5)
		)
		(min_thickness 0.25)
		(fill yes
			(thermal_gap 0.5)
			(thermal_bridge_width 0.5)
			(island_removal_mode 0)
		)
		(polygon
			(pts
				(xy 182.3466 -80.09128) (xy 182.0799 -80.35798) (xy 182.0799 -81.2546) (xy 182.17388 -81.34858)
				(xy 184.80786 -81.34858) (xy 184.91454 -81.2419) (xy 184.91454 -80.15224) (xy 184.85358 -80.09128)
			)
		)
		(polygon
			(pts
				(xy 183.94426 -80.63484) (xy 183.74106 -80.63484) (xy 183.74106 -80.83804) (xy 183.94426 -80.83804)
				(xy 184.0357 -80.84312) (xy 184.2389 -80.84312) (xy 184.2389 -80.63992) (xy 184.0357 -80.63992)
			)
		)
		(polygon
			(pts
				(xy 183.23306 -80.63484) (xy 182.77586 -80.63484) (xy 182.77586 -80.83804) (xy 183.23306 -80.83804)
			)
		)
	)
	(zone
		(layer "B.Cu")
		(hatch none 0.5)
		(connect_pads
			(clearance 0)
		)
		(min_thickness 0.25)
		(keepout
			(tracks allowed)
			(vias allowed)
			(pads allowed)
			(copperpour allowed)
			(footprints allowed)
		)
		(placement
			(enabled no)
			(sheetname "")
		)
		(fill
			(thermal_gap 0.5)
			(thermal_bridge_width 0.5)
			(island_removal_mode 0)
		)
		(polygon
			(pts
				(xy 159.258 -55.4482) (xy 171.1706 -55.4482) (xy 171.9326 -54.6862) (xy 171.9326 -52.5018) (xy 171.5135 -52.0827)
				(xy 160.3629 -52.0827) (xy 159.258 -53.1876)
			)
		)
	)
	(zone
		(net "AGND_P0V975")
		(layer "B.Cu")
		(hatch none 0.5)
		(connect_pads
			(clearance 0.5)
		)
		(min_thickness 0.25)
		(fill yes
			(thermal_gap 0.5)
			(thermal_bridge_width 0.5)
			(island_removal_mode 0)
		)
		(polygon
			(pts
				(xy 185.674 -121.4882) (xy 185.674 -123.029472) (xy 185.578496 -123.124976) (xy 185.578496 -124.078746)
				(xy 185.75655 -124.2568) (xy 189.4332 -124.2568) (xy 189.4332 -123.7996) (xy 189.2808 -123.6472)
				(xy 186.944 -123.6472) (xy 186.5122 -123.2154) (xy 186.5122 -122.936) (xy 186.2836 -122.7074) (xy 186.2836 -121.7422)
				(xy 186.0296 -121.4882)
			)
		)
		(polygon
			(pts
				(xy 186.6646 -123.592336) (xy 186.4614 -123.592336) (xy 186.4614 -123.795536) (xy 186.6646 -123.795536)
			)
		)
	)
	(zone
		(net "P5V_STBY")
		(layer "B.Cu")
		(hatch none 0.5)
		(connect_pads
			(clearance 0.5)
		)
		(min_thickness 0.25)
		(fill yes
			(thermal_gap 0.5)
			(thermal_bridge_width 0.5)
			(island_removal_mode 0)
		)
		(polygon
			(pts
				(xy 80.7974 -1.1684) (xy 75.7682 -6.1976) (xy 75.7682 -25.944068) (xy 82.546952 -32.72282) (xy 82.546952 -49.660048)
				(xy 82.3468 -49.8602) (xy 81.4324 -49.8602) (xy 81.3054 -49.9872) (xy 81.3054 -51.6382) (xy 81.407 -51.7398)
				(xy 83.693 -51.7398) (xy 85.33638 -50.09642) (xy 85.33638 -47.67834) (xy 86.05647 -46.95825) (xy 86.05647 -41.511474)
				(xy 86.935818 -40.632126) (xy 86.935818 -34.916618) (xy 86.935818 -32.986218) (xy 85.5599 -31.6103)
				(xy 85.471 -31.5214) (xy 85.471 -30.0228) (xy 85.5599 -29.9339) (xy 86.5378 -28.956) (xy 86.5378 -28.321)
				(xy 81.457292 -23.240492) (xy 81.457292 -12.466066) (xy 86.059264 -7.864094) (xy 87.727028 -7.864094)
				(xy 91.133676 -4.4577) (xy 122.7709 -4.4577) (xy 124.9934 -6.6802) (xy 127.0254 -6.6802) (xy 127.0381 -6.6675)
				(xy 141.2875 -6.6675) (xy 144.877028 -10.257028) (xy 152.694132 -10.257028) (xy 153.547064 -9.404096)
				(xy 153.547064 -1.7653) (xy 152.950164 -1.1684)
			)
		)
	)
	(zone
		(layer "B.Cu")
		(hatch none 0.5)
		(connect_pads
			(clearance 0)
		)
		(min_thickness 0.25)
		(keepout
			(tracks not_allowed)
			(vias allowed)
			(pads allowed)
			(copperpour not_allowed)
			(footprints allowed)
		)
		(placement
			(enabled no)
			(sheetname "")
		)
		(fill
			(thermal_gap 0.5)
			(thermal_bridge_width 0.5)
			(island_removal_mode 0)
		)
		(polygon
			(pts
				(arc
					(start 78.505558 -76.909168)
					(mid 78.122018 -76.525628)
					(end 77.738478 -76.909168)
				)
				(arc
					(start 77.738478 -77.797914)
					(mid 78.121891 -78.181708)
					(end 78.505558 -77.798168)
				)
				(xy 78.505558 -77.594968) (xy 78.415642 -77.594968)
				(arc
					(start 78.41107 -77.594968)
					(mid 78.363245 -77.600738)
					(end 78.318106 -77.617574)
				)
				(arc
					(start 78.318106 -77.617574)
					(mid 78.003361 -78.036772)
					(end 78.146402 -77.532484)
				)
				(arc
					(start 78.146402 -77.532484)
					(mid 78.25079 -77.459129)
					(end 78.373732 -77.425042)
				)
				(xy 78.37551 -77.423264) (xy 78.401418 -77.423264) (xy 78.41107 -77.423264) (xy 78.415642 -77.423264)
				(xy 78.505558 -77.423264) (xy 78.505558 -77.283564) (xy 78.415388 -77.283564) (xy 78.410816 -77.283818)
				(xy 78.401164 -77.283564) (xy 78.375256 -77.283564)
				(arc
					(start 78.373478 -77.28204)
					(mid 78.250807 -77.248026)
					(end 78.146656 -77.174852)
				)
				(arc
					(start 78.146656 -77.174852)
					(mid 78.003607 -76.670057)
					(end 78.31836 -77.089762)
				)
				(arc
					(start 78.31836 -77.089762)
					(mid 78.363263 -77.106402)
					(end 78.410816 -77.112114)
				)
				(xy 78.415388 -77.112368) (xy 78.505558 -77.112368)
			)
		)
	)
	(zone
		(layer "B.Cu")
		(hatch none 0.5)
		(connect_pads
			(clearance 0)
		)
		(min_thickness 0.25)
		(keepout
			(tracks not_allowed)
			(vias allowed)
			(pads allowed)
			(copperpour not_allowed)
			(footprints allowed)
		)
		(placement
			(enabled no)
			(sheetname "")
		)
		(fill
			(thermal_gap 0.5)
			(thermal_bridge_width 0.5)
			(island_removal_mode 0)
		)
		(polygon
			(pts
				(arc
					(start 191.57569 -21.0566)
					(mid 191.594386 -21.079002)
					(end 191.60109 -21.1074)
				)
				(arc
					(start 191.60109 -21.3106)
					(mid 191.594386 -21.338998)
					(end 191.57569 -21.3614)
				)
				(arc
					(start 191.80429 -21.3614)
					(mid 191.785594 -21.338998)
					(end 191.77889 -21.3106)
				)
				(arc
					(start 191.77889 -21.1074)
					(mid 191.785594 -21.079002)
					(end 191.80429 -21.0566)
				)
			)
		)
	)
	(zone
		(net "GND")
		(layer "B.Cu")
		(hatch none 0.5)
		(connect_pads
			(clearance 0.5)
		)
		(min_thickness 0.25)
		(fill yes
			(thermal_gap 0.5)
			(thermal_bridge_width 0.5)
			(island_removal_mode 0)
		)
		(polygon
			(pts
				(xy 46.5582 -139.7635) (xy 46.4693 -139.8524) (xy 46.4693 -141.19225) (xy 46.27245 -141.3891) (xy 46.27245 -143.04518)
				(xy 46.501558 -143.274288) (xy 46.501558 -143.670528) (xy 46.37913 -143.792956) (xy 45.589952 -143.792956)
				(xy 45.42917 -143.953738) (xy 45.42917 -145.421096) (xy 45.66158 -145.653506) (xy 45.66158 -146.707606)
				(xy 45.81652 -146.862546) (xy 47.84598 -146.862546) (xy 48.25492 -147.271486) (xy 48.25492 -148.452586)
				(xy 48.34382 -148.541486) (xy 50.156364 -148.541486) (xy 50.320956 -148.376894) (xy 50.320956 -147.628864)
				(xy 50.17262 -147.480528) (xy 50.17262 -146.25701) (xy 50.58918 -145.84045) (xy 50.597816 -145.84045)
				(xy 50.799746 -145.63852) (xy 50.799746 -144.052544) (xy 50.457354 -143.710152) (xy 49.740566 -143.710152)
				(xy 49.57572 -143.545306) (xy 49.57572 -142.768828) (xy 49.40808 -142.601188) (xy 48.9077 -142.601188)
				(xy 48.76546 -142.458948) (xy 48.76546 -141.58849) (xy 48.58131 -141.40434) (xy 47.65294 -141.40434)
				(xy 47.371 -141.1224) (xy 47.371 -140.8176) (xy 47.5742 -140.6144) (xy 47.5742 -139.8397) (xy 47.498 -139.7635)
			)
		)
		(polygon
			(pts
				(xy 49.71542 -147.66036) (xy 49.51222 -147.66036) (xy 49.51222 -147.86356) (xy 49.71542 -147.86356)
			)
		)
		(polygon
			(pts
				(xy 49.324006 -147.45335) (xy 49.120806 -147.45335) (xy 49.120806 -147.65655) (xy 49.324006 -147.65655)
			)
		)
		(polygon
			(pts
				(xy 49.925986 -147.014438) (xy 49.722786 -147.014438) (xy 49.722786 -147.217638) (xy 49.925986 -147.217638)
			)
		)
		(polygon
			(pts
				(xy 49.062386 -147.014438) (xy 48.859186 -147.014438) (xy 48.859186 -147.217638) (xy 49.062386 -147.217638)
			)
		)
		(polygon
			(pts
				(xy 49.925986 -146.150838) (xy 49.722786 -146.150838) (xy 49.722786 -146.354038) (xy 49.925986 -146.354038)
			)
		)
		(polygon
			(pts
				(xy 49.062386 -146.150838) (xy 48.859186 -146.150838) (xy 48.859186 -146.354038) (xy 49.062386 -146.354038)
			)
		)
		(polygon
			(pts
				(xy 46.63567 -145.717514) (xy 46.43247 -145.717514) (xy 46.43247 -145.920714) (xy 46.63567 -145.920714)
			)
		)
		(polygon
			(pts
				(xy 46.544992 -144.665954) (xy 46.341792 -144.665954) (xy 46.341792 -144.869154) (xy 46.544992 -144.869154)
			)
		)
		(polygon
			(pts
				(xy 50.39106 -144.272) (xy 50.18786 -144.272) (xy 50.18786 -144.4752) (xy 50.39106 -144.4752)
			)
		)
		(polygon
			(pts
				(xy 49.83226 -144.272) (xy 49.62906 -144.272) (xy 49.62906 -144.4752) (xy 49.83226 -144.4752)
			)
		)
		(polygon
			(pts
				(xy 48.0441 -142.3797) (xy 47.8409 -142.3797) (xy 47.8409 -142.5829) (xy 48.0441 -142.5829)
			)
		)
		(polygon
			(pts
				(xy 47.5742 -142.367) (xy 47.371 -142.367) (xy 47.371 -142.5702) (xy 47.5742 -142.5702)
			)
		)
		(polygon
			(pts
				(xy 46.7106 -142.367) (xy 46.5074 -142.367) (xy 46.5074 -142.5702) (xy 46.7106 -142.5702)
			)
		)
		(polygon
			(pts
				(xy 48.0441 -141.5161) (xy 47.8409 -141.5161) (xy 47.8409 -141.7193) (xy 48.0441 -141.7193)
			)
		)
		(polygon
			(pts
				(xy 47.5742 -141.5034) (xy 47.371 -141.5034) (xy 47.371 -141.7066) (xy 47.5742 -141.7066)
			)
		)
		(polygon
			(pts
				(xy 46.7106 -141.5034) (xy 46.5074 -141.5034) (xy 46.5074 -141.7066) (xy 46.7106 -141.7066)
			)
		)
	)
	(zone
		(layer "B.Cu")
		(hatch none 0.5)
		(connect_pads
			(clearance 0)
		)
		(min_thickness 0.25)
		(keepout
			(tracks allowed)
			(vias allowed)
			(pads allowed)
			(copperpour allowed)
			(footprints not_allowed)
		)
		(placement
			(enabled no)
			(sheetname "")
		)
		(fill
			(thermal_gap 0.5)
			(thermal_bridge_width 0.5)
			(island_removal_mode 0)
		)
		(polygon
			(pts
				(arc
					(start 37.69995 -169.999914)
					(mid 41.450006 -173.74997)
					(end 45.200062 -169.999914)
				)
				(arc
					(start 45.200062 -169.999914)
					(mid 41.450006 -166.249858)
					(end 37.69995 -169.999914)
				)
			)
		)
	)
	(zone
		(net "GND")
		(layer "B.Cu")
		(hatch none 0.5)
		(connect_pads
			(clearance 0.5)
		)
		(min_thickness 0.25)
		(fill yes
			(thermal_gap 0.5)
			(thermal_bridge_width 0.5)
			(island_removal_mode 0)
		)
		(polygon
			(pts
				(xy 191.1858 -45.8978) (xy 191.0588 -46.0248) (xy 191.0588 -47.4218) (xy 190.8556 -47.625) (xy 190.8556 -48.8696)
				(xy 189.8142 -49.911) (xy 189.8142 -51.689) (xy 190.1952 -52.07) (xy 192.7352 -52.07) (xy 192.8114 -51.9938)
				(xy 192.8114 -51.816) (xy 192.024 -51.0286) (xy 192.024 -47.8282) (xy 192.3034 -47.5488) (xy 192.3288 -47.5488)
				(xy 192.3796 -47.498) (xy 192.7606 -47.498) (xy 192.8368 -47.4218) (xy 192.8368 -46.6598) (xy 192.7352 -46.5582)
				(xy 192.6336 -46.5582) (xy 191.9732 -45.8978)
			)
		)
		(polygon
			(pts
				(xy 192.0748 -47.371) (xy 191.8716 -47.371) (xy 191.8716 -47.5742) (xy 192.0748 -47.5742)
			)
		)
		(polygon
			(pts
				(xy 192.0748 -46.5074) (xy 191.8716 -46.5074) (xy 191.8716 -46.7106) (xy 192.0748 -46.7106)
			)
		)
	)
	(zone
		(layer "B.Cu")
		(hatch none 0.5)
		(connect_pads
			(clearance 0)
		)
		(min_thickness 0.25)
		(keepout
			(tracks not_allowed)
			(vias allowed)
			(pads allowed)
			(copperpour not_allowed)
			(footprints allowed)
		)
		(placement
			(enabled no)
			(sheetname "")
		)
		(fill
			(thermal_gap 0.5)
			(thermal_bridge_width 0.5)
			(island_removal_mode 0)
		)
		(polygon
			(pts
				(xy 180.068474 -18.57248) (xy 179.970176 -18.43659) (xy 179.928774 -18.415762) (xy 179.927504 -18.41627)
				(xy 179.901088 -18.402046) (xy 179.874418 -18.388584) (xy 179.87391 -18.387314) (xy 179.811934 -18.354294)
				(xy 179.799488 -18.354294) (xy 179.78501 -18.339816) (xy 179.767992 -18.330926)
				(arc
					(start 179.766976 -18.327116)
					(mid 179.69851 -18.227499)
					(end 179.700174 -18.106644)
				)
				(xy 179.698904 -18.10258) (xy 179.713636 -18.075402)
				(arc
					(start 179.757324 -17.993868)
					(mid 180.179932 -17.364147)
					(end 179.889404 -18.064734)
				)
				(arc
					(start 179.845716 -18.146268)
					(mid 179.840368 -18.176721)
					(end 179.854098 -18.204434)
				)
				(xy 179.861718 -18.204434) (xy 179.875942 -18.218404) (xy 179.920646 -18.24228) (xy 179.947824 -18.257012)
				(xy 179.973224 -18.270474) (xy 180.043582 -18.30578) (xy 180.062632 -18.308828) (xy 180.070252 -18.319242)
				(xy 180.081428 -18.32483) (xy 180.087778 -18.343372) (xy 180.147214 -18.425668)
				(arc
					(start 180.413406 -17.92859)
					(mid 180.225704 -17.284948)
					(end 179.583334 -17.476978)
				)
				(arc
					(start 178.833526 -18.877026)
					(mid 179.027074 -19.516598)
					(end 179.666646 -19.32305)
				)
				(xy 179.855114 -18.97126) (xy 179.699158 -18.755614) (xy 179.687474 -18.749772) (xy 179.68722 -18.74901)
				(xy 179.681124 -18.745962) (xy 179.68087 -18.745454)
				(arc
					(start 179.603146 -18.703798)
					(mid 179.565576 -18.700241)
					(end 179.536344 -18.724118)
				)
				(arc
					(start 179.492402 -18.80616)
					(mid 179.069783 -19.435399)
					(end 179.360322 -18.735294)
				)
				(xy 179.418996 -18.626074)
				(arc
					(start 179.422806 -18.624804)
					(mid 179.522403 -18.556658)
					(end 179.643024 -18.55851)
				)
				(xy 179.646834 -18.55724) (xy 179.673758 -18.571718) (xy 179.674266 -18.571972) (xy 179.754276 -18.614644)
				(xy 179.75834 -18.613882) (xy 179.775612 -18.625312) (xy 179.791614 -18.627852) (xy 179.799234 -18.638266)
				(xy 179.81041 -18.643854) (xy 179.810664 -18.644616) (xy 179.810918 -18.644616) (xy 179.813712 -18.653252)
				(xy 179.81676 -18.662396) (xy 179.933854 -18.824194)
			)
		)
	)
	(zone
		(net "P0V975")
		(layer "B.Cu")
		(hatch none 0.5)
		(connect_pads
			(clearance 0.5)
		)
		(min_thickness 0.25)
		(fill yes
			(thermal_gap 0.5)
			(thermal_bridge_width 0.5)
			(island_removal_mode 0)
		)
		(polygon
			(pts
				(xy 187.6552 -59.23915) (xy 187.594748 -59.299348) (xy 187.594748 -60.4647) (xy 187.836048 -60.706)
				(xy 188.2267 -60.706) (xy 188.41085 -60.89015) (xy 188.41085 -65.30975) (xy 188.145674 -65.574926)
				(xy 187.190126 -65.574926) (xy 187.093352 -65.6717) (xy 187.093352 -66.970148) (xy 187.198 -67.07505)
				(xy 188.24575 -67.07505) (xy 188.4045 -67.2338) (xy 188.4045 -67.5767) (xy 188.5823 -67.7545) (xy 188.9252 -67.7545)
				(xy 189.0395 -67.6402) (xy 189.0395 -66.1924) (xy 189.21095 -66.02095) (xy 189.21095 -60.85205)
				(xy 189.3824 -60.6806) (xy 189.9031 -60.6806) (xy 190.0809 -60.8584) (xy 190.0809 -67.5894) (xy 189.73165 -67.93865)
				(xy 189.73165 -68.68795) (xy 190.0428 -68.9991) (xy 190.0428 -69.2912) (xy 190.1698 -69.4182) (xy 190.4873 -69.4182)
				(xy 190.6651 -69.2404) (xy 190.6651 -67.8688) (xy 190.7794 -67.7545) (xy 190.7794 -60.8203) (xy 190.8937 -60.706)
				(xy 191.6049 -60.706) (xy 191.7065 -60.8076) (xy 191.7065 -66.1162) (xy 191.8462 -66.2559) (xy 191.8462 -67.0941)
				(xy 191.6049 -67.3354) (xy 191.6049 -69.1896) (xy 191.8335 -69.4182) (xy 192.1256 -69.4182) (xy 192.3415 -69.2023)
				(xy 192.3415 -67.31) (xy 192.6082 -67.0433) (xy 192.6082 -66.2686) (xy 192.3161 -65.9765) (xy 192.3161 -60.8711)
				(xy 192.4812 -60.706) (xy 193.0908 -60.706) (xy 193.3067 -60.9219) (xy 193.3067 -67.7418) (xy 192.9511 -68.0974)
				(xy 192.9511 -68.58635) (xy 193.0781 -68.71335) (xy 193.60515 -68.71335) (xy 193.675 -68.6435) (xy 193.675 -67.945)
				(xy 193.929 -67.691) (xy 193.929 -61.4553) (xy 194.0814 -61.3029) (xy 194.5894 -61.3029) (xy 194.691 -61.2013)
				(xy 194.691 -60.7949) (xy 194.6021 -60.706) (xy 194.056 -60.706) (xy 193.929 -60.579) (xy 193.929 -59.4233)
				(xy 193.8655 -59.3598) (xy 192.5066 -59.3598) (xy 192.4304 -59.436) (xy 192.4304 -59.6646) (xy 192.1637 -59.9313)
				(xy 189.357 -59.9313) (xy 189.1411 -59.7154) (xy 189.1411 -59.309) (xy 189.07125 -59.23915)
			)
		)
		(polygon
			(pts
				(xy 190.4619 -68.5038) (xy 190.2587 -68.5038) (xy 190.2587 -68.707) (xy 190.4619 -68.707)
			)
		)
		(polygon
			(pts
				(xy 190.4619 -67.8942) (xy 190.2587 -67.8942) (xy 190.2587 -68.0974) (xy 190.4619 -68.0974)
			)
		)
		(polygon
			(pts
				(xy 192.024 -65.4558) (xy 191.8208 -65.4558) (xy 191.8208 -65.659) (xy 192.024 -65.659)
			)
		)
		(polygon
			(pts
				(xy 190.4365 -65.4558) (xy 190.2333 -65.4558) (xy 190.2333 -65.659) (xy 190.4365 -65.659)
			)
		)
		(polygon
			(pts
				(xy 188.8744 -65.4558) (xy 188.6712 -65.4558) (xy 188.6712 -65.659) (xy 188.8744 -65.659)
			)
		)
		(polygon
			(pts
				(xy 192.024 -64.897) (xy 191.8208 -64.897) (xy 191.8208 -65.3034) (xy 192.024 -65.3034)
			)
		)
		(polygon
			(pts
				(xy 190.4365 -64.897) (xy 190.2333 -64.897) (xy 190.2333 -65.3034) (xy 190.4365 -65.3034)
			)
		)
		(polygon
			(pts
				(xy 188.8744 -64.897) (xy 188.6712 -64.897) (xy 188.6712 -65.3034) (xy 188.8744 -65.3034)
			)
		)
		(polygon
			(pts
				(xy 192.024 -64.5414) (xy 191.8208 -64.5414) (xy 191.8208 -64.7446) (xy 192.024 -64.7446)
			)
		)
		(polygon
			(pts
				(xy 190.4365 -64.5414) (xy 190.2333 -64.5414) (xy 190.2333 -64.7446) (xy 190.4365 -64.7446)
			)
		)
		(polygon
			(pts
				(xy 188.8744 -64.5414) (xy 188.6712 -64.5414) (xy 188.6712 -64.7446) (xy 188.8744 -64.7446)
			)
		)
		(polygon
			(pts
				(xy 192.0367 -63.8556) (xy 191.8335 -63.8556) (xy 191.8335 -64.0588) (xy 192.0367 -64.0588)
			)
		)
		(polygon
			(pts
				(xy 190.4746 -63.8556) (xy 190.2714 -63.8556) (xy 190.2714 -64.0588) (xy 190.4746 -64.0588)
			)
		)
		(polygon
			(pts
				(xy 192.0367 -63.2968) (xy 191.8335 -63.2968) (xy 191.8335 -63.7032) (xy 192.0367 -63.7032)
			)
		)
		(polygon
			(pts
				(xy 190.4746 -63.2968) (xy 190.2714 -63.2968) (xy 190.2714 -63.7032) (xy 190.4746 -63.7032)
			)
		)
		(polygon
			(pts
				(xy 192.0367 -62.9412) (xy 191.8335 -62.9412) (xy 191.8335 -63.1444) (xy 192.0367 -63.1444)
			)
		)
		(polygon
			(pts
				(xy 190.4746 -62.9412) (xy 190.2714 -62.9412) (xy 190.2714 -63.1444) (xy 190.4746 -63.1444)
			)
		)
		(polygon
			(pts
				(xy 188.8871 -62.2681) (xy 188.6839 -62.2681) (xy 188.6839 -62.4713) (xy 188.8871 -62.4713)
			)
		)
		(polygon
			(pts
				(xy 190.450978 -62.25667) (xy 190.247778 -62.25667) (xy 190.247778 -62.45987) (xy 190.450978 -62.45987)
			)
		)
		(polygon
			(pts
				(xy 192.024 -62.2554) (xy 191.8208 -62.2554) (xy 191.8208 -62.4586) (xy 192.024 -62.4586)
			)
		)
		(polygon
			(pts
				(xy 192.024 -61.6966) (xy 191.8208 -61.6966) (xy 191.8208 -62.103) (xy 192.024 -62.103)
			)
		)
		(polygon
			(pts
				(xy 190.4492 -61.6966) (xy 190.246 -61.6966) (xy 190.246 -61.8998) (xy 190.247778 -61.90107) (xy 190.247778 -62.10427)
				(xy 190.450978 -62.10427) (xy 190.450978 -61.90107) (xy 190.4492 -61.8998)
			)
		)
		(polygon
			(pts
				(xy 188.8871 -61.6966) (xy 188.6839 -61.6966) (xy 188.6839 -62.1157) (xy 188.8871 -62.1157)
			)
		)
		(polygon
			(pts
				(xy 192.024 -61.341) (xy 191.8208 -61.341) (xy 191.8208 -61.5442) (xy 192.024 -61.5442)
			)
		)
		(polygon
			(pts
				(xy 190.4492 -61.341) (xy 190.246 -61.341) (xy 190.246 -61.5442) (xy 190.4492 -61.5442)
			)
		)
		(polygon
			(pts
				(xy 188.8871 -61.341) (xy 188.6839 -61.341) (xy 188.6839 -61.5442) (xy 188.8871 -61.5442)
			)
		)
	)
	(zone
		(layer "B.Cu")
		(hatch none 0.5)
		(connect_pads
			(clearance 0)
		)
		(min_thickness 0.25)
		(keepout
			(tracks allowed)
			(vias allowed)
			(pads allowed)
			(copperpour allowed)
			(footprints allowed)
		)
		(placement
			(enabled no)
			(sheetname "")
		)
		(fill
			(thermal_gap 0.5)
			(thermal_bridge_width 0.5)
			(island_removal_mode 0)
		)
		(polygon
			(pts
				(xy 189.3824 -81.788) (xy 189.3824 -80.4926) (xy 190.4746 -80.4926) (xy 190.4746 -81.788)
			)
		)
	)
	(zone
		(layer "B.Cu")
		(hatch none 0.5)
		(connect_pads
			(clearance 0)
		)
		(min_thickness 0.25)
		(keepout
			(tracks not_allowed)
			(vias allowed)
			(pads allowed)
			(copperpour not_allowed)
			(footprints allowed)
		)
		(placement
			(enabled no)
			(sheetname "")
		)
		(fill
			(thermal_gap 0.5)
			(thermal_bridge_width 0.5)
			(island_removal_mode 0)
		)
		(polygon
			(pts
				(arc
					(start 227.24999 -110.000034)
					(mid 222.499936 -105.24998)
					(end 217.749882 -110.000034)
				)
				(arc
					(start 217.749882 -110.000034)
					(mid 222.499936 -114.750088)
					(end 227.24999 -110.000034)
				)
			)
		)
	)
	(zone
		(net "P1V2_STBY")
		(layer "B.Cu")
		(hatch none 0.5)
		(connect_pads
			(clearance 0.5)
		)
		(min_thickness 0.25)
		(fill yes
			(thermal_gap 0.5)
			(thermal_bridge_width 0.5)
			(island_removal_mode 0)
		)
		(polygon
			(pts
				(xy 14.6812 -145.8087) (xy 14.6177 -145.8722) (xy 14.6177 -146.6723) (xy 14.40815 -146.88185) (xy 13.53185 -146.88185)
				(xy 13.31595 -147.09775) (xy 13.31595 -147.97405) (xy 13.1064 -148.1836) (xy 13.1064 -149.987) (xy 13.4239 -150.3045)
				(xy 14.8844 -150.3045) (xy 15.7988 -149.3901) (xy 15.7988 -147.4851) (xy 15.9766 -147.3073) (xy 17.1831 -147.3073)
				(xy 17.5006 -146.9898) (xy 17.5006 -146.3802) (xy 16.9291 -145.8087)
			)
		)
		(polygon
			(pts
				(xy 16.8783 -146.8628) (xy 16.6751 -146.8628) (xy 16.6751 -147.066) (xy 16.8783 -147.066)
			)
		)
		(polygon
			(pts
				(xy 16.0147 -146.8628) (xy 15.8115 -146.8628) (xy 15.8115 -147.066) (xy 16.0147 -147.066)
			)
		)
		(polygon
			(pts
				(xy 15.24 -146.4437) (xy 15.0368 -146.4437) (xy 15.0368 -146.6469) (xy 15.24 -146.6469)
			)
		)
		(polygon
			(pts
				(xy 16.0147 -145.9992) (xy 15.8115 -145.9992) (xy 15.8115 -146.2024) (xy 16.0147 -146.2024)
			)
		)
	)
	(zone
		(layer "B.Cu")
		(hatch none 0.5)
		(connect_pads
			(clearance 0)
		)
		(min_thickness 0.25)
		(keepout
			(tracks not_allowed)
			(vias allowed)
			(pads allowed)
			(copperpour not_allowed)
			(footprints allowed)
		)
		(placement
			(enabled no)
			(sheetname "")
		)
		(fill
			(thermal_gap 0.5)
			(thermal_bridge_width 0.5)
			(island_removal_mode 0)
		)
		(polygon
			(pts
				(xy 133.614922 -36.230052) (xy 133.614922 -36.368736) (xy 133.646164 -36.369752) (xy 133.650736 -36.369752)
				(xy 133.92404 -36.369752) (xy 133.928612 -36.369752) (xy 133.93674 -36.369752) (xy 133.964172 -36.369752)
				(arc
					(start 133.966966 -36.372546)
					(mid 134.044696 -36.39731)
					(end 134.11073 -36.44519)
				)
				(arc
					(start 134.11073 -36.44519)
					(mid 134.158381 -36.511025)
					(end 134.18312 -36.588446)
				)
				(xy 134.18566 -36.59124)
				(arc
					(start 134.18566 -36.615878)
					(mid 134.100585 -37.393899)
					(end 134.013448 -36.616132)
				)
				(arc
					(start 134.013448 -36.616132)
					(mid 134.005468 -36.589383)
					(end 133.989318 -36.566602)
				)
				(arc
					(start 133.989318 -36.566602)
					(mid 133.961466 -36.547992)
					(end 133.928612 -36.541456)
				)
				(xy 133.92404 -36.541456) (xy 133.650736 -36.541456) (xy 133.646164 -36.541456) (xy 133.632956 -36.541456)
				(xy 133.614922 -36.541456)
				(arc
					(start 133.614922 -37.00018)
					(mid 134.100062 -37.48532)
					(end 134.585202 -37.00018)
				)
				(arc
					(start 134.585202 -35.600386)
					(mid 134.100189 -35.114992)
					(end 133.614922 -35.600132)
				)
				(arc
					(start 133.614922 -36.056316)
					(mid 133.630499 -36.058055)
					(end 133.646164 -36.058602)
				)
				(xy 133.650736 -36.058856) (xy 133.869684 -36.058856)
				(arc
					(start 133.874256 -36.058602)
					(mid 133.927717 -36.047968)
					(end 133.973062 -36.017708)
				)
				(arc
					(start 133.973062 -36.017708)
					(mid 133.98776 -36.000363)
					(end 133.999478 -35.980878)
				)
				(arc
					(start 133.999478 -35.980878)
					(mid 134.110897 -35.206545)
					(end 134.178548 -35.985958)
				)
				(arc
					(start 134.178548 -35.985958)
					(mid 134.147463 -36.068554)
					(end 134.094474 -36.13912)
				)
				(arc
					(start 134.094474 -36.13912)
					(mid 134.010618 -36.198897)
					(end 133.911848 -36.22802)
				)
				(xy 133.909816 -36.230052) (xy 133.883146 -36.230052) (xy 133.874256 -36.230306) (xy 133.869684 -36.230052)
				(xy 133.650736 -36.230052) (xy 133.646164 -36.230306) (xy 133.636512 -36.230052)
			)
		)
	)
	(zone
		(layer "B.Cu")
		(hatch none 0.5)
		(connect_pads
			(clearance 0)
		)
		(min_thickness 0.25)
		(keepout
			(tracks not_allowed)
			(vias allowed)
			(pads allowed)
			(copperpour not_allowed)
			(footprints allowed)
		)
		(placement
			(enabled no)
			(sheetname "")
		)
		(fill
			(thermal_gap 0.5)
			(thermal_bridge_width 0.5)
			(island_removal_mode 0)
		)
		(polygon
			(pts
				(xy 110.214918 -33.83026) (xy 110.214918 -33.96869) (xy 110.24616 -33.969706) (xy 110.250732 -33.96996)
				(xy 110.524036 -33.96996) (xy 110.528608 -33.969706) (xy 110.536736 -33.96996) (xy 110.564168 -33.96996)
				(arc
					(start 110.566962 -33.9725)
					(mid 110.644692 -33.997264)
					(end 110.710726 -34.045144)
				)
				(arc
					(start 110.710726 -34.045144)
					(mid 110.758377 -34.110979)
					(end 110.783116 -34.1884)
				)
				(xy 110.785656 -34.191194)
				(arc
					(start 110.785656 -34.215832)
					(mid 110.700581 -34.993853)
					(end 110.613444 -34.216086)
				)
				(arc
					(start 110.613444 -34.216086)
					(mid 110.605464 -34.189337)
					(end 110.589314 -34.166556)
				)
				(arc
					(start 110.589314 -34.166556)
					(mid 110.561462 -34.147946)
					(end 110.528608 -34.14141)
				)
				(xy 110.524036 -34.141156) (xy 110.250732 -34.141156) (xy 110.24616 -34.14141) (xy 110.232952 -34.141156)
				(xy 110.214918 -34.141156)
				(arc
					(start 110.214918 -34.600134)
					(mid 110.700058 -35.085274)
					(end 111.185198 -34.600134)
				)
				(arc
					(start 111.185198 -33.20034)
					(mid 110.700185 -32.714946)
					(end 110.214918 -33.200086)
				)
				(arc
					(start 110.214918 -33.65627)
					(mid 110.230495 -33.658009)
					(end 110.24616 -33.658556)
				)
				(xy 110.250732 -33.658556) (xy 110.46968 -33.658556)
				(arc
					(start 110.474252 -33.658556)
					(mid 110.527713 -33.647922)
					(end 110.573058 -33.617662)
				)
				(arc
					(start 110.573058 -33.617662)
					(mid 110.587756 -33.600317)
					(end 110.599474 -33.580832)
				)
				(arc
					(start 110.599474 -33.580832)
					(mid 110.710893 -32.806499)
					(end 110.778544 -33.585912)
				)
				(arc
					(start 110.778544 -33.585912)
					(mid 110.747459 -33.668508)
					(end 110.69447 -33.739074)
				)
				(arc
					(start 110.69447 -33.739074)
					(mid 110.610614 -33.798851)
					(end 110.511844 -33.827974)
				)
				(xy 110.509812 -33.83026) (xy 110.483142 -33.83026) (xy 110.474252 -33.83026) (xy 110.46968 -33.83026)
				(xy 110.250732 -33.83026) (xy 110.24616 -33.83026) (xy 110.236508 -33.83026)
			)
		)
	)
	(zone
		(net "ADCAV33")
		(layer "B.Cu")
		(hatch none 0.5)
		(connect_pads
			(clearance 0.5)
		)
		(min_thickness 0.25)
		(fill yes
			(thermal_gap 0.5)
			(thermal_bridge_width 0.5)
			(island_removal_mode 0)
		)
		(polygon
			(pts
				(xy 53.72862 -153.31948) (xy 53.5432 -153.5049) (xy 53.5178 -153.5049) (xy 53.5178 -155.0416) (xy 54.6862 -156.21)
				(xy 55.0672 -156.21) (xy 55.30723 -156.45003) (xy 55.30723 -156.92755) (xy 55.37454 -156.99486)
				(xy 56.41594 -156.99486) (xy 56.515 -156.8958) (xy 56.515 -155.55722) (xy 56.36514 -155.40736) (xy 56.2356 -155.40736)
				(xy 56.23306 -155.40482) (xy 55.93842 -155.40482) (xy 55.88 -155.3464) (xy 55.88 -155.34132) (xy 55.61076 -155.07208)
				(xy 55.61076 -154.3812) (xy 55.38724 -154.15768) (xy 55.3085 -154.15768) (xy 55.20182 -154.051)
				(xy 55.20182 -153.4287) (xy 55.0926 -153.31948)
			)
		)
		(polygon
			(pts
				(xy 54.7751 -155.0543) (xy 54.5719 -155.0543) (xy 54.5719 -155.2575) (xy 54.7751 -155.2575)
			)
		)
		(polygon
			(pts
				(xy 54.58968 -153.89098) (xy 54.38648 -153.89098) (xy 54.38648 -154.09418) (xy 54.5719 -154.3939)
				(xy 54.7751 -154.3939) (xy 54.7751 -154.1907)
			)
		)
	)
	(zone
		(layer "B.Cu")
		(hatch none 0.5)
		(connect_pads
			(clearance 0)
		)
		(min_thickness 0.25)
		(keepout
			(tracks not_allowed)
			(vias allowed)
			(pads allowed)
			(copperpour not_allowed)
			(footprints allowed)
		)
		(placement
			(enabled no)
			(sheetname "")
		)
		(fill
			(thermal_gap 0.5)
			(thermal_bridge_width 0.5)
			(island_removal_mode 0)
		)
		(polygon
			(pts
				(arc
					(start 160.250124 -110.000034)
					(mid 155.50007 -105.24998)
					(end 150.750016 -110.000034)
				)
				(arc
					(start 150.750016 -110.000034)
					(mid 155.50007 -114.750088)
					(end 160.250124 -110.000034)
				)
			)
		)
	)
	(zone
		(net "PCE_AVDD")
		(layer "B.Cu")
		(hatch none 0.5)
		(connect_pads
			(clearance 0.5)
		)
		(min_thickness 0.25)
		(fill yes
			(thermal_gap 0.5)
			(thermal_bridge_width 0.5)
			(island_removal_mode 0)
		)
		(polygon
			(pts
				(xy 176.596548 -78.45171) (xy 174.8409 -80.207358) (xy 174.8409 -81.2038) (xy 174.9552 -81.3181)
				(xy 175.8823 -81.3181) (xy 176.403 -80.7974) (xy 180.088286 -80.7974) (xy 180.335428 -81.044542)
				(xy 181.758082 -81.044542) (xy 181.764432 -81.038192) (xy 181.75732 -81.03108) (xy 181.75732 -79.36992)
				(xy 181.697376 -79.309976) (xy 181.697376 -79.102458) (xy 181.450996 -78.856078) (xy 179.190142 -78.856078)
				(xy 178.785774 -78.45171)
			)
		)
		(polygon
			(pts
				(xy 175.95088 -80.27416) (xy 175.74768 -80.27416) (xy 175.74768 -80.47736) (xy 175.95088 -80.47736)
			)
		)
		(polygon
			(pts
				(xy 180.00472 -79.74076) (xy 179.80152 -79.74076) (xy 179.80152 -79.94396) (xy 180.00472 -79.94396)
			)
		)
		(polygon
			(pts
				(xy 179.14112 -79.74076) (xy 178.93792 -79.74076) (xy 178.93792 -79.94396) (xy 179.14112 -79.94396)
			)
		)
	)
	(zone
		(layer "B.Cu")
		(hatch none 0.5)
		(connect_pads
			(clearance 0)
		)
		(min_thickness 0.25)
		(keepout
			(tracks not_allowed)
			(vias allowed)
			(pads allowed)
			(copperpour not_allowed)
			(footprints allowed)
		)
		(placement
			(enabled no)
			(sheetname "")
		)
		(fill
			(thermal_gap 0.5)
			(thermal_bridge_width 0.5)
			(island_removal_mode 0)
		)
		(polygon
			(pts
				(arc
					(start 109.3851 -32.000444)
					(mid 108.900087 -31.51505)
					(end 108.41482 -32.00019)
				)
				(arc
					(start 108.41482 -32.45612)
					(mid 108.430397 -32.457859)
					(end 108.446062 -32.458406)
				)
				(xy 108.450634 -32.45866) (xy 108.669582 -32.45866)
				(arc
					(start 108.674154 -32.458406)
					(mid 108.727615 -32.447772)
					(end 108.77296 -32.417512)
				)
				(arc
					(start 108.77296 -32.417512)
					(mid 108.787669 -32.400305)
					(end 108.799376 -32.380936)
				)
				(arc
					(start 108.799376 -32.380936)
					(mid 108.910795 -31.606603)
					(end 108.978446 -32.386016)
				)
				(arc
					(start 108.978446 -32.386016)
					(mid 108.947275 -32.468437)
					(end 108.894372 -32.538924)
				)
				(arc
					(start 108.894372 -32.538924)
					(mid 108.810516 -32.598701)
					(end 108.711746 -32.627824)
				)
				(xy 108.709714 -32.629856) (xy 108.683044 -32.629856) (xy 108.674154 -32.63011) (xy 108.669582 -32.629856)
				(xy 108.450634 -32.629856) (xy 108.446062 -32.63011) (xy 108.43641 -32.629856) (xy 108.41482 -32.629856)
				(xy 108.41482 -32.76854) (xy 108.446062 -32.769556) (xy 108.450634 -32.769556) (xy 108.723938 -32.769556)
				(xy 108.72851 -32.769556) (xy 108.736638 -32.769556) (xy 108.76407 -32.769556)
				(arc
					(start 108.766864 -32.77235)
					(mid 108.844594 -32.797114)
					(end 108.910628 -32.844994)
				)
				(arc
					(start 108.910628 -32.844994)
					(mid 108.958279 -32.910829)
					(end 108.983018 -32.98825)
				)
				(xy 108.985812 -32.991044)
				(arc
					(start 108.985812 -33.015682)
					(mid 108.900861 -33.793703)
					(end 108.813346 -33.015936)
				)
				(arc
					(start 108.813346 -33.015936)
					(mid 108.805366 -32.989187)
					(end 108.789216 -32.966406)
				)
				(arc
					(start 108.789216 -32.966406)
					(mid 108.761364 -32.947796)
					(end 108.72851 -32.94126)
				)
				(xy 108.723938 -32.94126) (xy 108.450634 -32.94126) (xy 108.446062 -32.94126) (xy 108.432854 -32.94126)
				(xy 108.41482 -32.94126)
				(arc
					(start 108.41482 -33.399984)
					(mid 108.89996 -33.885124)
					(end 109.3851 -33.399984)
				)
			)
		)
	)
	(zone
		(layer "B.Cu")
		(hatch none 0.5)
		(connect_pads
			(clearance 0)
		)
		(min_thickness 0.25)
		(keepout
			(tracks allowed)
			(vias allowed)
			(pads allowed)
			(copperpour allowed)
			(footprints allowed)
		)
		(placement
			(enabled no)
			(sheetname "")
		)
		(fill
			(thermal_gap 0.5)
			(thermal_bridge_width 0.5)
			(island_removal_mode 0)
		)
		(polygon
			(pts
				(xy 131.740656 -38.711124) (xy 131.740656 -36.254436) (xy 132.816346 -36.254436) (xy 132.816346 -38.711124)
			)
		)
	)
	(zone
		(layer "B.Cu")
		(hatch none 0.5)
		(connect_pads
			(clearance 0)
		)
		(min_thickness 0.25)
		(keepout
			(tracks not_allowed)
			(vias allowed)
			(pads allowed)
			(copperpour not_allowed)
			(footprints allowed)
		)
		(placement
			(enabled no)
			(sheetname "")
		)
		(fill
			(thermal_gap 0.5)
			(thermal_bridge_width 0.5)
			(island_removal_mode 0)
		)
		(polygon
			(pts
				(arc
					(start 197.717918 -81.0641)
					(mid 197.68952 -81.057396)
					(end 197.667118 -81.0387)
				)
				(arc
					(start 197.667118 -81.2673)
					(mid 197.68952 -81.248604)
					(end 197.717918 -81.2419)
				)
				(arc
					(start 197.921118 -81.2419)
					(mid 197.949516 -81.248604)
					(end 197.971918 -81.2673)
				)
				(arc
					(start 197.971918 -81.0387)
					(mid 197.949516 -81.057396)
					(end 197.921118 -81.0641)
				)
			)
		)
	)
	(zone
		(net "GND")
		(layer "B.Cu")
		(hatch none 0.5)
		(connect_pads
			(clearance 0.5)
		)
		(min_thickness 0.25)
		(fill yes
			(thermal_gap 0.5)
			(thermal_bridge_width 0.5)
			(island_removal_mode 0)
		)
		(polygon
			(pts
				(xy 47.45228 -154.8892) (xy 47.28718 -155.0543) (xy 47.28718 -155.48356) (xy 47.7647 -155.96108)
				(xy 47.91964 -155.96108) (xy 48.02886 -156.0703) (xy 48.02886 -158.6484) (xy 48.19396 -158.8135)
				(xy 49.35728 -158.8135) (xy 49.49952 -158.67126) (xy 49.49952 -156.32684) (xy 48.82007 -155.64739)
				(xy 48.82007 -155.10637) (xy 48.6029 -154.8892)
			)
		)
		(polygon
			(pts
				(xy 48.96612 -156.67736) (xy 48.76292 -156.67736) (xy 48.76292 -156.88056) (xy 48.96612 -156.88056)
			)
		)
		(polygon
			(pts
				(xy 48.08728 -155.45816) (xy 47.88408 -155.45816) (xy 47.88408 -155.66136) (xy 48.08728 -155.66136)
			)
		)
	)
	(zone
		(layer "B.Cu")
		(hatch none 0.5)
		(connect_pads
			(clearance 0)
		)
		(min_thickness 0.25)
		(keepout
			(tracks allowed)
			(vias allowed)
			(pads allowed)
			(copperpour allowed)
			(footprints not_allowed)
		)
		(placement
			(enabled no)
			(sheetname "")
		)
		(fill
			(thermal_gap 0.5)
			(thermal_bridge_width 0.5)
			(island_removal_mode 0)
		)
		(polygon
			(pts
				(arc
					(start 168.800018 -45.72)
					(mid 165.800024 -42.720006)
					(end 162.80003 -45.72)
				)
				(arc
					(start 162.80003 -45.72)
					(mid 165.800024 -48.719994)
					(end 168.800018 -45.72)
				)
			)
		)
	)
	(zone
		(layer "B.Cu")
		(hatch none 0.5)
		(connect_pads
			(clearance 0)
		)
		(min_thickness 0.25)
		(keepout
			(tracks not_allowed)
			(vias allowed)
			(pads allowed)
			(copperpour not_allowed)
			(footprints allowed)
		)
		(placement
			(enabled no)
			(sheetname "")
		)
		(fill
			(thermal_gap 0.5)
			(thermal_bridge_width 0.5)
			(island_removal_mode 0)
		)
		(polygon
			(pts
				(arc
					(start 191.57569 -19.6596)
					(mid 191.594386 -19.682002)
					(end 191.60109 -19.7104)
				)
				(arc
					(start 191.60109 -19.9136)
					(mid 191.594386 -19.941998)
					(end 191.57569 -19.9644)
				)
				(arc
					(start 191.80429 -19.9644)
					(mid 191.785594 -19.941998)
					(end 191.77889 -19.9136)
				)
				(arc
					(start 191.77889 -19.7104)
					(mid 191.785594 -19.682002)
					(end 191.80429 -19.6596)
				)
			)
		)
	)
	(zone
		(layer "B.Cu")
		(hatch none 0.5)
		(connect_pads
			(clearance 0)
		)
		(min_thickness 0.25)
		(keepout
			(tracks allowed)
			(vias allowed)
			(pads allowed)
			(copperpour allowed)
			(footprints allowed)
		)
		(placement
			(enabled no)
			(sheetname "")
		)
		(fill
			(thermal_gap 0.5)
			(thermal_bridge_width 0.5)
			(island_removal_mode 0)
		)
		(polygon
			(pts
				(xy 191.02705 -26.200354) (xy 191.02705 -24.981662) (xy 192.375282 -24.981662) (xy 192.375282 -26.200354)
			)
		)
	)
	(zone
		(layer "B.Cu")
		(hatch none 0.5)
		(connect_pads
			(clearance 0)
		)
		(min_thickness 0.25)
		(keepout
			(tracks allowed)
			(vias allowed)
			(pads allowed)
			(copperpour allowed)
			(footprints allowed)
		)
		(placement
			(enabled no)
			(sheetname "")
		)
		(fill
			(thermal_gap 0.5)
			(thermal_bridge_width 0.5)
			(island_removal_mode 0)
		)
		(polygon
			(pts
				(xy 44.6532 -126.3142) (xy 45.3136 -126.3142) (xy 45.3136 -128.3716) (xy 44.6532 -128.3716)
			)
		)
	)
	(zone
		(layer "B.Cu")
		(hatch none 0.5)
		(connect_pads
			(clearance 0)
		)
		(min_thickness 0.25)
		(keepout
			(tracks allowed)
			(vias allowed)
			(pads allowed)
			(copperpour allowed)
			(footprints allowed)
		)
		(placement
			(enabled no)
			(sheetname "")
		)
		(fill
			(thermal_gap 0.5)
			(thermal_bridge_width 0.5)
			(island_removal_mode 0)
		)
		(polygon
			(pts
				(xy 138.94054 -38.711124) (xy 138.94054 -36.254436) (xy 140.01623 -36.254436) (xy 140.01623 -38.711124)
			)
		)
	)
	(zone
		(net "GND")
		(layer "B.Cu")
		(hatch none 0.5)
		(connect_pads
			(clearance 0.5)
		)
		(min_thickness 0.25)
		(fill yes
			(thermal_gap 0.5)
			(thermal_bridge_width 0.5)
			(island_removal_mode 0)
		)
		(polygon
			(pts
				(xy 19.653504 -143.443706) (xy 19.56689 -143.53032) (xy 19.56689 -144.439386) (xy 19.37258 -144.633696)
				(xy 18.99412 -144.633696) (xy 18.993612 -144.634204) (xy 17.969484 -144.634204) (xy 17.760188 -144.8435)
				(xy 17.760188 -146.682968) (xy 17.92986 -146.85264) (xy 18.16608 -146.85264) (xy 18.3134 -146.70532)
				(xy 18.3134 -146.35734) (xy 18.44294 -146.2278) (xy 19.888708 -146.2278) (xy 20.186904 -145.929604)
				(xy 20.186904 -143.51127) (xy 20.11934 -143.443706)
			)
		)
	)
	(zone
		(net "V1PLLAV11")
		(layer "B.Cu")
		(hatch none 0.5)
		(connect_pads
			(clearance 0.5)
		)
		(min_thickness 0.25)
		(fill yes
			(thermal_gap 0.5)
			(thermal_bridge_width 0.5)
			(island_removal_mode 0)
		)
		(polygon
			(pts
				(xy 47.8282 -149.4663) (xy 47.117 -150.1775) (xy 46.69536 -150.1775) (xy 46.45914 -150.41372) (xy 46.45914 -151.57958)
				(xy 46.24832 -151.7904) (xy 46.05528 -151.7904) (xy 45.91812 -151.92756) (xy 45.91812 -153.3779)
				(xy 45.4025 -153.89352) (xy 45.33138 -153.89352) (xy 45.19168 -154.03322) (xy 45.19168 -156.72054)
				(xy 44.72432 -157.1879) (xy 44.72432 -158.75508) (xy 45.90796 -158.75508) (xy 46.03877 -158.62427)
				(xy 46.03877 -156.98089) (xy 46.29404 -156.72562) (xy 46.29404 -153.95448) (xy 46.45406 -153.79446)
				(xy 46.45406 -152.21458) (xy 47.21606 -151.45258) (xy 47.58944 -151.45258) (xy 48.12284 -150.91918)
				(xy 48.59528 -150.91918) (xy 48.76546 -150.749) (xy 48.76546 -149.59076) (xy 48.641 -149.4663)
			)
		)
		(polygon
			(pts
				(xy 45.93844 -155.44292) (xy 45.73524 -155.44292) (xy 45.73524 -155.64612) (xy 45.93844 -155.64612)
			)
		)
		(polygon
			(pts
				(xy 45.93844 -154.83332) (xy 45.73524 -154.83332) (xy 45.73524 -155.03652) (xy 45.93844 -155.03652)
			)
		)
		(polygon
			(pts
				(xy 45.93844 -154.50312) (xy 45.73524 -154.50312) (xy 45.73524 -154.70632) (xy 45.93844 -154.70632)
			)
		)
		(polygon
			(pts
				(xy 45.93844 -153.89352) (xy 45.73524 -153.89352) (xy 45.73524 -154.09672) (xy 45.93844 -154.09672)
			)
		)
	)
	(zone
		(net "P1V15_STBY")
		(layer "B.Cu")
		(hatch none 0.5)
		(connect_pads
			(clearance 0.5)
		)
		(min_thickness 0.25)
		(fill yes
			(thermal_gap 0.5)
			(thermal_bridge_width 0.5)
			(island_removal_mode 0)
		)
		(polygon
			(pts
				(xy 42.2783 -155.88234) (xy 41.87952 -156.28112) (xy 41.87952 -156.93898) (xy 41.7195 -157.099)
				(xy 41.7195 -158.5595) (xy 41.93794 -158.77794) (xy 43.9039 -158.77794) (xy 44.0055 -158.67634)
				(xy 44.0055 -157.2133) (xy 43.91025 -157.11805) (xy 42.75455 -157.11805) (xy 42.6339 -156.9974)
				(xy 42.6339 -155.96362) (xy 42.55262 -155.88234)
			)
		)
	)
	(zone
		(net "P1V8")
		(layer "B.Cu")
		(hatch none 0.5)
		(connect_pads
			(clearance 0.5)
		)
		(min_thickness 0.25)
		(fill yes
			(thermal_gap 0.5)
			(thermal_bridge_width 0.5)
			(island_removal_mode 0)
		)
		(polygon
			(pts
				(xy 196.2912 -44.8818) (xy 195.8848 -45.2882) (xy 195.8848 -46.609) (xy 195.8721 -46.6217) (xy 195.8721 -46.7233)
				(xy 194.9196 -47.6758) (xy 194.9196 -50.2666) (xy 194.9958 -50.3428) (xy 195.453 -50.3428) (xy 195.5038 -50.292)
				(xy 195.5038 -48.9458) (xy 195.9102 -48.5394) (xy 197.0532 -48.5394) (xy 197.1294 -48.4632) (xy 197.1294 -46.9138)
				(xy 197.4596 -46.5836) (xy 197.4596 -45.72) (xy 197.5358 -45.6438) (xy 198.9074 -45.6438) (xy 199.129396 -45.865796)
				(xy 199.129396 -46.566582) (xy 199.41921 -46.856396) (xy 199.41921 -48.354488) (xy 199.614282 -48.54956)
				(xy 200.758298 -48.54956) (xy 200.808082 -48.499776) (xy 200.808082 -48.360584) (xy 200.809352 -48.359314)
				(xy 200.809352 -46.755558) (xy 200.95337 -46.61154) (xy 200.95337 -45.709586) (xy 200.961498 -45.709586)
				(xy 201.0918 -45.579284) (xy 202.647804 -45.579284) (xy 203.04125 -45.97273) (xy 203.04125 -48.4759)
				(xy 203.149962 -48.584612) (xy 204.533246 -48.584612) (xy 204.61224 -48.505618) (xy 204.61224 -45.985684)
				(xy 204.023468 -45.396912) (xy 204.023468 -45.360844) (xy 203.544424 -44.8818)
			)
		)
		(polygon
			(pts
				(xy 200.500742 -46.486572) (xy 200.297542 -46.486572) (xy 200.297542 -46.689772) (xy 200.500742 -46.689772)
			)
		)
		(polygon
			(pts
				(xy 204.163168 -46.458886) (xy 203.959968 -46.458886) (xy 203.959968 -46.662086) (xy 204.163168 -46.662086)
			)
		)
		(polygon
			(pts
				(xy 196.977 -46.4566) (xy 196.7738 -46.4566) (xy 196.7738 -46.6598) (xy 196.977 -46.6598)
			)
		)
		(polygon
			(pts
				(xy 200.500742 -45.927772) (xy 200.297542 -45.927772) (xy 200.297542 -46.130972) (xy 200.500742 -46.130972)
			)
		)
		(polygon
			(pts
				(xy 204.163168 -45.900086) (xy 203.959968 -45.900086) (xy 203.959968 -46.103286) (xy 204.163168 -46.103286)
			)
		)
		(polygon
			(pts
				(xy 196.977 -45.8978) (xy 196.7738 -45.8978) (xy 196.7738 -46.101) (xy 196.977 -46.101)
			)
		)
	)
	(zone
		(layer "B.Cu")
		(hatch none 0.5)
		(connect_pads
			(clearance 0)
		)
		(min_thickness 0.25)
		(keepout
			(tracks not_allowed)
			(vias allowed)
			(pads allowed)
			(copperpour not_allowed)
			(footprints allowed)
		)
		(placement
			(enabled no)
			(sheetname "")
		)
		(fill
			(thermal_gap 0.5)
			(thermal_bridge_width 0.5)
			(island_removal_mode 0)
		)
		(polygon
			(pts
				(arc
					(start 191.57569 -21.6916)
					(mid 191.594386 -21.714002)
					(end 191.60109 -21.7424)
				)
				(arc
					(start 191.60109 -21.9456)
					(mid 191.594386 -21.973998)
					(end 191.57569 -21.9964)
				)
				(arc
					(start 191.80429 -21.9964)
					(mid 191.785594 -21.973998)
					(end 191.77889 -21.9456)
				)
				(arc
					(start 191.77889 -21.7424)
					(mid 191.785594 -21.714002)
					(end 191.80429 -21.6916)
				)
			)
		)
	)
	(zone
		(layer "B.Cu")
		(hatch none 0.5)
		(connect_pads
			(clearance 0)
		)
		(min_thickness 0.25)
		(keepout
			(tracks allowed)
			(vias allowed)
			(pads allowed)
			(copperpour allowed)
			(footprints allowed)
		)
		(placement
			(enabled no)
			(sheetname "")
		)
		(fill
			(thermal_gap 0.5)
			(thermal_bridge_width 0.5)
			(island_removal_mode 0)
		)
		(polygon
			(pts
				(xy 196.977 -81.8134) (xy 196.977 -80.518) (xy 198.0692 -80.518) (xy 198.0692 -81.8134)
			)
		)
	)
	(zone
		(layer "B.Cu")
		(hatch none 0.5)
		(connect_pads
			(clearance 0)
		)
		(min_thickness 0.25)
		(keepout
			(tracks allowed)
			(vias allowed)
			(pads allowed)
			(copperpour allowed)
			(footprints not_allowed)
		)
		(placement
			(enabled no)
			(sheetname "")
		)
		(fill
			(thermal_gap 0.5)
			(thermal_bridge_width 0.5)
			(island_removal_mode 0)
		)
		(polygon
			(pts
				(arc
					(start 217.749882 -14.99997)
					(mid 222.499936 -19.750024)
					(end 227.24999 -14.99997)
				)
				(arc
					(start 227.24999 -14.99997)
					(mid 222.499936 -10.249916)
					(end 217.749882 -14.99997)
				)
			)
		)
	)
	(zone
		(layer "B.Cu")
		(hatch none 0.5)
		(connect_pads
			(clearance 0)
		)
		(min_thickness 0.25)
		(keepout
			(tracks allowed)
			(vias allowed)
			(pads allowed)
			(copperpour allowed)
			(footprints allowed)
		)
		(placement
			(enabled no)
			(sheetname "")
		)
		(fill
			(thermal_gap 0.5)
			(thermal_bridge_width 0.5)
			(island_removal_mode 0)
		)
		(polygon
			(pts
				(xy 62.8142 -141.9606) (xy 62.8142 -140.8684) (xy 64.1858 -140.8684) (xy 64.1858 -141.9606)
			)
		)
	)
	(zone
		(layer "B.Cu")
		(hatch none 0.5)
		(connect_pads
			(clearance 0)
		)
		(min_thickness 0.25)
		(keepout
			(tracks not_allowed)
			(vias allowed)
			(pads allowed)
			(copperpour not_allowed)
			(footprints allowed)
		)
		(placement
			(enabled no)
			(sheetname "")
		)
		(fill
			(thermal_gap 0.5)
			(thermal_bridge_width 0.5)
			(island_removal_mode 0)
		)
		(polygon
			(pts
				(arc
					(start 191.57569 -23.0886)
					(mid 191.594386 -23.111002)
					(end 191.60109 -23.1394)
				)
				(arc
					(start 191.60109 -23.3426)
					(mid 191.594386 -23.370998)
					(end 191.57569 -23.3934)
				)
				(arc
					(start 191.80429 -23.3934)
					(mid 191.785594 -23.370998)
					(end 191.77889 -23.3426)
				)
				(arc
					(start 191.77889 -23.1394)
					(mid 191.785594 -23.111002)
					(end 191.80429 -23.0886)
				)
			)
		)
	)
	(zone
		(net "P1V8")
		(layer "B.Cu")
		(hatch none 0.5)
		(connect_pads
			(clearance 0.5)
		)
		(min_thickness 0.25)
		(fill yes
			(thermal_gap 0.5)
			(thermal_bridge_width 0.5)
			(island_removal_mode 0)
		)
		(polygon
			(pts
				(xy 190.98641 -43.447462) (xy 190.881 -43.552872) (xy 190.881 -45.4406) (xy 190.9826 -45.5422) (xy 192.1256 -45.5422)
				(xy 192.8114 -46.228) (xy 193.5988 -46.228) (xy 193.675 -46.1518) (xy 193.675 -45.5168) (xy 193.3194 -45.1612)
				(xy 193.3194 -43.625516) (xy 193.141346 -43.447462)
			)
		)
		(polygon
			(pts
				(xy 193.1924 -45.5422) (xy 192.9892 -45.5422) (xy 192.9892 -45.7454) (xy 193.1924 -45.7454)
			)
		)
	)
	(zone
		(layer "B.Cu")
		(hatch none 0.5)
		(connect_pads
			(clearance 0)
		)
		(min_thickness 0.25)
		(keepout
			(tracks not_allowed)
			(vias allowed)
			(pads allowed)
			(copperpour not_allowed)
			(footprints allowed)
		)
		(placement
			(enabled no)
			(sheetname "")
		)
		(fill
			(thermal_gap 0.5)
			(thermal_bridge_width 0.5)
			(island_removal_mode 0)
		)
		(polygon
			(pts
				(arc
					(start 162.500056 -14.699996)
					(mid 160.000188 -12.200128)
					(end 157.500066 -14.699996)
				)
				(arc
					(start 157.500066 -14.699996)
					(mid 160.000188 -17.200118)
					(end 162.500056 -14.699996)
				)
			)
		)
	)
	(zone
		(layer "B.Cu")
		(hatch none 0.5)
		(connect_pads
			(clearance 0)
		)
		(min_thickness 0.25)
		(keepout
			(tracks allowed)
			(vias allowed)
			(pads allowed)
			(copperpour allowed)
			(footprints not_allowed)
		)
		(placement
			(enabled no)
			(sheetname "")
		)
		(fill
			(thermal_gap 0.5)
			(thermal_bridge_width 0.5)
			(island_removal_mode 0)
		)
		(polygon
			(pts
				(arc
					(start 150.750016 -110.000034)
					(mid 155.50007 -114.750088)
					(end 160.250124 -110.000034)
				)
				(arc
					(start 160.250124 -110.000034)
					(mid 155.50007 -105.24998)
					(end 150.750016 -110.000034)
				)
			)
		)
	)
	(zone
		(layer "B.Cu")
		(hatch none 0.5)
		(connect_pads
			(clearance 0)
		)
		(min_thickness 0.25)
		(keepout
			(tracks allowed)
			(vias allowed)
			(pads allowed)
			(copperpour allowed)
			(footprints not_allowed)
		)
		(placement
			(enabled no)
			(sheetname "")
		)
		(fill
			(thermal_gap 0.5)
			(thermal_bridge_width 0.5)
			(island_removal_mode 0)
		)
		(polygon
			(pts
				(arc
					(start 125.370082 -41.844976)
					(mid 124.165106 -40.64)
					(end 122.96013 -41.844976)
				)
				(arc
					(start 122.96013 -41.844976)
					(mid 124.165106 -43.049952)
					(end 125.370082 -41.844976)
				)
			)
		)
	)
	(zone
		(net "P1V8")
		(layer "B.Cu")
		(hatch none 0.5)
		(connect_pads
			(clearance 0.5)
		)
		(min_thickness 0.25)
		(fill yes
			(thermal_gap 0.5)
			(thermal_bridge_width 0.5)
			(island_removal_mode 0)
		)
		(polygon
			(pts
				(xy 212.3186 -87.3506) (xy 212.1916 -87.4776) (xy 212.1916 -87.63) (xy 212.217 -87.6554) (xy 212.217 -89.154)
				(xy 211.963 -89.408) (xy 211.963 -89.8906) (xy 212.1154 -90.043) (xy 214.1982 -90.043) (xy 214.6046 -89.6366)
				(xy 214.6046 -87.6554) (xy 214.2998 -87.3506)
			)
		)
		(polygon
			(pts
				(xy 212.6488 -89.281) (xy 212.4456 -89.281) (xy 212.4456 -89.4842) (xy 212.6488 -89.4842)
			)
		)
	)
	(zone
		(net "P3V3_STBY")
		(layer "B.Cu")
		(hatch none 0.5)
		(connect_pads
			(clearance 0.5)
		)
		(min_thickness 0.25)
		(fill yes
			(thermal_gap 0.5)
			(thermal_bridge_width 0.5)
			(island_removal_mode 0)
		)
		(polygon
			(pts
				(xy 42.134536 -130.172714) (xy 42.043604 -130.263646) (xy 42.043604 -130.593084) (xy 42.20845 -130.75793)
				(xy 42.833544 -130.75793) (xy 43.009566 -130.933952) (xy 43.009566 -132.812536) (xy 43.222672 -133.025642)
				(xy 43.677332 -133.025642) (xy 43.816524 -132.88645) (xy 43.816524 -130.473704) (xy 43.515534 -130.172714)
			)
		)
	)
	(zone
		(layer "B.Cu")
		(hatch none 0.5)
		(connect_pads
			(clearance 0)
		)
		(min_thickness 0.25)
		(keepout
			(tracks not_allowed)
			(vias allowed)
			(pads allowed)
			(copperpour not_allowed)
			(footprints allowed)
		)
		(placement
			(enabled no)
			(sheetname "")
		)
		(fill
			(thermal_gap 0.5)
			(thermal_bridge_width 0.5)
			(island_removal_mode 0)
		)
		(polygon
			(pts
				(arc
					(start 191.57569 -23.7236)
					(mid 191.594386 -23.746002)
					(end 191.60109 -23.7744)
				)
				(arc
					(start 191.60109 -23.9776)
					(mid 191.594386 -24.005998)
					(end 191.57569 -24.0284)
				)
				(arc
					(start 191.80429 -24.0284)
					(mid 191.785594 -24.005998)
					(end 191.77889 -23.9776)
				)
				(arc
					(start 191.77889 -23.7744)
					(mid 191.785594 -23.746002)
					(end 191.80429 -23.7236)
				)
			)
		)
	)
	(zone
		(net "VDDA_SAS_REF_CLK")
		(layer "B.Cu")
		(hatch none 0.5)
		(connect_pads
			(clearance 0.5)
		)
		(min_thickness 0.25)
		(fill yes
			(thermal_gap 0.5)
			(thermal_bridge_width 0.5)
			(island_removal_mode 0)
		)
		(polygon
			(pts
				(xy 197.7898 -45.9994) (xy 197.739 -46.0502) (xy 197.739 -46.6598) (xy 197.6628 -46.736) (xy 197.6628 -49.0982)
				(xy 197.6882 -49.1236) (xy 197.6882 -52.2732) (xy 197.612 -52.3494) (xy 197.612 -53.1114) (xy 197.6374 -53.1368)
				(xy 199.12076 -53.1368) (xy 199.45223 -52.80533) (xy 199.45223 -52.121816) (xy 199.118474 -51.78806)
				(xy 199.118474 -49.065688) (xy 199.0344 -48.981614) (xy 199.0344 -47.0916) (xy 198.6915 -46.7487)
				(xy 198.4883 -46.7487) (xy 198.3232 -46.5836) (xy 198.3232 -46.0248) (xy 198.2978 -45.9994)
			)
		)
		(polygon
			(pts
				(xy 198.1454 -52.5272) (xy 197.9422 -52.5272) (xy 197.9422 -52.9336) (xy 198.1454 -52.9336)
			)
		)
		(polygon
			(pts
				(xy 198.1454 -52.1716) (xy 197.9422 -52.1716) (xy 197.9422 -52.3748) (xy 198.1454 -52.3748)
			)
		)
		(polygon
			(pts
				(xy 198.8058 -51.7652) (xy 198.6026 -51.7652) (xy 198.6026 -51.9684) (xy 198.8058 -51.9684)
			)
		)
		(polygon
			(pts
				(xy 198.8058 -50.9016) (xy 198.6026 -50.9016) (xy 198.6026 -51.1048) (xy 198.8058 -51.1048)
			)
		)
	)
	(zone
		(net "GND")
		(layer "B.Cu")
		(hatch none 0.5)
		(connect_pads
			(clearance 0.5)
		)
		(min_thickness 0.25)
		(fill yes
			(thermal_gap 0.5)
			(thermal_bridge_width 0.5)
			(island_removal_mode 0)
		)
		(polygon
			(pts
				(xy 73.453752 -178.727354) (xy 73.453752 -181.991762) (xy 76.717906 -181.991762) (xy 76.717906 -178.727354)
			)
		)
	)
	(zone
		(net "VT235_VDDH")
		(layer "B.Cu")
		(hatch none 0.5)
		(connect_pads
			(clearance 0.5)
		)
		(min_thickness 0.25)
		(fill yes
			(thermal_gap 0.5)
			(thermal_bridge_width 0.5)
			(island_removal_mode 0)
		)
		(polygon
			(pts
				(xy 181.4322 -114.4524) (xy 181.0512 -114.8334) (xy 181.0512 -118.7196) (xy 181.5846 -119.253) (xy 183.7182 -119.253)
				(xy 183.9468 -119.0244) (xy 183.9468 -114.9096) (xy 183.4896 -114.4524)
			)
		)
	)
	(zone
		(layer "B.Cu")
		(hatch none 0.5)
		(connect_pads
			(clearance 0)
		)
		(min_thickness 0.25)
		(keepout
			(tracks not_allowed)
			(vias allowed)
			(pads allowed)
			(copperpour not_allowed)
			(footprints allowed)
		)
		(placement
			(enabled no)
			(sheetname "")
		)
		(fill
			(thermal_gap 0.5)
			(thermal_bridge_width 0.5)
			(island_removal_mode 0)
		)
		(polygon
			(pts
				(xy 130.014726 -36.230052) (xy 130.014726 -36.368736) (xy 130.045968 -36.369752) (xy 130.05054 -36.369752)
				(xy 130.323844 -36.369752) (xy 130.328416 -36.369752) (xy 130.336544 -36.369752) (xy 130.363976 -36.369752)
				(arc
					(start 130.36677 -36.372546)
					(mid 130.4445 -36.39731)
					(end 130.510534 -36.44519)
				)
				(arc
					(start 130.510534 -36.44519)
					(mid 130.558185 -36.511025)
					(end 130.582924 -36.588446)
				)
				(xy 130.585464 -36.59124)
				(arc
					(start 130.585464 -36.615878)
					(mid 130.500389 -37.393899)
					(end 130.413252 -36.616132)
				)
				(arc
					(start 130.413252 -36.616132)
					(mid 130.405272 -36.589383)
					(end 130.389122 -36.566602)
				)
				(arc
					(start 130.389122 -36.566602)
					(mid 130.36127 -36.547992)
					(end 130.328416 -36.541456)
				)
				(xy 130.323844 -36.541456) (xy 130.05054 -36.541456) (xy 130.045968 -36.541456) (xy 130.03276 -36.541456)
				(xy 130.014726 -36.541456)
				(arc
					(start 130.014726 -37.00018)
					(mid 130.499866 -37.48532)
					(end 130.985006 -37.00018)
				)
				(arc
					(start 130.985006 -35.600386)
					(mid 130.499993 -35.114992)
					(end 130.014726 -35.600132)
				)
				(arc
					(start 130.014726 -36.056316)
					(mid 130.030303 -36.058055)
					(end 130.045968 -36.058602)
				)
				(xy 130.05054 -36.058856) (xy 130.269488 -36.058856)
				(arc
					(start 130.27406 -36.058602)
					(mid 130.327521 -36.047968)
					(end 130.372866 -36.017708)
				)
				(arc
					(start 130.372866 -36.017708)
					(mid 130.387564 -36.000363)
					(end 130.399282 -35.980878)
				)
				(arc
					(start 130.399282 -35.980878)
					(mid 130.510701 -35.206545)
					(end 130.578352 -35.985958)
				)
				(arc
					(start 130.578352 -35.985958)
					(mid 130.547267 -36.068554)
					(end 130.494278 -36.13912)
				)
				(arc
					(start 130.494278 -36.13912)
					(mid 130.410422 -36.198897)
					(end 130.311652 -36.22802)
				)
				(xy 130.30962 -36.230052) (xy 130.28295 -36.230052) (xy 130.27406 -36.230306) (xy 130.269488 -36.230052)
				(xy 130.05054 -36.230052) (xy 130.045968 -36.230306) (xy 130.036316 -36.230052)
			)
		)
	)
	(zone
		(net "P3V3_STBY")
		(layer "B.Cu")
		(hatch none 0.5)
		(connect_pads
			(clearance 0.5)
		)
		(min_thickness 0.25)
		(fill yes
			(thermal_gap 0.5)
			(thermal_bridge_width 0.5)
			(island_removal_mode 0)
		)
		(polygon
			(pts
				(xy 39.293038 -130.175254) (xy 39.099744 -130.368548) (xy 39.099744 -130.69824) (xy 39.793164 -131.39166)
				(xy 39.793164 -133.57098) (xy 40.199564 -133.97738) (xy 40.952166 -133.97738) (xy 41.30167 -134.326884)
				(xy 41.776396 -134.326884) (xy 41.85031 -134.25297) (xy 41.85031 -133.74116) (xy 41.65473 -133.54558)
				(xy 41.100502 -133.54558) (xy 40.804592 -133.24967) (xy 40.804592 -131.777994) (xy 40.935402 -131.647184)
				(xy 41.576244 -131.647184) (xy 41.696894 -131.526534) (xy 41.696894 -131.084574) (xy 41.509442 -130.897122)
				(xy 41.122854 -130.897122) (xy 40.400986 -130.175254)
			)
		)
		(polygon
			(pts
				(xy 41.3766 -133.6548) (xy 41.1734 -133.6548) (xy 41.1734 -133.858) (xy 41.3766 -133.858)
			)
		)
		(polygon
			(pts
				(xy 40.2844 -133.2992) (xy 40.0812 -133.2992) (xy 40.0812 -133.5024) (xy 40.2844 -133.5024)
			)
		)
		(polygon
			(pts
				(xy 40.357552 -132.799836) (xy 40.154352 -132.799836) (xy 40.154352 -133.003036) (xy 40.357552 -133.003036)
			)
		)
		(polygon
			(pts
				(xy 40.357552 -132.241036) (xy 40.154352 -132.241036) (xy 40.154352 -132.444236) (xy 40.357552 -132.444236)
			)
		)
		(polygon
			(pts
				(xy 40.349932 -131.667758) (xy 40.146732 -131.667758) (xy 40.146732 -131.870958) (xy 40.349932 -131.870958)
			)
		)
		(polygon
			(pts
				(xy 40.349932 -131.108958) (xy 40.146732 -131.108958) (xy 40.146732 -131.312158) (xy 40.349932 -131.312158)
			)
		)
	)
	(zone
		(layer "B.Cu")
		(hatch none 0.5)
		(connect_pads
			(clearance 0)
		)
		(min_thickness 0.25)
		(keepout
			(tracks allowed)
			(vias allowed)
			(pads allowed)
			(copperpour allowed)
			(footprints allowed)
		)
		(placement
			(enabled no)
			(sheetname "")
		)
		(fill
			(thermal_gap 0.5)
			(thermal_bridge_width 0.5)
			(island_removal_mode 0)
		)
		(polygon
			(pts
				(xy 190.9826 -22.0726) (xy 190.9826 -20.9804) (xy 192.3542 -20.9804) (xy 192.3542 -22.0726)
			)
		)
	)
	(zone
		(layer "B.Cu")
		(hatch none 0.5)
		(connect_pads
			(clearance 0)
		)
		(min_thickness 0.25)
		(keepout
			(tracks not_allowed)
			(vias allowed)
			(pads allowed)
			(copperpour not_allowed)
			(footprints allowed)
		)
		(placement
			(enabled no)
			(sheetname "")
		)
		(fill
			(thermal_gap 0.5)
			(thermal_bridge_width 0.5)
			(island_removal_mode 0)
		)
		(polygon
			(pts
				(arc
					(start 182.500016 -14.699996)
					(mid 180.000148 -12.200128)
					(end 177.500026 -14.699996)
				)
				(arc
					(start 177.500026 -14.699996)
					(mid 180.000148 -17.200118)
					(end 182.500016 -14.699996)
				)
			)
		)
	)
	(zone
		(net "GND")
		(layer "B.Cu")
		(hatch none 0.5)
		(connect_pads
			(clearance 0.5)
		)
		(min_thickness 0.25)
		(fill yes
			(thermal_gap 0.5)
			(thermal_bridge_width 0.5)
			(island_removal_mode 0)
		)
		(polygon
			(pts
				(xy 176.40935 -81.2419) (xy 175.9331 -81.71815) (xy 174.89805 -81.71815) (xy 174.7393 -81.8769)
				(xy 174.7393 -82.931) (xy 174.8663 -83.058) (xy 178.5493 -83.058) (xy 178.6636 -82.9437) (xy 178.6636 -81.4197)
				(xy 178.4858 -81.2419)
			)
		)
		(polygon
			(pts
				(xy 175.95088 -82.56016) (xy 175.74768 -82.56016) (xy 175.74768 -82.76336) (xy 175.95088 -82.76336)
			)
		)
		(polygon
			(pts
				(xy 175.08728 -82.56016) (xy 174.88408 -82.56016) (xy 174.88408 -82.76336) (xy 175.08728 -82.76336)
			)
		)
	)
	(zone
		(layer "B.Cu")
		(hatch none 0.5)
		(connect_pads
			(clearance 0)
		)
		(min_thickness 0.25)
		(keepout
			(tracks not_allowed)
			(vias allowed)
			(pads allowed)
			(copperpour not_allowed)
			(footprints allowed)
		)
		(placement
			(enabled no)
			(sheetname "")
		)
		(fill
			(thermal_gap 0.5)
			(thermal_bridge_width 0.5)
			(island_removal_mode 0)
		)
		(polygon
			(pts
				(arc
					(start 107.750102 -9.99998)
					(mid 103.000048 -5.249926)
					(end 98.249994 -9.99998)
				)
				(arc
					(start 98.249994 -9.99998)
					(mid 103.000048 -14.750034)
					(end 107.750102 -9.99998)
				)
			)
		)
	)
	(zone
		(layer "B.Cu")
		(hatch none 0.5)
		(connect_pads
			(clearance 0)
		)
		(min_thickness 0.25)
		(keepout
			(tracks allowed)
			(vias allowed)
			(pads allowed)
			(copperpour allowed)
			(footprints not_allowed)
		)
		(placement
			(enabled no)
			(sheetname "")
		)
		(fill
			(thermal_gap 0.5)
			(thermal_bridge_width 0.5)
			(island_removal_mode 0)
		)
		(polygon
			(pts
				(arc
					(start 182.500016 -14.699996)
					(mid 180.000148 -12.200128)
					(end 177.500026 -14.699996)
				)
				(arc
					(start 177.500026 -14.699996)
					(mid 180.000148 -17.200118)
					(end 182.500016 -14.699996)
				)
			)
		)
	)
	(zone
		(layer "B.Cu")
		(hatch none 0.5)
		(connect_pads
			(clearance 0)
		)
		(min_thickness 0.25)
		(keepout
			(tracks not_allowed)
			(vias allowed)
			(pads allowed)
			(copperpour not_allowed)
			(footprints allowed)
		)
		(placement
			(enabled no)
			(sheetname "")
		)
		(fill
			(thermal_gap 0.5)
			(thermal_bridge_width 0.5)
			(island_removal_mode 0)
		)
		(polygon
			(pts
				(arc
					(start 22.61616 -120.000014)
					(mid 13.383768 -120.000014)
					(end 22.61616 -120.000014)
				)
			)
		)
	)
	(zone
		(layer "B.Cu")
		(hatch none 0.5)
		(connect_pads
			(clearance 0)
		)
		(min_thickness 0.25)
		(keepout
			(tracks not_allowed)
			(vias allowed)
			(pads allowed)
			(copperpour not_allowed)
			(footprints allowed)
		)
		(placement
			(enabled no)
			(sheetname "")
		)
		(fill
			(thermal_gap 0.5)
			(thermal_bridge_width 0.5)
			(island_removal_mode 0)
		)
		(polygon
			(pts
				(arc
					(start 191.57569 -19.0246)
					(mid 191.594386 -19.047002)
					(end 191.60109 -19.0754)
				)
				(arc
					(start 191.60109 -19.2786)
					(mid 191.594386 -19.306998)
					(end 191.57569 -19.3294)
				)
				(arc
					(start 191.80429 -19.3294)
					(mid 191.785594 -19.306998)
					(end 191.77889 -19.2786)
				)
				(arc
					(start 191.77889 -19.0754)
					(mid 191.785594 -19.047002)
					(end 191.80429 -19.0246)
				)
			)
		)
	)
	(zone
		(layer "B.Cu")
		(hatch none 0.5)
		(connect_pads
			(clearance 0)
		)
		(min_thickness 0.25)
		(keepout
			(tracks allowed)
			(vias allowed)
			(pads allowed)
			(copperpour allowed)
			(footprints allowed)
		)
		(placement
			(enabled no)
			(sheetname "")
		)
		(fill
			(thermal_gap 0.5)
			(thermal_bridge_width 0.5)
			(island_removal_mode 0)
		)
		(polygon
			(pts
				(xy 135.340598 -38.711124) (xy 135.340598 -36.254436) (xy 136.416288 -36.254436) (xy 136.416288 -38.711124)
			)
		)
	)
	(zone
		(layer "B.Cu")
		(hatch none 0.5)
		(connect_pads
			(clearance 0)
		)
		(min_thickness 0.25)
		(keepout
			(tracks not_allowed)
			(vias allowed)
			(pads allowed)
			(copperpour not_allowed)
			(footprints allowed)
		)
		(placement
			(enabled no)
			(sheetname "")
		)
		(fill
			(thermal_gap 0.5)
			(thermal_bridge_width 0.5)
			(island_removal_mode 0)
		)
		(polygon
			(pts
				(xy 113.81486 -33.83026) (xy 113.81486 -33.96869) (xy 113.846102 -33.969706) (xy 113.850674 -33.96996)
				(xy 114.123978 -33.96996) (xy 114.12855 -33.969706) (xy 114.136678 -33.96996) (xy 114.16411 -33.96996)
				(arc
					(start 114.166904 -33.9725)
					(mid 114.244634 -33.997264)
					(end 114.310668 -34.045144)
				)
				(arc
					(start 114.310668 -34.045144)
					(mid 114.358319 -34.110979)
					(end 114.383058 -34.1884)
				)
				(xy 114.385852 -34.191194)
				(arc
					(start 114.385852 -34.215832)
					(mid 114.300901 -34.993853)
					(end 114.213386 -34.216086)
				)
				(arc
					(start 114.213386 -34.216086)
					(mid 114.205406 -34.189337)
					(end 114.189256 -34.166556)
				)
				(arc
					(start 114.189256 -34.166556)
					(mid 114.161404 -34.147946)
					(end 114.12855 -34.14141)
				)
				(xy 114.123978 -34.141156) (xy 113.850674 -34.141156) (xy 113.846102 -34.14141) (xy 113.832894 -34.141156)
				(xy 113.81486 -34.141156)
				(arc
					(start 113.81486 -34.600134)
					(mid 114.3 -35.085274)
					(end 114.78514 -34.600134)
				)
				(arc
					(start 114.78514 -33.20034)
					(mid 114.300127 -32.714946)
					(end 113.81486 -33.200086)
				)
				(arc
					(start 113.81486 -33.65627)
					(mid 113.830437 -33.658009)
					(end 113.846102 -33.658556)
				)
				(xy 113.850674 -33.658556) (xy 114.069622 -33.658556)
				(arc
					(start 114.074194 -33.658556)
					(mid 114.127655 -33.647922)
					(end 114.173 -33.617662)
				)
				(arc
					(start 114.173 -33.617662)
					(mid 114.187698 -33.600317)
					(end 114.199416 -33.580832)
				)
				(arc
					(start 114.199416 -33.580832)
					(mid 114.310835 -32.806499)
					(end 114.378486 -33.585912)
				)
				(arc
					(start 114.378486 -33.585912)
					(mid 114.347401 -33.668508)
					(end 114.294412 -33.739074)
				)
				(arc
					(start 114.294412 -33.739074)
					(mid 114.210556 -33.798851)
					(end 114.111786 -33.827974)
				)
				(xy 114.109754 -33.83026) (xy 114.083084 -33.83026) (xy 114.074194 -33.83026) (xy 114.069622 -33.83026)
				(xy 113.850674 -33.83026) (xy 113.846102 -33.83026) (xy 113.83645 -33.83026)
			)
		)
	)
	(zone
		(net "SYS_PLL_VDD")
		(layer "B.Cu")
		(hatch none 0.5)
		(connect_pads
			(clearance 0.5)
		)
		(min_thickness 0.25)
		(fill yes
			(thermal_gap 0.5)
			(thermal_bridge_width 0.5)
			(island_removal_mode 0)
		)
		(polygon
			(pts
				(xy 201.244962 -46.024038) (xy 201.244962 -46.602396) (xy 201.360024 -46.717458) (xy 201.360024 -51.8033)
				(xy 201.168254 -51.99507) (xy 201.168254 -53.232812) (xy 201.35215 -53.416708) (xy 203.112116 -53.416708)
				(xy 203.241148 -53.287676) (xy 203.241148 -52.144168) (xy 202.720194 -51.623214) (xy 202.720194 -46.932088)
				(xy 201.812144 -46.024038)
			)
		)
		(polygon
			(pts
				(xy 201.676508 -53.045868) (xy 201.473308 -53.045868) (xy 201.473308 -53.249068) (xy 201.676508 -53.249068)
			)
		)
		(polygon
			(pts
				(xy 201.676508 -52.410868) (xy 201.473308 -52.410868) (xy 201.473308 -52.893468) (xy 201.676508 -52.893468)
			)
		)
		(polygon
			(pts
				(xy 201.676508 -52.055268) (xy 201.473308 -52.055268) (xy 201.473308 -52.258468) (xy 201.676508 -52.258468)
			)
		)
		(polygon
			(pts
				(xy 202.421998 -51.769772) (xy 202.218798 -51.769772) (xy 202.218798 -51.972972) (xy 202.421998 -51.972972)
			)
		)
		(polygon
			(pts
				(xy 202.421998 -50.906172) (xy 202.218798 -50.906172) (xy 202.218798 -51.109372) (xy 202.421998 -51.109372)
			)
		)
		(polygon
			(pts
				(xy 201.923142 -46.486572) (xy 201.719942 -46.486572) (xy 201.719942 -46.689772) (xy 201.923142 -46.689772)
			)
		)
	)
	(zone
		(net "GND")
		(layer "B.Cu")
		(hatch none 0.5)
		(connect_pads
			(clearance 0.5)
		)
		(min_thickness 0.25)
		(fill yes
			(thermal_gap 0.5)
			(thermal_bridge_width 0.5)
			(island_removal_mode 0)
		)
		(polygon
			(pts
				(xy 204.153516 -125.342396) (xy 204.153516 -128.603502) (xy 207.435958 -128.603502) (xy 207.435958 -125.342396)
			)
		)
	)
	(zone
		(layer "B.Cu")
		(hatch none 0.5)
		(connect_pads
			(clearance 0)
		)
		(min_thickness 0.25)
		(keepout
			(tracks allowed)
			(vias allowed)
			(pads allowed)
			(copperpour allowed)
			(footprints not_allowed)
		)
		(placement
			(enabled no)
			(sheetname "")
		)
		(fill
			(thermal_gap 0.5)
			(thermal_bridge_width 0.5)
			(island_removal_mode 0)
		)
		(polygon
			(pts
				(arc
					(start 73.749916 -40.049958)
					(mid 78.49997 -44.800012)
					(end 83.250024 -40.049958)
				)
				(arc
					(start 83.250024 -40.049958)
					(mid 78.49997 -35.299904)
					(end 73.749916 -40.049958)
				)
			)
		)
	)
	(zone
		(layer "B.Cu")
		(hatch none 0.5)
		(connect_pads
			(clearance 0)
		)
		(min_thickness 0.25)
		(keepout
			(tracks allowed)
			(vias allowed)
			(pads allowed)
			(copperpour allowed)
			(footprints not_allowed)
		)
		(placement
			(enabled no)
			(sheetname "")
		)
		(fill
			(thermal_gap 0.5)
			(thermal_bridge_width 0.5)
			(island_removal_mode 0)
		)
		(polygon
			(pts
				(arc
					(start 73.799954 -105.050082)
					(mid 78.550008 -109.800136)
					(end 83.300062 -105.050082)
				)
				(arc
					(start 83.300062 -105.050082)
					(mid 78.550008 -100.300028)
					(end 73.799954 -105.050082)
				)
			)
		)
	)
	(zone
		(layer "B.Cu")
		(hatch none 0.5)
		(connect_pads
			(clearance 0)
		)
		(min_thickness 0.25)
		(keepout
			(tracks not_allowed)
			(vias allowed)
			(pads allowed)
			(copperpour not_allowed)
			(footprints allowed)
		)
		(placement
			(enabled no)
			(sheetname "")
		)
		(fill
			(thermal_gap 0.5)
			(thermal_bridge_width 0.5)
			(island_removal_mode 0)
		)
		(polygon
			(pts
				(arc
					(start 187.888118 -81.0641)
					(mid 187.85972 -81.057396)
					(end 187.837318 -81.0387)
				)
				(arc
					(start 187.837318 -81.2673)
					(mid 187.85972 -81.248604)
					(end 187.888118 -81.2419)
				)
				(arc
					(start 188.091318 -81.2419)
					(mid 188.119716 -81.248604)
					(end 188.142118 -81.2673)
				)
				(arc
					(start 188.142118 -81.0387)
					(mid 188.119716 -81.057396)
					(end 188.091318 -81.0641)
				)
			)
		)
	)
	(zone
		(layer "B.Cu")
		(hatch none 0.5)
		(connect_pads
			(clearance 0)
		)
		(min_thickness 0.25)
		(keepout
			(tracks allowed)
			(vias allowed)
			(pads allowed)
			(copperpour allowed)
			(footprints allowed)
		)
		(placement
			(enabled no)
			(sheetname "")
		)
		(fill
			(thermal_gap 0.5)
			(thermal_bridge_width 0.5)
			(island_removal_mode 0)
		)
		(polygon
			(pts
				(xy 200.8632 -81.8134) (xy 200.8632 -80.518) (xy 201.9554 -80.518) (xy 201.9554 -81.8134)
			)
		)
	)
	(zone
		(net "P3V3_STBY")
		(layer "B.Cu")
		(hatch none 0.5)
		(connect_pads
			(clearance 0.5)
		)
		(min_thickness 0.25)
		(fill yes
			(thermal_gap 0.5)
			(thermal_bridge_width 0.5)
			(island_removal_mode 0)
		)
		(polygon
			(pts
				(xy 51.17338 -145.523966) (xy 50.341022 -146.356324) (xy 50.341022 -147.368768) (xy 50.77714 -147.804886)
				(xy 50.77714 -148.434806) (xy 51.02098 -148.678646) (xy 51.75758 -148.678646) (xy 51.90744 -148.528786)
				(xy 51.90744 -147.947126) (xy 51.74234 -147.782026) (xy 51.53152 -147.782026) (xy 51.33086 -147.581366)
				(xy 51.33086 -147.241768) (xy 52.02682 -146.545808) (xy 52.02682 -145.683986) (xy 52.01412 -145.683986)
				(xy 51.8541 -145.523966)
			)
		)
		(polygon
			(pts
				(xy 51.13782 -147.66036) (xy 50.93462 -147.66036) (xy 50.93462 -147.86356) (xy 51.13782 -147.86356)
			)
		)
	)
	(zone
		(net "P12V_STBY")
		(layer "B.Cu")
		(hatch none 0.5)
		(connect_pads
			(clearance 0.5)
		)
		(min_thickness 0.25)
		(fill yes
			(thermal_gap 0.5)
			(thermal_bridge_width 0.5)
			(island_removal_mode 0)
		)
		(polygon
			(pts
				(xy 75.134978 -46.3296) (xy 74.857356 -46.607222) (xy 74.857356 -48.927004) (xy 75.167998 -49.237646)
				(xy 78.353158 -49.237646) (xy 78.671928 -49.556416) (xy 79.967328 -49.556416) (xy 80.030828 -49.492916)
				(xy 80.030828 -47.859696) (xy 79.774288 -47.603156) (xy 77.574394 -47.603156) (xy 76.300584 -46.3296)
			)
		)
	)
	(zone
		(layer "B.Cu")
		(hatch none 0.5)
		(connect_pads
			(clearance 0)
		)
		(min_thickness 0.25)
		(keepout
			(tracks allowed)
			(vias allowed)
			(pads allowed)
			(copperpour allowed)
			(footprints not_allowed)
		)
		(placement
			(enabled no)
			(sheetname "")
		)
		(fill
			(thermal_gap 0.5)
			(thermal_bridge_width 0.5)
			(island_removal_mode 0)
		)
		(polygon
			(pts
				(arc
					(start 126.664974 -34.854896)
					(mid 124.165106 -32.355028)
					(end 121.664984 -34.854896)
				)
				(arc
					(start 121.664984 -34.854896)
					(mid 124.165106 -37.355018)
					(end 126.664974 -34.854896)
				)
			)
		)
	)
	(zone
		(layer "B.Cu")
		(hatch none 0.5)
		(connect_pads
			(clearance 0)
		)
		(min_thickness 0.25)
		(keepout
			(tracks allowed)
			(vias allowed)
			(pads allowed)
			(copperpour allowed)
			(footprints allowed)
		)
		(placement
			(enabled no)
			(sheetname "")
		)
		(fill
			(thermal_gap 0.5)
			(thermal_bridge_width 0.5)
			(island_removal_mode 0)
		)
		(polygon
			(pts
				(xy 113.740692 -35.111182) (xy 113.740692 -32.654494) (xy 114.816382 -32.654494) (xy 114.816382 -35.111182)
			)
		)
	)
	(zone
		(layer "B.Cu")
		(hatch none 0.5)
		(connect_pads
			(clearance 0)
		)
		(min_thickness 0.25)
		(keepout
			(tracks allowed)
			(vias allowed)
			(pads allowed)
			(copperpour allowed)
			(footprints allowed)
		)
		(placement
			(enabled no)
			(sheetname "")
		)
		(fill
			(thermal_gap 0.5)
			(thermal_bridge_width 0.5)
			(island_removal_mode 0)
		)
		(polygon
			(pts
				(xy 128.140714 -38.711124) (xy 128.140714 -36.254436) (xy 129.216404 -36.254436) (xy 129.216404 -38.711124)
			)
		)
	)
	(zone
		(layer "B.Cu")
		(hatch none 0.5)
		(connect_pads
			(clearance 0)
		)
		(min_thickness 0.25)
		(keepout
			(tracks allowed)
			(vias allowed)
			(pads allowed)
			(copperpour allowed)
			(footprints not_allowed)
		)
		(placement
			(enabled no)
			(sheetname "")
		)
		(fill
			(thermal_gap 0.5)
			(thermal_bridge_width 0.5)
			(island_removal_mode 0)
		)
		(polygon
			(pts
				(arc
					(start 73.03008 -109.050074)
					(mid 72.737187 -109.757179)
					(end 72.030082 -110.050072)
				)
				(arc
					(start 31.530036 -110.050072)
					(mid 30.822931 -109.757179)
					(end 30.530038 -109.050074)
				)
				(arc
					(start 30.530038 -0.999998)
					(mid 30.237145 -0.292893)
					(end 29.53004 0)
				)
				(xy 4.99999 0)
				(arc
					(start 4.99999 -193.786252)
					(mid 5.291008 -193.945107)
					(end 5.617972 -194.00012)
				)
				(arc
					(start 98.081846 -194.00012)
					(mid 98.607673 -193.850711)
					(end 98.976434 -193.447162)
				)
				(arc
					(start 103.594408 -184.211214)
					(mid 103.673264 -183.993717)
					(end 103.700072 -183.76392)
				)
				(arc
					(start 103.700072 -47.999904)
					(mid 104.200198 -47.499778)
					(end 104.70007 -47.999904)
				)
				(arc
					(start 143.299942 -47.999904)
					(mid 143.800068 -47.499778)
					(end 144.29994 -47.999904)
				)
				(arc
					(start 144.29994 -183.76392)
					(mid 144.326704 -183.993728)
					(end 144.405604 -184.211214)
				)
				(arc
					(start 149.023578 -193.447162)
					(mid 149.392195 -193.850703)
					(end 149.917912 -194.00012)
				)
				(arc
					(start 229.382066 -194.00012)
					(mid 229.709045 -193.945151)
					(end 230.000048 -193.786252)
				)
				(xy 230.000048 0)
				(arc
					(start 74.030078 0)
					(mid 73.322973 -0.292893)
					(end 73.03008 -0.999998)
				)
			)
		)
	)
	(zone
		(layer "B.Cu")
		(hatch none 0.5)
		(connect_pads
			(clearance 0)
		)
		(min_thickness 0.25)
		(keepout
			(tracks not_allowed)
			(vias allowed)
			(pads allowed)
			(copperpour not_allowed)
			(footprints allowed)
		)
		(placement
			(enabled no)
			(sheetname "")
		)
		(fill
			(thermal_gap 0.5)
			(thermal_bridge_width 0.5)
			(island_removal_mode 0)
		)
		(polygon
			(pts
				(arc
					(start 78.505558 -83.335368)
					(mid 78.122018 -82.951828)
					(end 77.738478 -83.335368)
				)
				(arc
					(start 77.738478 -84.224114)
					(mid 78.121891 -84.607908)
					(end 78.505558 -84.224368)
				)
				(xy 78.505558 -84.021168) (xy 78.415642 -84.021168)
				(arc
					(start 78.41107 -84.021168)
					(mid 78.363245 -84.026938)
					(end 78.318106 -84.043774)
				)
				(arc
					(start 78.318106 -84.043774)
					(mid 78.003361 -84.462972)
					(end 78.146402 -83.958684)
				)
				(arc
					(start 78.146402 -83.958684)
					(mid 78.25079 -83.885329)
					(end 78.373732 -83.851242)
				)
				(xy 78.37551 -83.849464) (xy 78.401418 -83.849464) (xy 78.41107 -83.849464) (xy 78.415642 -83.849464)
				(xy 78.505558 -83.849464) (xy 78.505558 -83.709764) (xy 78.415388 -83.709764) (xy 78.410816 -83.710018)
				(xy 78.401164 -83.709764) (xy 78.375256 -83.709764)
				(arc
					(start 78.373478 -83.70824)
					(mid 78.250807 -83.674226)
					(end 78.146656 -83.601052)
				)
				(arc
					(start 78.146656 -83.601052)
					(mid 78.003607 -83.096257)
					(end 78.31836 -83.515962)
				)
				(arc
					(start 78.31836 -83.515962)
					(mid 78.363263 -83.532602)
					(end 78.410816 -83.538314)
				)
				(xy 78.415388 -83.538568) (xy 78.505558 -83.538568)
			)
		)
	)
	(zone
		(layer "B.Cu")
		(hatch none 0.5)
		(connect_pads
			(clearance 0)
		)
		(min_thickness 0.25)
		(keepout
			(tracks allowed)
			(vias allowed)
			(pads allowed)
			(copperpour allowed)
			(footprints not_allowed)
		)
		(placement
			(enabled no)
			(sheetname "")
		)
		(fill
			(thermal_gap 0.5)
			(thermal_bridge_width 0.5)
			(island_removal_mode 0)
		)
		(polygon
			(pts
				(arc
					(start 177.500026 -14.699996)
					(mid 180.000148 -17.200118)
					(end 182.500016 -14.699996)
				)
				(arc
					(start 182.500016 -14.699996)
					(mid 180.000148 -12.200128)
					(end 177.500026 -14.699996)
				)
			)
		)
	)
	(zone
		(net "GND")
		(layer "B.Cu")
		(hatch none 0.5)
		(connect_pads
			(clearance 0.5)
		)
		(min_thickness 0.25)
		(fill yes
			(thermal_gap 0.5)
			(thermal_bridge_width 0.5)
			(island_removal_mode 0)
		)
		(polygon
			(pts
				(xy 63.4619 -158.1912) (xy 63.20282 -158.45028) (xy 61.92012 -158.45028) (xy 61.86678 -158.50362)
				(xy 61.86678 -160.13938) (xy 62.327536 -160.600136) (xy 65.356994 -160.600136) (xy 65.67297 -160.28416)
				(xy 65.67297 -159.3596) (xy 64.93637 -158.623) (xy 64.93637 -158.37281) (xy 64.75476 -158.1912)
			)
		)
		(polygon
			(pts
				(xy 64.58458 -158.708598) (xy 64.38138 -158.708598) (xy 64.38138 -158.911798) (xy 64.58458 -158.911798)
			)
		)
		(polygon
			(pts
				(xy 63.97498 -158.708598) (xy 63.77178 -158.708598) (xy 63.77178 -158.911798) (xy 63.97498 -158.911798)
			)
		)
	)
	(zone
		(net "P1V15_STBY")
		(layer "B.Cu")
		(hatch none 0.5)
		(connect_pads
			(clearance 0.5)
		)
		(min_thickness 0.25)
		(fill yes
			(thermal_gap 0.5)
			(thermal_bridge_width 0.5)
			(island_removal_mode 0)
		)
		(polygon
			(pts
				(xy 47.625 -132.6896) (xy 47.498 -132.8166) (xy 47.498 -134.5184) (xy 47.8028 -134.8232) (xy 48.895 -134.8232)
				(xy 49.149 -134.5692) (xy 49.149 -134.2898) (xy 49.4792 -133.9596) (xy 54.9656 -133.9596) (xy 55.1942 -134.1882)
				(xy 56.6674 -134.1882) (xy 56.6674 -132.8166) (xy 56.5404 -132.6896)
			)
		)
		(polygon
			(pts
				(xy 49.3014 -133.7056) (xy 49.0982 -133.7056) (xy 49.0982 -133.9088) (xy 49.3014 -133.9088)
			)
		)
		(polygon
			(pts
				(xy 54.9148 -132.842) (xy 54.7116 -132.842) (xy 54.7116 -133.0452) (xy 54.9148 -133.0452)
			)
		)
		(polygon
			(pts
				(xy 54.0512 -132.842) (xy 53.848 -132.842) (xy 53.848 -133.0452) (xy 54.0512 -133.0452)
			)
		)
		(polygon
			(pts
				(xy 50.165 -132.842) (xy 49.9618 -132.842) (xy 49.9618 -133.0452) (xy 50.165 -133.0452)
			)
		)
		(polygon
			(pts
				(xy 53.73243 -132.829046) (xy 53.52923 -132.829046) (xy 53.52923 -133.032246) (xy 53.73243 -133.032246)
			)
		)
		(polygon
			(pts
				(xy 52.86883 -132.829046) (xy 52.66563 -132.829046) (xy 52.66563 -133.032246) (xy 52.86883 -133.032246)
			)
		)
		(polygon
			(pts
				(xy 52.5272 -132.8166) (xy 52.324 -132.8166) (xy 52.324 -133.0198) (xy 52.5272 -133.0198)
			)
		)
		(polygon
			(pts
				(xy 51.6636 -132.8166) (xy 51.4604 -132.8166) (xy 51.4604 -133.0198) (xy 51.6636 -133.0198)
			)
		)
		(polygon
			(pts
				(xy 51.34737 -132.804154) (xy 51.14417 -132.804154) (xy 51.14417 -133.007354) (xy 51.34737 -133.007354)
			)
		)
		(polygon
			(pts
				(xy 50.48377 -132.804154) (xy 50.28057 -132.804154) (xy 50.28057 -133.007354) (xy 50.48377 -133.007354)
			)
		)
	)
	(zone
		(layers "B.Cu" "In2.Cu")
		(hatch none 0.5)
		(connect_pads
			(clearance 0)
		)
		(min_thickness 0.25)
		(keepout
			(tracks not_allowed)
			(vias allowed)
			(pads allowed)
			(copperpour not_allowed)
			(footprints allowed)
		)
		(placement
			(enabled no)
			(sheetname "")
		)
		(fill yes
			(thermal_gap 0.5)
			(thermal_bridge_width 0.5)
			(island_removal_mode 0)
		)
		(polygon
			(pts
				(arc
					(start 83.741768 -75.305158)
					(mid 83.358228 -74.921618)
					(end 82.974688 -75.305158)
				)
				(arc
					(start 82.974688 -76.193904)
					(mid 83.356831 -76.577696)
					(end 83.741768 -76.196698)
				)
				(arc
					(start 83.624928 -76.196698)
					(mid 83.358228 -76.46087)
					(end 83.091528 -76.196698)
				)
				(arc
					(start 83.091528 -76.194158)
					(mid 83.358228 -75.927458)
					(end 83.624928 -76.194158)
				)
				(xy 83.741768 -76.194158) (xy 83.741768 -75.307698)
				(arc
					(start 83.624928 -75.307698)
					(mid 83.358228 -75.57187)
					(end 83.091528 -75.307698)
				)
				(arc
					(start 83.091528 -75.305158)
					(mid 83.358228 -75.038458)
					(end 83.624928 -75.305158)
				)
			)
		)
	)
	(zone
		(layers "B.Cu" "In2.Cu")
		(hatch none 0.5)
		(connect_pads
			(clearance 0)
		)
		(min_thickness 0.25)
		(keepout
			(tracks not_allowed)
			(vias allowed)
			(pads allowed)
			(copperpour not_allowed)
			(footprints allowed)
		)
		(placement
			(enabled no)
			(sheetname "")
		)
		(fill yes
			(thermal_gap 0.5)
			(thermal_bridge_width 0.5)
			(island_removal_mode 0)
		)
		(polygon
			(pts
				(arc
					(start 194.83197 -88.382602)
					(mid 194.596772 -88.030604)
					(end 194.181476 -88.113108)
				)
				(arc
					(start 193.557906 -88.736932)
					(mid 193.550827 -89.278046)
					(end 194.092068 -89.280492)
				)
				(xy 194.359022 -89.013538)
				(arc
					(start 194.089274 -89.013538)
					(mid 193.822574 -89.27771)
					(end 193.555874 -89.013538)
				)
				(arc
					(start 193.555874 -89.010998)
					(mid 193.822574 -88.744298)
					(end 194.089274 -89.010998)
				)
				(xy 194.361562 -89.010998)
				(arc
					(start 194.720464 -88.652096)
					(mid 194.802511 -88.529609)
					(end 194.83197 -88.385142)
				)
				(arc
					(start 194.71767 -88.385142)
					(mid 194.45097 -88.649314)
					(end 194.18427 -88.385142)
				)
				(arc
					(start 194.18427 -88.382602)
					(mid 194.45097 -88.115902)
					(end 194.71767 -88.382602)
				)
			)
		)
	)
	(zone
		(layers "B.Cu" "In2.Cu")
		(hatch none 0.5)
		(connect_pads
			(clearance 0)
		)
		(min_thickness 0.25)
		(keepout
			(tracks not_allowed)
			(vias allowed)
			(pads allowed)
			(copperpour not_allowed)
			(footprints allowed)
		)
		(placement
			(enabled no)
			(sheetname "")
		)
		(fill yes
			(thermal_gap 0.5)
			(thermal_bridge_width 0.5)
			(island_removal_mode 0)
		)
		(polygon
			(pts
				(arc
					(start 202.218798 -85.461602)
					(mid 201.9836 -85.109604)
					(end 201.568304 -85.192108)
				)
				(arc
					(start 200.944734 -85.815932)
					(mid 200.937655 -86.357046)
					(end 201.478896 -86.359492)
				)
				(xy 201.74585 -86.092538)
				(arc
					(start 201.476102 -86.092538)
					(mid 201.209402 -86.35671)
					(end 200.942702 -86.092538)
				)
				(arc
					(start 200.942702 -86.089998)
					(mid 201.209402 -85.823298)
					(end 201.476102 -86.089998)
				)
				(xy 201.74839 -86.089998)
				(arc
					(start 202.107292 -85.731096)
					(mid 202.189339 -85.608609)
					(end 202.218798 -85.464142)
				)
				(arc
					(start 202.104498 -85.464142)
					(mid 201.837798 -85.728314)
					(end 201.571098 -85.464142)
				)
				(arc
					(start 201.571098 -85.461602)
					(mid 201.837798 -85.194902)
					(end 202.104498 -85.461602)
				)
			)
		)
	)
	(zone
		(layers "B.Cu" "In2.Cu")
		(hatch none 0.5)
		(connect_pads
			(clearance 0)
		)
		(min_thickness 0.25)
		(keepout
			(tracks not_allowed)
			(vias allowed)
			(pads allowed)
			(copperpour not_allowed)
			(footprints allowed)
		)
		(placement
			(enabled no)
			(sheetname "")
		)
		(fill yes
			(thermal_gap 0.5)
			(thermal_bridge_width 0.5)
			(island_removal_mode 0)
		)
		(polygon
			(pts
				(arc
					(start 197.90537 -85.334602)
					(mid 197.670172 -84.982604)
					(end 197.254876 -85.065108)
				)
				(arc
					(start 196.631306 -85.688932)
					(mid 196.624227 -86.230046)
					(end 197.165468 -86.232492)
				)
				(xy 197.432422 -85.965538)
				(arc
					(start 197.162674 -85.965538)
					(mid 196.895974 -86.22971)
					(end 196.629274 -85.965538)
				)
				(arc
					(start 196.629274 -85.962998)
					(mid 196.895974 -85.696298)
					(end 197.162674 -85.962998)
				)
				(xy 197.434962 -85.962998)
				(arc
					(start 197.793864 -85.604096)
					(mid 197.875911 -85.481609)
					(end 197.90537 -85.337142)
				)
				(arc
					(start 197.79107 -85.337142)
					(mid 197.52437 -85.601314)
					(end 197.25767 -85.337142)
				)
				(arc
					(start 197.25767 -85.334602)
					(mid 197.52437 -85.067902)
					(end 197.79107 -85.334602)
				)
			)
		)
	)
	(zone
		(layers "B.Cu" "In2.Cu")
		(hatch none 0.5)
		(connect_pads
			(clearance 0)
		)
		(min_thickness 0.25)
		(keepout
			(tracks not_allowed)
			(vias allowed)
			(pads allowed)
			(copperpour not_allowed)
			(footprints allowed)
		)
		(placement
			(enabled no)
			(sheetname "")
		)
		(fill yes
			(thermal_gap 0.5)
			(thermal_bridge_width 0.5)
			(island_removal_mode 0)
		)
		(polygon
			(pts
				(arc
					(start 85.367368 -91.306396)
					(mid 84.983828 -90.922856)
					(end 84.600288 -91.306396)
				)
				(arc
					(start 84.600288 -92.195142)
					(mid 84.982431 -92.578934)
					(end 85.367368 -92.197936)
				)
				(arc
					(start 85.250528 -92.197936)
					(mid 84.983828 -92.462108)
					(end 84.717128 -92.197936)
				)
				(arc
					(start 84.717128 -92.195396)
					(mid 84.983828 -91.928696)
					(end 85.250528 -92.195396)
				)
				(xy 85.367368 -92.195396) (xy 85.367368 -91.308936)
				(arc
					(start 85.250528 -91.308936)
					(mid 84.983828 -91.573108)
					(end 84.717128 -91.308936)
				)
				(arc
					(start 84.717128 -91.306396)
					(mid 84.983828 -91.039696)
					(end 85.250528 -91.306396)
				)
			)
		)
	)
	(zone
		(layers "B.Cu" "In2.Cu")
		(hatch none 0.5)
		(connect_pads
			(clearance 0)
		)
		(min_thickness 0.25)
		(keepout
			(tracks not_allowed)
			(vias allowed)
			(pads allowed)
			(copperpour not_allowed)
			(footprints allowed)
		)
		(placement
			(enabled no)
			(sheetname "")
		)
		(fill yes
			(thermal_gap 0.5)
			(thermal_bridge_width 0.5)
			(island_removal_mode 0)
		)
		(polygon
			(pts
				(arc
					(start 85.367368 -72.081136)
					(mid 84.983828 -71.697596)
					(end 84.600288 -72.081136)
				)
				(arc
					(start 84.600288 -72.970136)
					(mid 84.982558 -73.353674)
					(end 85.367368 -72.972676)
				)
				(arc
					(start 85.250528 -72.972676)
					(mid 84.983828 -73.236848)
					(end 84.717128 -72.972676)
				)
				(arc
					(start 84.717128 -72.970136)
					(mid 84.983828 -72.703436)
					(end 85.250528 -72.970136)
				)
				(xy 85.367368 -72.970136) (xy 85.367368 -72.083676)
				(arc
					(start 85.250528 -72.083676)
					(mid 84.983828 -72.347848)
					(end 84.717128 -72.083676)
				)
				(arc
					(start 84.717128 -72.081136)
					(mid 84.983828 -71.814436)
					(end 85.250528 -72.081136)
				)
			)
		)
	)
	(zone
		(layers "B.Cu" "In2.Cu")
		(hatch none 0.5)
		(connect_pads
			(clearance 0)
		)
		(min_thickness 0.25)
		(keepout
			(tracks not_allowed)
			(vias allowed)
			(pads allowed)
			(copperpour not_allowed)
			(footprints allowed)
		)
		(placement
			(enabled no)
			(sheetname "")
		)
		(fill yes
			(thermal_gap 0.5)
			(thermal_bridge_width 0.5)
			(island_removal_mode 0)
		)
		(polygon
			(pts
				(arc
					(start 85.367368 -78.504796)
					(mid 84.983828 -78.121256)
					(end 84.600288 -78.504796)
				)
				(arc
					(start 84.600288 -79.393542)
					(mid 84.982431 -79.777334)
					(end 85.367368 -79.396336)
				)
				(arc
					(start 85.250528 -79.396336)
					(mid 84.983828 -79.660508)
					(end 84.717128 -79.396336)
				)
				(arc
					(start 84.717128 -79.393796)
					(mid 84.983828 -79.127096)
					(end 85.250528 -79.393796)
				)
				(xy 85.367368 -79.393796) (xy 85.367368 -78.507336)
				(arc
					(start 85.250528 -78.507336)
					(mid 84.983828 -78.771508)
					(end 84.717128 -78.507336)
				)
				(arc
					(start 84.717128 -78.504796)
					(mid 84.983828 -78.238096)
					(end 85.250528 -78.504796)
				)
			)
		)
	)
	(zone
		(layers "B.Cu" "In2.Cu")
		(hatch none 0.5)
		(connect_pads
			(clearance 0)
		)
		(min_thickness 0.25)
		(keepout
			(tracks not_allowed)
			(vias allowed)
			(pads allowed)
			(copperpour not_allowed)
			(footprints allowed)
		)
		(placement
			(enabled no)
			(sheetname "")
		)
		(fill yes
			(thermal_gap 0.5)
			(thermal_bridge_width 0.5)
			(island_removal_mode 0)
		)
		(polygon
			(pts
				(arc
					(start 192.109598 -86.680802)
					(mid 191.8744 -86.328804)
					(end 191.459104 -86.411308)
				)
				(arc
					(start 190.835534 -87.035132)
					(mid 190.828455 -87.576246)
					(end 191.369696 -87.578692)
				)
				(xy 191.63665 -87.311738)
				(arc
					(start 191.366902 -87.311738)
					(mid 191.100202 -87.57591)
					(end 190.833502 -87.311738)
				)
				(arc
					(start 190.833502 -87.309198)
					(mid 191.100202 -87.042498)
					(end 191.366902 -87.309198)
				)
				(xy 191.63919 -87.309198)
				(arc
					(start 191.998092 -86.950296)
					(mid 192.080139 -86.827809)
					(end 192.109598 -86.683342)
				)
				(arc
					(start 191.995298 -86.683342)
					(mid 191.728598 -86.947514)
					(end 191.461898 -86.683342)
				)
				(arc
					(start 191.461898 -86.680802)
					(mid 191.728598 -86.414102)
					(end 191.995298 -86.680802)
				)
			)
		)
	)
	(zone
		(layers "B.Cu" "In2.Cu")
		(hatch none 0.5)
		(connect_pads
			(clearance 0)
		)
		(min_thickness 0.25)
		(keepout
			(tracks not_allowed)
			(vias allowed)
			(pads allowed)
			(copperpour not_allowed)
			(footprints allowed)
		)
		(placement
			(enabled no)
			(sheetname "")
		)
		(fill yes
			(thermal_gap 0.5)
			(thermal_bridge_width 0.5)
			(island_removal_mode 0)
		)
		(polygon
			(pts
				(arc
					(start 195.055998 -83.658202)
					(mid 194.8208 -83.306204)
					(end 194.405504 -83.388708)
				)
				(arc
					(start 193.781934 -84.012532)
					(mid 193.774855 -84.553646)
					(end 194.316096 -84.556092)
				)
				(xy 194.58305 -84.289138)
				(arc
					(start 194.313302 -84.289138)
					(mid 194.046602 -84.55331)
					(end 193.779902 -84.289138)
				)
				(arc
					(start 193.779902 -84.286598)
					(mid 194.046602 -84.019898)
					(end 194.313302 -84.286598)
				)
				(xy 194.58559 -84.286598)
				(arc
					(start 194.944492 -83.927696)
					(mid 195.026539 -83.805209)
					(end 195.055998 -83.660742)
				)
				(arc
					(start 194.941698 -83.660742)
					(mid 194.674998 -83.924914)
					(end 194.408298 -83.660742)
				)
				(arc
					(start 194.408298 -83.658202)
					(mid 194.674998 -83.391502)
					(end 194.941698 -83.658202)
				)
			)
		)
	)
	(zone
		(layers "B.Cu" "In2.Cu")
		(hatch none 0.5)
		(connect_pads
			(clearance 0)
		)
		(min_thickness 0.25)
		(keepout
			(tracks not_allowed)
			(vias allowed)
			(pads allowed)
			(copperpour not_allowed)
			(footprints allowed)
		)
		(placement
			(enabled no)
			(sheetname "")
		)
		(fill yes
			(thermal_gap 0.5)
			(thermal_bridge_width 0.5)
			(island_removal_mode 0)
		)
		(polygon
			(pts
				(arc
					(start 213.89086 -67.210686)
					(mid 213.655819 -66.858923)
					(end 213.240874 -66.941446)
				)
				(xy 213.24062 -66.941192) (xy 212.432392 -67.74942)
				(arc
					(start 212.432646 -67.749674)
					(mid 212.432646 -68.288154)
					(end 212.971126 -68.288154)
				)
				(xy 212.97138 -68.288408) (xy 213.238334 -68.021454)
				(arc
					(start 212.968586 -68.021454)
					(mid 212.701886 -68.285626)
					(end 212.435186 -68.021454)
				)
				(arc
					(start 212.435186 -68.018914)
					(mid 212.701886 -67.752214)
					(end 212.968586 -68.018914)
				)
				(xy 213.240874 -68.018914) (xy 213.779354 -67.48018)
				(arc
					(start 213.779354 -67.479926)
					(mid 213.861405 -67.35757)
					(end 213.89086 -67.213226)
				)
				(arc
					(start 213.776814 -67.213226)
					(mid 213.510114 -67.477398)
					(end 213.243414 -67.213226)
				)
				(arc
					(start 213.243414 -67.210686)
					(mid 213.510114 -66.943986)
					(end 213.776814 -67.210686)
				)
			)
		)
	)
	(zone
		(layers "B.Cu" "In2.Cu")
		(hatch none 0.5)
		(connect_pads
			(clearance 0)
		)
		(min_thickness 0.25)
		(keepout
			(tracks not_allowed)
			(vias allowed)
			(pads allowed)
			(copperpour not_allowed)
			(footprints allowed)
		)
		(placement
			(enabled no)
			(sheetname "")
		)
		(fill yes
			(thermal_gap 0.5)
			(thermal_bridge_width 0.5)
			(island_removal_mode 0)
		)
		(polygon
			(pts
				(arc
					(start 212.41766 -65.559686)
					(mid 212.182619 -65.207923)
					(end 211.767674 -65.290446)
				)
				(xy 211.76742 -65.290192) (xy 210.959192 -66.09842)
				(arc
					(start 210.959446 -66.098674)
					(mid 210.959446 -66.637154)
					(end 211.497926 -66.637154)
				)
				(xy 211.49818 -66.637408) (xy 211.765134 -66.370454)
				(arc
					(start 211.495386 -66.370454)
					(mid 211.228686 -66.634626)
					(end 210.961986 -66.370454)
				)
				(arc
					(start 210.961986 -66.367914)
					(mid 211.228686 -66.101214)
					(end 211.495386 -66.367914)
				)
				(xy 211.767674 -66.367914) (xy 212.306154 -65.82918)
				(arc
					(start 212.306154 -65.828926)
					(mid 212.388205 -65.70657)
					(end 212.41766 -65.562226)
				)
				(arc
					(start 212.303614 -65.562226)
					(mid 212.036914 -65.826398)
					(end 211.770214 -65.562226)
				)
				(arc
					(start 211.770214 -65.559686)
					(mid 212.036914 -65.292986)
					(end 212.303614 -65.559686)
				)
			)
		)
	)
	(zone
		(layers "B.Cu" "In2.Cu")
		(hatch none 0.5)
		(connect_pads
			(clearance 0)
		)
		(min_thickness 0.25)
		(keepout
			(tracks not_allowed)
			(vias allowed)
			(pads allowed)
			(copperpour not_allowed)
			(footprints allowed)
		)
		(placement
			(enabled no)
			(sheetname "")
		)
		(fill yes
			(thermal_gap 0.5)
			(thermal_bridge_width 0.5)
			(island_removal_mode 0)
		)
		(polygon
			(pts
				(arc
					(start 190.560198 -83.886802)
					(mid 190.325 -83.534804)
					(end 189.909704 -83.617308)
				)
				(arc
					(start 189.286134 -84.241132)
					(mid 189.279055 -84.782246)
					(end 189.820296 -84.784692)
				)
				(xy 190.08725 -84.517738)
				(arc
					(start 189.817502 -84.517738)
					(mid 189.550802 -84.78191)
					(end 189.284102 -84.517738)
				)
				(arc
					(start 189.284102 -84.515198)
					(mid 189.550802 -84.248498)
					(end 189.817502 -84.515198)
				)
				(xy 190.08979 -84.515198)
				(arc
					(start 190.448692 -84.156296)
					(mid 190.530739 -84.033809)
					(end 190.560198 -83.889342)
				)
				(arc
					(start 190.445898 -83.889342)
					(mid 190.179198 -84.153514)
					(end 189.912498 -83.889342)
				)
				(arc
					(start 189.912498 -83.886802)
					(mid 190.179198 -83.620102)
					(end 190.445898 -83.886802)
				)
			)
		)
	)
	(zone
		(layers "B.Cu" "In2.Cu")
		(hatch none 0.5)
		(connect_pads
			(clearance 0)
		)
		(min_thickness 0.25)
		(keepout
			(tracks not_allowed)
			(vias allowed)
			(pads allowed)
			(copperpour not_allowed)
			(footprints allowed)
		)
		(placement
			(enabled no)
			(sheetname "")
		)
		(fill yes
			(thermal_gap 0.5)
			(thermal_bridge_width 0.5)
			(island_removal_mode 0)
		)
		(polygon
			(pts
				(arc
					(start 83.741768 -94.492572)
					(mid 83.358228 -94.109032)
					(end 82.974688 -94.492572)
				)
				(arc
					(start 82.974688 -95.381318)
					(mid 83.356831 -95.76511)
					(end 83.741768 -95.384112)
				)
				(arc
					(start 83.624928 -95.384112)
					(mid 83.358228 -95.648284)
					(end 83.091528 -95.384112)
				)
				(arc
					(start 83.091528 -95.381572)
					(mid 83.358228 -95.114872)
					(end 83.624928 -95.381572)
				)
				(xy 83.741768 -95.381572) (xy 83.741768 -94.495112)
				(arc
					(start 83.624928 -94.495112)
					(mid 83.358228 -94.759284)
					(end 83.091528 -94.495112)
				)
				(arc
					(start 83.091528 -94.492572)
					(mid 83.358228 -94.225872)
					(end 83.624928 -94.492572)
				)
			)
		)
	)
	(zone
		(layers "B.Cu" "In2.Cu")
		(hatch none 0.5)
		(connect_pads
			(clearance 0)
		)
		(min_thickness 0.25)
		(keepout
			(tracks not_allowed)
			(vias allowed)
			(pads allowed)
			(copperpour not_allowed)
			(footprints allowed)
		)
		(placement
			(enabled no)
			(sheetname "")
		)
		(fill yes
			(thermal_gap 0.5)
			(thermal_bridge_width 0.5)
			(island_removal_mode 0)
		)
		(polygon
			(pts
				(arc
					(start 199.196198 -88.458802)
					(mid 198.961 -88.106804)
					(end 198.545704 -88.189308)
				)
				(arc
					(start 197.922134 -88.813132)
					(mid 197.915055 -89.354246)
					(end 198.456296 -89.356692)
				)
				(xy 198.72325 -89.089738)
				(arc
					(start 198.453502 -89.089738)
					(mid 198.186802 -89.35391)
					(end 197.920102 -89.089738)
				)
				(arc
					(start 197.920102 -89.087198)
					(mid 198.186802 -88.820498)
					(end 198.453502 -89.087198)
				)
				(xy 198.72579 -89.087198)
				(arc
					(start 199.084692 -88.728296)
					(mid 199.166739 -88.605809)
					(end 199.196198 -88.461342)
				)
				(arc
					(start 199.081898 -88.461342)
					(mid 198.815198 -88.725514)
					(end 198.548498 -88.461342)
				)
				(arc
					(start 198.548498 -88.458802)
					(mid 198.815198 -88.192102)
					(end 199.081898 -88.458802)
				)
			)
		)
	)
	(zone
		(layers "B.Cu" "In2.Cu")
		(hatch none 0.5)
		(connect_pads
			(clearance 0)
		)
		(min_thickness 0.25)
		(keepout
			(tracks not_allowed)
			(vias allowed)
			(pads allowed)
			(copperpour not_allowed)
			(footprints allowed)
		)
		(placement
			(enabled no)
			(sheetname "")
		)
		(fill yes
			(thermal_gap 0.5)
			(thermal_bridge_width 0.5)
			(island_removal_mode 0)
		)
		(polygon
			(pts
				(arc
					(start 216.68486 -78.843886)
					(mid 216.449819 -78.492123)
					(end 216.034874 -78.574646)
				)
				(xy 216.03462 -78.574392) (xy 215.226392 -79.38262)
				(arc
					(start 215.226646 -79.382874)
					(mid 215.226646 -79.921354)
					(end 215.765126 -79.921354)
				)
				(xy 215.76538 -79.921608) (xy 216.032334 -79.654654)
				(arc
					(start 215.762586 -79.654654)
					(mid 215.495886 -79.918826)
					(end 215.229186 -79.654654)
				)
				(arc
					(start 215.229186 -79.652114)
					(mid 215.495886 -79.385414)
					(end 215.762586 -79.652114)
				)
				(xy 216.034874 -79.652114) (xy 216.573354 -79.11338)
				(arc
					(start 216.573354 -79.113126)
					(mid 216.655405 -78.99077)
					(end 216.68486 -78.846426)
				)
				(arc
					(start 216.570814 -78.846426)
					(mid 216.304114 -79.110598)
					(end 216.037414 -78.846426)
				)
				(arc
					(start 216.037414 -78.843886)
					(mid 216.304114 -78.577186)
					(end 216.570814 -78.843886)
				)
			)
		)
	)
	(zone
		(layers "B.Cu" "In2.Cu")
		(hatch none 0.5)
		(connect_pads
			(clearance 0)
		)
		(min_thickness 0.25)
		(keepout
			(tracks not_allowed)
			(vias allowed)
			(pads allowed)
			(copperpour not_allowed)
			(footprints allowed)
		)
		(placement
			(enabled no)
			(sheetname "")
		)
		(fill yes
			(thermal_gap 0.5)
			(thermal_bridge_width 0.5)
			(island_removal_mode 0)
		)
		(polygon
			(pts
				(arc
					(start 83.741768 -88.105234)
					(mid 83.358228 -87.721694)
					(end 82.974688 -88.105234)
				)
				(arc
					(start 82.974688 -88.994234)
					(mid 83.356958 -89.377772)
					(end 83.741768 -88.996774)
				)
				(arc
					(start 83.624928 -88.996774)
					(mid 83.358228 -89.260946)
					(end 83.091528 -88.996774)
				)
				(arc
					(start 83.091528 -88.994234)
					(mid 83.358228 -88.727534)
					(end 83.624928 -88.994234)
				)
				(xy 83.741768 -88.994234) (xy 83.741768 -88.107774)
				(arc
					(start 83.624928 -88.107774)
					(mid 83.358228 -88.371946)
					(end 83.091528 -88.107774)
				)
				(arc
					(start 83.091528 -88.105234)
					(mid 83.358228 -87.838534)
					(end 83.624928 -88.105234)
				)
			)
		)
	)
	(zone
		(layers "B.Cu" "In2.Cu")
		(hatch none 0.5)
		(connect_pads
			(clearance 0)
		)
		(min_thickness 0.25)
		(keepout
			(tracks not_allowed)
			(vias allowed)
			(pads allowed)
			(copperpour not_allowed)
			(footprints allowed)
		)
		(placement
			(enabled no)
			(sheetname "")
		)
		(fill yes
			(thermal_gap 0.5)
			(thermal_bridge_width 0.5)
			(island_removal_mode 0)
		)
		(polygon
			(pts
				(arc
					(start 214.90686 -71.985886)
					(mid 214.671819 -71.634123)
					(end 214.256874 -71.716646)
				)
				(xy 214.25662 -71.716392) (xy 213.448392 -72.52462)
				(arc
					(start 213.448646 -72.524874)
					(mid 213.448646 -73.063354)
					(end 213.987126 -73.063354)
				)
				(xy 213.98738 -73.063608) (xy 214.254334 -72.796654)
				(arc
					(start 213.984586 -72.796654)
					(mid 213.717886 -73.060826)
					(end 213.451186 -72.796654)
				)
				(arc
					(start 213.451186 -72.794114)
					(mid 213.717886 -72.527414)
					(end 213.984586 -72.794114)
				)
				(xy 214.256874 -72.794114) (xy 214.795354 -72.25538)
				(arc
					(start 214.795354 -72.255126)
					(mid 214.877405 -72.13277)
					(end 214.90686 -71.988426)
				)
				(arc
					(start 214.792814 -71.988426)
					(mid 214.526114 -72.252598)
					(end 214.259414 -71.988426)
				)
				(arc
					(start 214.259414 -71.985886)
					(mid 214.526114 -71.719186)
					(end 214.792814 -71.985886)
				)
			)
		)
	)
	(zone
		(layers "B.Cu" "In2.Cu")
		(hatch none 0.5)
		(connect_pads
			(clearance 0)
		)
		(min_thickness 0.25)
		(keepout
			(tracks not_allowed)
			(vias allowed)
			(pads allowed)
			(copperpour not_allowed)
			(footprints allowed)
		)
		(placement
			(enabled no)
			(sheetname "")
		)
		(fill yes
			(thermal_gap 0.5)
			(thermal_bridge_width 0.5)
			(island_removal_mode 0)
		)
		(polygon
			(pts
				(arc
					(start 216.30386 -73.382886)
					(mid 216.068819 -73.031123)
					(end 215.653874 -73.113646)
				)
				(xy 215.65362 -73.113392) (xy 214.845392 -73.92162)
				(arc
					(start 214.845646 -73.921874)
					(mid 214.845646 -74.460354)
					(end 215.384126 -74.460354)
				)
				(xy 215.38438 -74.460608) (xy 215.651334 -74.193654)
				(arc
					(start 215.381586 -74.193654)
					(mid 215.114886 -74.457826)
					(end 214.848186 -74.193654)
				)
				(arc
					(start 214.848186 -74.191114)
					(mid 215.114886 -73.924414)
					(end 215.381586 -74.191114)
				)
				(xy 215.653874 -74.191114) (xy 216.192354 -73.65238)
				(arc
					(start 216.192354 -73.652126)
					(mid 216.274405 -73.52977)
					(end 216.30386 -73.385426)
				)
				(arc
					(start 216.189814 -73.385426)
					(mid 215.923114 -73.649598)
					(end 215.656414 -73.385426)
				)
				(arc
					(start 215.656414 -73.382886)
					(mid 215.923114 -73.116186)
					(end 216.189814 -73.382886)
				)
			)
		)
	)
	(zone
		(layers "B.Cu" "In2.Cu")
		(hatch none 0.5)
		(connect_pads
			(clearance 0)
		)
		(min_thickness 0.25)
		(keepout
			(tracks not_allowed)
			(vias allowed)
			(pads allowed)
			(copperpour not_allowed)
			(footprints allowed)
		)
		(placement
			(enabled no)
			(sheetname "")
		)
		(fill yes
			(thermal_gap 0.5)
			(thermal_bridge_width 0.5)
			(island_removal_mode 0)
		)
		(polygon
			(pts
				(arc
					(start 215.41486 -68.683886)
					(mid 215.179819 -68.332123)
					(end 214.764874 -68.414646)
				)
				(xy 214.76462 -68.414392) (xy 213.956392 -69.22262)
				(arc
					(start 213.956646 -69.222874)
					(mid 213.956646 -69.761354)
					(end 214.495126 -69.761354)
				)
				(xy 214.49538 -69.761608) (xy 214.762334 -69.494654)
				(arc
					(start 214.492586 -69.494654)
					(mid 214.225886 -69.758826)
					(end 213.959186 -69.494654)
				)
				(arc
					(start 213.959186 -69.492114)
					(mid 214.225886 -69.225414)
					(end 214.492586 -69.492114)
				)
				(xy 214.764874 -69.492114) (xy 215.303354 -68.95338)
				(arc
					(start 215.303354 -68.953126)
					(mid 215.385405 -68.83077)
					(end 215.41486 -68.686426)
				)
				(arc
					(start 215.300814 -68.686426)
					(mid 215.034114 -68.950598)
					(end 214.767414 -68.686426)
				)
				(arc
					(start 214.767414 -68.683886)
					(mid 215.034114 -68.417186)
					(end 215.300814 -68.683886)
				)
			)
		)
	)
	(zone
		(layers "B.Cu" "In2.Cu")
		(hatch none 0.5)
		(connect_pads
			(clearance 0)
		)
		(min_thickness 0.25)
		(keepout
			(tracks not_allowed)
			(vias allowed)
			(pads allowed)
			(copperpour not_allowed)
			(footprints allowed)
		)
		(placement
			(enabled no)
			(sheetname "")
		)
		(fill yes
			(thermal_gap 0.5)
			(thermal_bridge_width 0.5)
			(island_removal_mode 0)
		)
		(polygon
			(pts
				(arc
					(start 85.367368 -84.904834)
					(mid 84.983828 -84.521294)
					(end 84.600288 -84.904834)
				)
				(arc
					(start 84.600288 -85.79358)
					(mid 84.982431 -86.177372)
					(end 85.367368 -85.796374)
				)
				(arc
					(start 85.250528 -85.796374)
					(mid 84.983828 -86.060546)
					(end 84.717128 -85.796374)
				)
				(arc
					(start 84.717128 -85.793834)
					(mid 84.983828 -85.527134)
					(end 85.250528 -85.793834)
				)
				(xy 85.367368 -85.793834) (xy 85.367368 -84.907374)
				(arc
					(start 85.250528 -84.907374)
					(mid 84.983828 -85.171546)
					(end 84.717128 -84.907374)
				)
				(arc
					(start 84.717128 -84.904834)
					(mid 84.983828 -84.638134)
					(end 85.250528 -84.904834)
				)
			)
		)
	)
	(zone
		(layers "B.Cu" "In2.Cu")
		(hatch none 0.5)
		(connect_pads
			(clearance 0)
		)
		(min_thickness 0.25)
		(keepout
			(tracks not_allowed)
			(vias allowed)
			(pads allowed)
			(copperpour not_allowed)
			(footprints allowed)
		)
		(placement
			(enabled no)
			(sheetname "")
		)
		(fill yes
			(thermal_gap 0.5)
			(thermal_bridge_width 0.5)
			(island_removal_mode 0)
		)
		(polygon
			(pts
				(arc
					(start 83.741768 -81.705196)
					(mid 83.358228 -81.321656)
					(end 82.974688 -81.705196)
				)
				(arc
					(start 82.974688 -82.593942)
					(mid 83.356831 -82.977734)
					(end 83.741768 -82.596736)
				)
				(arc
					(start 83.624928 -82.596736)
					(mid 83.358228 -82.860908)
					(end 83.091528 -82.596736)
				)
				(arc
					(start 83.091528 -82.594196)
					(mid 83.358228 -82.327496)
					(end 83.624928 -82.594196)
				)
				(xy 83.741768 -82.594196) (xy 83.741768 -81.707736)
				(arc
					(start 83.624928 -81.707736)
					(mid 83.358228 -81.971908)
					(end 83.091528 -81.707736)
				)
				(arc
					(start 83.091528 -81.705196)
					(mid 83.358228 -81.438496)
					(end 83.624928 -81.705196)
				)
			)
		)
	)
	(zone
		(layers "B.Cu" "In2.Cu")
		(hatch none 0.5)
		(connect_pads
			(clearance 0)
		)
		(min_thickness 0.25)
		(keepout
			(tracks not_allowed)
			(vias allowed)
			(pads allowed)
			(copperpour not_allowed)
			(footprints allowed)
		)
		(placement
			(enabled no)
			(sheetname "")
		)
		(fill yes
			(thermal_gap 0.5)
			(thermal_bridge_width 0.5)
			(island_removal_mode 0)
		)
		(polygon
			(pts
				(arc
					(start 217.82786 -74.906886)
					(mid 217.592819 -74.555123)
					(end 217.177874 -74.637646)
				)
				(xy 217.17762 -74.637392) (xy 216.369392 -75.44562)
				(arc
					(start 216.369646 -75.445874)
					(mid 216.369646 -75.984354)
					(end 216.908126 -75.984354)
				)
				(xy 216.90838 -75.984608) (xy 217.175334 -75.717654)
				(arc
					(start 216.905586 -75.717654)
					(mid 216.638886 -75.981826)
					(end 216.372186 -75.717654)
				)
				(arc
					(start 216.372186 -75.715114)
					(mid 216.638886 -75.448414)
					(end 216.905586 -75.715114)
				)
				(xy 217.177874 -75.715114) (xy 217.716354 -75.17638)
				(arc
					(start 217.716354 -75.176126)
					(mid 217.798405 -75.05377)
					(end 217.82786 -74.909426)
				)
				(arc
					(start 217.713814 -74.909426)
					(mid 217.447114 -75.173598)
					(end 217.180414 -74.909426)
				)
				(arc
					(start 217.180414 -74.906886)
					(mid 217.447114 -74.640186)
					(end 217.713814 -74.906886)
				)
			)
		)
	)
	(zone
		(layers "B.Cu" "In2.Cu")
		(hatch none 0.5)
		(connect_pads
			(clearance 0)
		)
		(min_thickness 0.25)
		(keepout
			(tracks not_allowed)
			(vias allowed)
			(pads allowed)
			(copperpour not_allowed)
			(footprints allowed)
		)
		(placement
			(enabled no)
			(sheetname "")
		)
		(fill yes
			(thermal_gap 0.5)
			(thermal_bridge_width 0.5)
			(island_removal_mode 0)
		)
		(polygon
			(pts
				(arc
					(start 212.249004 -63.11646)
					(mid 212.013963 -62.764697)
					(end 211.599018 -62.84722)
				)
				(xy 211.598764 -62.846966) (xy 210.790536 -63.655194)
				(arc
					(start 210.79079 -63.655448)
					(mid 210.79079 -64.193928)
					(end 211.32927 -64.193928)
				)
				(xy 211.329524 -64.194182) (xy 211.596478 -63.927228)
				(arc
					(start 211.32673 -63.927228)
					(mid 211.06003 -64.1914)
					(end 210.79333 -63.927228)
				)
				(arc
					(start 210.79333 -63.924688)
					(mid 211.06003 -63.657988)
					(end 211.32673 -63.924688)
				)
				(xy 211.599018 -63.924688) (xy 212.137498 -63.385954)
				(arc
					(start 212.137498 -63.3857)
					(mid 212.219549 -63.263344)
					(end 212.249004 -63.119)
				)
				(arc
					(start 212.134958 -63.119)
					(mid 211.868258 -63.383172)
					(end 211.601558 -63.119)
				)
				(arc
					(start 211.601558 -63.11646)
					(mid 211.868258 -62.84976)
					(end 212.134958 -63.11646)
				)
			)
		)
	)
	(zone
		(layers "B.Cu" "In2.Cu")
		(hatch none 0.5)
		(connect_pads
			(clearance 0)
		)
		(min_thickness 0.25)
		(keepout
			(tracks not_allowed)
			(vias allowed)
			(pads allowed)
			(copperpour not_allowed)
			(footprints allowed)
		)
		(placement
			(enabled no)
			(sheetname "")
		)
		(fill yes
			(thermal_gap 0.5)
			(thermal_bridge_width 0.5)
			(island_removal_mode 0)
		)
		(polygon
			(pts
				(arc
					(start 204.809598 -84.877402)
					(mid 204.5744 -84.525404)
					(end 204.159104 -84.607908)
				)
				(arc
					(start 203.535534 -85.231732)
					(mid 203.528455 -85.772846)
					(end 204.069696 -85.775292)
				)
				(xy 204.33665 -85.508338)
				(arc
					(start 204.066902 -85.508338)
					(mid 203.800202 -85.77251)
					(end 203.533502 -85.508338)
				)
				(arc
					(start 203.533502 -85.505798)
					(mid 203.800202 -85.239098)
					(end 204.066902 -85.505798)
				)
				(xy 204.33919 -85.505798)
				(arc
					(start 204.698092 -85.146896)
					(mid 204.780139 -85.024409)
					(end 204.809598 -84.879942)
				)
				(arc
					(start 204.695298 -84.879942)
					(mid 204.428598 -85.144114)
					(end 204.161898 -84.879942)
				)
				(arc
					(start 204.161898 -84.877402)
					(mid 204.428598 -84.610702)
					(end 204.695298 -84.877402)
				)
			)
		)
	)
	(zone
		(layers "B.Cu" "In2.Cu" "In3.Cu" "In4.Cu" "In5.Cu")
		(hatch none 0.5)
		(connect_pads
			(clearance 0)
		)
		(min_thickness 0.25)
		(keepout
			(tracks not_allowed)
			(vias allowed)
			(pads allowed)
			(copperpour not_allowed)
			(footprints allowed)
		)
		(placement
			(enabled no)
			(sheetname "")
		)
		(fill yes
			(thermal_gap 0.5)
			(thermal_bridge_width 0.5)
			(island_removal_mode 0)
		)
		(polygon
			(pts
				(arc
					(start 84.749894 -120.000014)
					(mid 80.000094 -115.250214)
					(end 75.25004 -120.000014)
				)
				(arc
					(start 75.25004 -120.000014)
					(mid 80.000094 -124.750068)
					(end 84.749894 -120.000014)
				)
			)
		)
	)
	(zone
		(layers "B.Cu" "In2.Cu" "In5.Cu" "Cmts.User")
		(hatch none 0.5)
		(connect_pads
			(clearance 0)
		)
		(min_thickness 0.25)
		(keepout
			(tracks allowed)
			(vias allowed)
			(pads allowed)
			(copperpour allowed)
			(footprints allowed)
		)
		(placement
			(enabled no)
			(sheetname "")
		)
		(fill yes
			(thermal_gap 0.5)
			(thermal_bridge_width 0.5)
			(island_removal_mode 0)
		)
		(polygon
			(pts
				(xy 24.63673 -150.308564) (xy 24.63673 -134.585964) (xy 15.08633 -134.585964) (xy 15.08633 -150.308564)
			)
		)
	)
	(zone
		(layers "B.Cu" "In5.Cu")
		(hatch none 0.5)
		(connect_pads
			(clearance 0)
		)
		(min_thickness 0.25)
		(keepout
			(tracks not_allowed)
			(vias allowed)
			(pads allowed)
			(copperpour not_allowed)
			(footprints allowed)
		)
		(placement
			(enabled no)
			(sheetname "")
		)
		(fill yes
			(thermal_gap 0.5)
			(thermal_bridge_width 0.5)
			(island_removal_mode 0)
		)
		(polygon
			(pts
				(xy 90.7034 -163.4744) (xy 94.5134 -163.4744) (xy 94.5134 -166.116) (xy 90.7034 -166.116)
			)
		)
	)
	(zone
		(layers "B.Cu" "In5.Cu")
		(hatch none 0.5)
		(connect_pads
			(clearance 0)
		)
		(min_thickness 0.25)
		(keepout
			(tracks not_allowed)
			(vias allowed)
			(pads allowed)
			(copperpour not_allowed)
			(footprints allowed)
		)
		(placement
			(enabled no)
			(sheetname "")
		)
		(fill yes
			(thermal_gap 0.5)
			(thermal_bridge_width 0.5)
			(island_removal_mode 0)
		)
		(polygon
			(pts
				(xy 67.9958 -154.9654) (xy 71.8058 -154.9654) (xy 71.8058 -157.607) (xy 67.9958 -157.607)
			)
		)
	)
	(zone
		(layers "B.Cu" "Cmts.User")
		(hatch none 0.5)
		(connect_pads
			(clearance 0)
		)
		(min_thickness 0.25)
		(keepout
			(tracks allowed)
			(vias allowed)
			(pads allowed)
			(copperpour allowed)
			(footprints allowed)
		)
		(placement
			(enabled no)
			(sheetname "")
		)
		(fill yes
			(thermal_gap 0.5)
			(thermal_bridge_width 0.5)
			(island_removal_mode 0)
		)
		(polygon
			(pts
				(xy 140.740638 -37.511228) (xy 140.740638 -35.05454) (xy 141.816328 -35.05454) (xy 141.816328 -37.511228)
			)
		)
	)
	(zone
		(net "AGND_CURRENT_MON")
		(layer "In1.Cu")
		(hatch none 0.5)
		(connect_pads
			(clearance 0.5)
		)
		(min_thickness 0.25)
		(fill yes
			(thermal_gap 0.5)
			(thermal_bridge_width 0.5)
			(island_removal_mode 0)
		)
		(polygon
			(pts
				(xy 119.854726 -4.235958) (xy 119.374158 -4.716526) (xy 111.976408 -4.716526) (xy 109.92866 -6.764274)
				(xy 109.92866 -15.115286) (xy 111.005874 -16.1925) (xy 120.614694 -16.1925) (xy 120.904 -16.481806)
				(xy 120.904 -17.675606) (xy 121.440194 -18.2118) (xy 126.692406 -18.2118) (xy 128.524 -16.380206)
				(xy 128.524 -12.123674) (xy 126.458218 -10.057892) (xy 126.458218 -4.33832) (xy 126.355856 -4.235958)
			)
		)
	)
	(zone
		(net "GND")
		(layer "In1.Cu")
		(hatch none 0.5)
		(connect_pads
			(clearance 0.5)
		)
		(min_thickness 0.25)
		(fill yes
			(thermal_gap 0.5)
			(thermal_bridge_width 0.5)
			(island_removal_mode 0)
		)
		(polygon
			(pts
				(arc
					(start 0.999998 -0.763016)
					(mid 0.832426 -0.832426)
					(end 0.763016 -0.999998)
				)
				(arc
					(start 0.763016 -183.76392)
					(mid 0.769411 -183.818347)
					(end 0.788162 -183.869838)
				)
				(arc
					(start 5.406136 -193.10604)
					(mid 5.493436 -193.201687)
					(end 5.617972 -193.237104)
				)
				(arc
					(start 98.0821 -193.237104)
					(mid 98.206591 -193.201614)
					(end 98.293936 -193.10604)
				)
				(arc
					(start 102.91191 -183.869838)
					(mid 102.930633 -183.818341)
					(end 102.937056 -183.76392)
				)
				(arc
					(start 102.937056 -47.999904)
					(mid 103.797626 -46.802631)
					(end 105.206546 -47.236888)
				)
				(arc
					(start 142.793466 -47.236888)
					(mid 144.202311 -46.802855)
					(end 145.062956 -47.999904)
				)
				(arc
					(start 145.062956 -183.76392)
					(mid 145.069351 -183.818347)
					(end 145.088102 -183.869838)
				)
				(arc
					(start 149.706076 -193.10604)
					(mid 149.793376 -193.201687)
					(end 149.917912 -193.237104)
				)
				(arc
					(start 229.382066 -193.237104)
					(mid 229.506557 -193.201614)
					(end 229.593902 -193.10604)
				)
				(arc
					(start 234.211876 -183.869838)
					(mid 234.230599 -183.818341)
					(end 234.237022 -183.76392)
				)
				(arc
					(start 234.237022 -0.999998)
					(mid 234.167612 -0.832426)
					(end 234.00004 -0.763016)
				)
				(arc
					(start 74.030078 -0.763016)
					(mid 73.862506 -0.832426)
					(end 73.793096 -0.999998)
				)
				(arc
					(start 73.793096 -109.050074)
					(mid 73.276721 -110.296713)
					(end 72.030082 -110.813088)
				)
				(arc
					(start 31.530036 -110.813088)
					(mid 30.283397 -110.296713)
					(end 29.767022 -109.050074)
				)
				(arc
					(start 29.767022 -0.999998)
					(mid 29.697612 -0.832426)
					(end 29.53004 -0.763016)
				)
			)
		)
		(polygon
			(pts
				(xy 80.953864 -94.295976) (xy 78.896464 -94.295976) (xy 78.896464 -95.604076) (xy 80.953864 -95.604076)
			)
		)
		(polygon
			(pts
				(arc
					(start 83.741768 -94.492572)
					(mid 83.358228 -94.109032)
					(end 82.974688 -94.492572)
				)
				(arc
					(start 82.974688 -95.381826)
					(mid 83.358355 -95.765112)
					(end 83.741768 -95.381572)
				)
			)
		)
		(polygon
			(pts
				(xy 76.503784 -92.69603) (xy 74.446384 -92.69603) (xy 74.446384 -94.00413) (xy 76.503784 -94.00413)
			)
		)
		(polygon
			(pts
				(arc
					(start 77.667358 -92.911168)
					(mid 77.283818 -92.527628)
					(end 76.900278 -92.911168)
				)
				(arc
					(start 76.900278 -93.800422)
					(mid 77.283945 -94.183708)
					(end 77.667358 -93.800168)
				)
			)
		)
		(polygon
			(pts
				(xy 80.953864 -91.096084) (xy 78.896464 -91.096084) (xy 78.896464 -92.40393) (xy 80.953864 -92.40393)
			)
		)
		(polygon
			(pts
				(arc
					(start 85.367368 -91.306396)
					(mid 84.983828 -90.922856)
					(end 84.600288 -91.306396)
				)
				(arc
					(start 84.600288 -92.19565)
					(mid 84.983955 -92.578936)
					(end 85.367368 -92.195396)
				)
			)
		)
		(polygon
			(pts
				(xy 76.503784 -89.496138) (xy 74.446384 -89.496138) (xy 74.446384 -90.803984) (xy 76.503784 -90.803984)
			)
		)
		(polygon
			(pts
				(arc
					(start 78.505558 -89.710768)
					(mid 78.122018 -89.327228)
					(end 77.738478 -89.710768)
				)
				(arc
					(start 77.738478 -90.600022)
					(mid 78.122145 -90.983308)
					(end 78.505558 -90.599768)
				)
			)
		)
		(polygon
			(pts
				(arc
					(start 199.084692 -88.728296)
					(mid 199.084692 -88.189308)
					(end 198.545704 -88.189308)
				)
				(arc
					(start 197.922134 -88.813132)
					(mid 197.915055 -89.354246)
					(end 198.456296 -89.356692)
				)
			)
		)
		(polygon
			(pts
				(arc
					(start 194.720464 -88.652096)
					(mid 194.720464 -88.113108)
					(end 194.181476 -88.113108)
				)
				(arc
					(start 193.557906 -88.736932)
					(mid 193.550827 -89.278046)
					(end 194.092068 -89.280492)
				)
			)
		)
		(polygon
			(pts
				(xy 80.953864 -87.895938) (xy 78.896464 -87.895938) (xy 78.896464 -89.204038) (xy 80.953864 -89.204038)
			)
		)
		(polygon
			(pts
				(arc
					(start 83.741768 -88.10498)
					(mid 83.358101 -87.721694)
					(end 82.974688 -88.105234)
				)
				(arc
					(start 82.974688 -88.994234)
					(mid 83.358228 -89.377774)
					(end 83.741768 -88.994234)
				)
			)
		)
		(polygon
			(pts
				(arc
					(start 191.998092 -86.950296)
					(mid 191.998092 -86.411308)
					(end 191.459104 -86.411308)
				)
				(arc
					(start 190.835534 -87.035132)
					(mid 190.828455 -87.576246)
					(end 191.369696 -87.578692)
				)
			)
		)
		(polygon
			(pts
				(xy 76.503784 -86.295992) (xy 74.446384 -86.295992) (xy 74.446384 -87.604092) (xy 76.503784 -87.604092)
			)
		)
		(polygon
			(pts
				(arc
					(start 77.667358 -86.510368)
					(mid 77.283818 -86.126828)
					(end 76.900278 -86.510368)
				)
				(arc
					(start 76.900278 -87.399622)
					(mid 77.283945 -87.782908)
					(end 77.667358 -87.399368)
				)
			)
		)
		(polygon
			(pts
				(arc
					(start 202.107292 -85.731096)
					(mid 202.107292 -85.192108)
					(end 201.568304 -85.192108)
				)
				(arc
					(start 200.944734 -85.815932)
					(mid 200.937655 -86.357046)
					(end 201.478896 -86.359492)
				)
			)
		)
		(polygon
			(pts
				(arc
					(start 197.793864 -85.604096)
					(mid 197.793864 -85.065108)
					(end 197.254876 -85.065108)
				)
				(arc
					(start 196.631306 -85.688932)
					(mid 196.624227 -86.230046)
					(end 197.165468 -86.232492)
				)
			)
		)
		(polygon
			(pts
				(xy 80.953864 -84.696046) (xy 78.896464 -84.696046) (xy 78.896464 -86.004146) (xy 80.953864 -86.004146)
			)
		)
		(polygon
			(pts
				(arc
					(start 85.367368 -84.904834)
					(mid 84.983828 -84.521294)
					(end 84.600288 -84.904834)
				)
				(arc
					(start 84.600288 -85.794088)
					(mid 84.983955 -86.177374)
					(end 85.367368 -85.793834)
				)
			)
		)
		(polygon
			(pts
				(arc
					(start 204.698092 -85.146896)
					(mid 204.698092 -84.607908)
					(end 204.159104 -84.607908)
				)
				(arc
					(start 203.535534 -85.231732)
					(mid 203.528455 -85.772846)
					(end 204.069696 -85.775292)
				)
			)
		)
		(polygon
			(pts
				(arc
					(start 190.448692 -84.156296)
					(mid 190.448692 -83.617308)
					(end 189.909704 -83.617308)
				)
				(arc
					(start 189.286134 -84.241132)
					(mid 189.279055 -84.782246)
					(end 189.820296 -84.784692)
				)
			)
		)
		(polygon
			(pts
				(arc
					(start 194.944492 -83.927696)
					(mid 194.944492 -83.388708)
					(end 194.405504 -83.388708)
				)
				(arc
					(start 193.781934 -84.012532)
					(mid 193.774855 -84.553646)
					(end 194.316096 -84.556092)
				)
			)
		)
		(polygon
			(pts
				(xy 76.503784 -83.0961) (xy 74.446384 -83.0961) (xy 74.446384 -84.403946) (xy 76.503784 -84.403946)
			)
		)
		(polygon
			(pts
				(arc
					(start 78.505558 -83.335368)
					(mid 78.122018 -82.951828)
					(end 77.738478 -83.335368)
				)
				(arc
					(start 77.738478 -84.224622)
					(mid 78.122145 -84.607908)
					(end 78.505558 -84.224368)
				)
			)
		)
		(polygon
			(pts
				(xy 80.953864 -81.4959) (xy 78.896464 -81.4959) (xy 78.896464 -82.804) (xy 80.953864 -82.804)
			)
		)
		(polygon
			(pts
				(arc
					(start 83.741768 -81.705196)
					(mid 83.358228 -81.321656)
					(end 82.974688 -81.705196)
				)
				(arc
					(start 82.974688 -82.59445)
					(mid 83.358355 -82.977736)
					(end 83.741768 -82.594196)
				)
			)
		)
		(polygon
			(pts
				(xy 76.503784 -79.895954) (xy 74.446384 -79.895954) (xy 74.446384 -81.204054) (xy 76.503784 -81.204054)
			)
		)
		(polygon
			(pts
				(arc
					(start 77.667358 -80.109568)
					(mid 77.283818 -79.726028)
					(end 76.900278 -80.109568)
				)
				(arc
					(start 76.900278 -80.998822)
					(mid 77.283945 -81.382108)
					(end 77.667358 -80.998568)
				)
			)
		)
		(polygon
			(pts
				(arc
					(start 216.573354 -79.113126)
					(mid 216.573354 -78.574646)
					(end 216.034874 -78.574646)
				)
				(xy 216.03462 -78.574392) (xy 215.226392 -79.38262)
				(arc
					(start 215.226646 -79.382874)
					(mid 215.226646 -79.921354)
					(end 215.765126 -79.921354)
				)
				(xy 215.76538 -79.921608) (xy 216.573354 -79.11338)
			)
		)
		(polygon
			(pts
				(xy 80.953864 -78.296008) (xy 78.896464 -78.296008) (xy 78.896464 -79.604108) (xy 80.953864 -79.604108)
			)
		)
		(polygon
			(pts
				(arc
					(start 85.367368 -78.504796)
					(mid 84.983828 -78.121256)
					(end 84.600288 -78.504796)
				)
				(arc
					(start 84.600288 -79.39405)
					(mid 84.983955 -79.777336)
					(end 85.367368 -79.393796)
				)
			)
		)
		(polygon
			(pts
				(xy 76.503784 -76.696062) (xy 74.446384 -76.696062) (xy 74.446384 -78.003908) (xy 76.503784 -78.003908)
			)
		)
		(polygon
			(pts
				(arc
					(start 208.513172 -76.6064)
					(mid 208.498293 -76.570479)
					(end 208.462372 -76.5556)
				)
				(arc
					(start 207.649572 -76.5556)
					(mid 207.613651 -76.570479)
					(end 207.598772 -76.6064)
				)
				(arc
					(start 207.598772 -76.8096)
					(mid 207.613651 -76.845521)
					(end 207.649572 -76.8604)
				)
				(arc
					(start 208.462372 -76.8604)
					(mid 208.498293 -76.845521)
					(end 208.513172 -76.8096)
				)
			)
		)
		(polygon
			(pts
				(arc
					(start 78.505558 -76.909168)
					(mid 78.122018 -76.525628)
					(end 77.738478 -76.909168)
				)
				(arc
					(start 77.738478 -77.798422)
					(mid 78.122145 -78.181708)
					(end 78.505558 -77.798168)
				)
			)
		)
		(polygon
			(pts
				(arc
					(start 208.513172 -76.0476)
					(mid 208.498293 -76.011679)
					(end 208.462372 -75.9968)
				)
				(arc
					(start 207.649572 -75.9968)
					(mid 207.613651 -76.011679)
					(end 207.598772 -76.0476)
				)
				(arc
					(start 207.598772 -76.2508)
					(mid 207.613651 -76.286721)
					(end 207.649572 -76.3016)
				)
				(arc
					(start 208.462372 -76.3016)
					(mid 208.498293 -76.286721)
					(end 208.513172 -76.2508)
				)
			)
		)
		(polygon
			(pts
				(arc
					(start 202.399646 -75.883262)
					(mid 202.783186 -75.499722)
					(end 202.399646 -75.116182)
				)
				(arc
					(start 201.599546 -75.116182)
					(mid 201.21626 -75.499849)
					(end 201.5998 -75.883262)
				)
			)
		)
		(polygon
			(pts
				(xy 80.953864 -75.096116) (xy 78.896464 -75.096116) (xy 78.896464 -76.403962) (xy 80.953864 -76.403962)
			)
		)
		(polygon
			(pts
				(arc
					(start 83.741768 -75.305158)
					(mid 83.358228 -74.921618)
					(end 82.974688 -75.305158)
				)
				(arc
					(start 82.974688 -76.194412)
					(mid 83.358355 -76.577698)
					(end 83.741768 -76.194158)
				)
			)
		)
		(polygon
			(pts
				(arc
					(start 208.513172 -74.93)
					(mid 208.498293 -74.894079)
					(end 208.462372 -74.8792)
				)
				(arc
					(start 207.649572 -74.8792)
					(mid 207.613651 -74.894079)
					(end 207.598772 -74.93)
				)
				(arc
					(start 207.598772 -75.1332)
					(mid 207.613651 -75.169121)
					(end 207.649572 -75.184)
				)
				(arc
					(start 208.462372 -75.184)
					(mid 208.498293 -75.169121)
					(end 208.513172 -75.1332)
				)
			)
		)
		(polygon
			(pts
				(arc
					(start 217.716354 -75.176126)
					(mid 217.716354 -74.637646)
					(end 217.177874 -74.637646)
				)
				(xy 217.17762 -74.637392) (xy 216.369392 -75.44562)
				(arc
					(start 216.369646 -75.445874)
					(mid 216.369646 -75.984354)
					(end 216.908126 -75.984354)
				)
				(xy 216.90838 -75.984608) (xy 217.716354 -75.17638)
			)
		)
		(polygon
			(pts
				(arc
					(start 208.513172 -74.3712)
					(mid 208.498293 -74.335279)
					(end 208.462372 -74.3204)
				)
				(arc
					(start 207.649572 -74.3204)
					(mid 207.613651 -74.335279)
					(end 207.598772 -74.3712)
				)
				(arc
					(start 207.598772 -74.5744)
					(mid 207.613651 -74.610321)
					(end 207.649572 -74.6252)
				)
				(arc
					(start 208.462372 -74.6252)
					(mid 208.498293 -74.610321)
					(end 208.513172 -74.5744)
				)
			)
		)
		(polygon
			(pts
				(arc
					(start 200.357994 -73.899268)
					(mid 199.999219 -73.54189)
					(end 199.641714 -73.900538)
				)
				(xy 199.643492 -74.691494) (xy 199.643492 -74.692256)
				(arc
					(start 199.643492 -74.695558)
					(mid 200.002394 -75.052936)
					(end 200.359772 -74.694034)
				)
				(xy 200.357994 -73.900538) (xy 200.357994 -73.899776)
			)
		)
		(polygon
			(pts
				(arc
					(start 199.557894 -73.899268)
					(mid 199.199119 -73.54189)
					(end 198.841614 -73.900538)
				)
				(arc
					(start 198.843392 -74.693018)
					(mid 199.202294 -75.050396)
					(end 199.559672 -74.691494)
				)
				(xy 199.557894 -73.900538) (xy 199.557894 -73.899776)
			)
		)
		(polygon
			(pts
				(arc
					(start 195.557902 -73.900538)
					(mid 195.200397 -73.54189)
					(end 194.841622 -73.899268)
				)
				(xy 194.841622 -73.899776) (xy 194.841622 -73.903332) (xy 194.840352 -74.70521)
				(arc
					(start 194.840352 -74.706988)
					(mid 195.197984 -75.065636)
					(end 195.556632 -74.708004)
				)
				(xy 195.556632 -74.707496) (xy 195.556632 -74.706988)
			)
		)
		(polygon
			(pts
				(arc
					(start 194.757802 -73.903332)
					(mid 194.403091 -73.541891)
					(end 194.041522 -73.896474)
				)
				(arc
					(start 194.03441 -74.698606)
					(mid 194.389248 -75.060048)
					(end 194.75069 -74.70521)
				)
			)
		)
		(polygon
			(pts
				(arc
					(start 197.157848 -73.89622)
					(mid 196.796025 -73.541889)
					(end 196.441568 -73.903586)
				)
				(arc
					(start 196.44995 -74.702162)
					(mid 196.8119 -75.056492)
					(end 197.16623 -74.694542)
				)
			)
		)
		(polygon
			(pts
				(arc
					(start 197.957948 -73.895712)
					(mid 197.595617 -73.541888)
					(end 197.241668 -73.904094)
				)
				(arc
					(start 197.251066 -74.70394)
					(mid 197.613524 -75.057762)
					(end 197.967346 -74.695304)
				)
			)
		)
		(polygon
			(pts
				(arc
					(start 192.35801 -73.899522)
					(mid 191.999743 -73.541636)
					(end 191.64173 -73.899776)
				)
				(arc
					(start 191.64173 -74.699622)
					(mid 191.99987 -75.057762)
					(end 192.35801 -74.699622)
				)
			)
		)
		(polygon
			(pts
				(arc
					(start 193.157856 -73.899522)
					(mid 192.799462 -73.541636)
					(end 192.441576 -73.90003)
				)
				(xy 192.44183 -74.699622)
				(arc
					(start 192.44183 -74.699876)
					(mid 192.800097 -75.058016)
					(end 193.15811 -74.699622)
				)
				(xy 193.157856 -74.257916)
			)
		)
		(polygon
			(pts
				(arc
					(start 201.598276 -74.287126)
					(mid 201.981816 -73.903586)
					(end 201.598276 -73.520046)
				)
				(arc
					(start 200.798176 -73.520046)
					(mid 200.41489 -73.903713)
					(end 200.79843 -74.287126)
				)
			)
		)
		(polygon
			(pts
				(xy 76.503784 -73.495916) (xy 74.446384 -73.495916) (xy 74.446384 -74.804016) (xy 76.503784 -74.804016)
			)
		)
		(polygon
			(pts
				(arc
					(start 77.667358 -73.708768)
					(mid 77.283818 -73.325228)
					(end 76.900278 -73.708768)
				)
				(arc
					(start 76.900278 -74.598022)
					(mid 77.283945 -74.981308)
					(end 77.667358 -74.597768)
				)
			)
		)
		(polygon
			(pts
				(arc
					(start 208.513172 -73.2536)
					(mid 208.498293 -73.217679)
					(end 208.462372 -73.2028)
				)
				(arc
					(start 207.649572 -73.2028)
					(mid 207.613651 -73.217679)
					(end 207.598772 -73.2536)
				)
				(arc
					(start 207.598772 -73.4568)
					(mid 207.613651 -73.492721)
					(end 207.649572 -73.5076)
				)
				(arc
					(start 208.462372 -73.5076)
					(mid 208.498293 -73.492721)
					(end 208.513172 -73.4568)
				)
			)
		)
		(polygon
			(pts
				(arc
					(start 216.192354 -73.652126)
					(mid 216.192354 -73.113646)
					(end 215.653874 -73.113646)
				)
				(xy 215.65362 -73.113392) (xy 214.845392 -73.92162)
				(arc
					(start 214.845646 -73.921874)
					(mid 214.845646 -74.460354)
					(end 215.384126 -74.460354)
				)
				(xy 215.38438 -74.460608) (xy 216.192354 -73.65238)
			)
		)
		(polygon
			(pts
				(arc
					(start 202.39863 -73.480676)
					(mid 202.780646 -73.095612)
					(end 202.395582 -72.713596)
				)
				(arc
					(start 201.599292 -72.716898)
					(mid 201.217276 -73.101835)
					(end 201.602086 -73.483978)
				)
			)
		)
		(polygon
			(pts
				(arc
					(start 208.513172 -72.6948)
					(mid 208.498293 -72.658879)
					(end 208.462372 -72.644)
				)
				(arc
					(start 207.649572 -72.644)
					(mid 207.613651 -72.658879)
					(end 207.598772 -72.6948)
				)
				(arc
					(start 207.598772 -72.898)
					(mid 207.613651 -72.933921)
					(end 207.649572 -72.9488)
				)
				(arc
					(start 208.462372 -72.9488)
					(mid 208.498293 -72.933921)
					(end 208.513172 -72.898)
				)
			)
		)
		(polygon
			(pts
				(xy 80.953864 -71.89597) (xy 78.896464 -71.89597) (xy 78.896464 -73.20407) (xy 80.953864 -73.20407)
			)
		)
		(polygon
			(pts
				(arc
					(start 85.367368 -72.080882)
					(mid 84.983701 -71.697596)
					(end 84.600288 -72.081136)
				)
				(arc
					(start 84.600288 -72.970136)
					(mid 84.983828 -73.353676)
					(end 85.367368 -72.970136)
				)
			)
		)
		(polygon
			(pts
				(arc
					(start 214.795354 -72.255126)
					(mid 214.795354 -71.716646)
					(end 214.256874 -71.716646)
				)
				(xy 214.25662 -71.716392) (xy 213.448392 -72.52462)
				(arc
					(start 213.448646 -72.524874)
					(mid 213.448646 -73.063354)
					(end 213.987126 -73.063354)
				)
				(xy 213.98738 -73.063608) (xy 214.795354 -72.25538)
			)
		)
		(polygon
			(pts
				(arc
					(start 208.513172 -71.5772)
					(mid 208.498293 -71.541279)
					(end 208.462372 -71.5264)
				)
				(arc
					(start 207.649572 -71.5264)
					(mid 207.613651 -71.541279)
					(end 207.598772 -71.5772)
				)
				(arc
					(start 207.598772 -71.7804)
					(mid 207.613651 -71.816321)
					(end 207.649572 -71.8312)
				)
				(arc
					(start 208.462372 -71.8312)
					(mid 208.498293 -71.816321)
					(end 208.513172 -71.7804)
				)
			)
		)
		(polygon
			(pts
				(arc
					(start 201.978006 -71.50354)
					(mid 201.594974 -71.119492)
					(end 201.210926 -71.502524)
				)
				(arc
					(start 201.20991 -72.297036)
					(mid 201.592815 -72.681338)
					(end 201.97699 -72.298306)
				)
				(xy 201.97699 -72.297798) (xy 201.97699 -72.297036)
			)
		)
		(polygon
			(pts
				(arc
					(start 208.513172 -71.0184)
					(mid 208.498293 -70.982479)
					(end 208.462372 -70.9676)
				)
				(arc
					(start 207.649572 -70.9676)
					(mid 207.613651 -70.982479)
					(end 207.598772 -71.0184)
				)
				(arc
					(start 207.598772 -71.2216)
					(mid 207.613651 -71.257521)
					(end 207.649572 -71.2724)
				)
				(arc
					(start 208.462372 -71.2724)
					(mid 208.498293 -71.257521)
					(end 208.513172 -71.2216)
				)
			)
		)
		(polygon
			(pts
				(arc
					(start 201.594466 -70.319138)
					(mid 201.210164 -70.701789)
					(end 201.592688 -71.086218)
				)
				(arc
					(start 202.40371 -71.087996)
					(mid 202.788012 -70.705218)
					(end 202.405234 -70.320916)
				)
			)
		)
		(polygon
			(pts
				(xy 76.503784 -70.296024) (xy 74.446384 -70.296024) (xy 74.446384 -71.604124) (xy 76.503784 -71.604124)
			)
		)
		(polygon
			(pts
				(arc
					(start 78.505558 -70.508368)
					(mid 78.122018 -70.124828)
					(end 77.738478 -70.508368)
				)
				(arc
					(start 77.738478 -71.397622)
					(mid 78.122145 -71.780908)
					(end 78.505558 -71.397368)
				)
			)
		)
		(polygon
			(pts
				(arc
					(start 208.513172 -69.9008)
					(mid 208.498293 -69.864879)
					(end 208.462372 -69.85)
				)
				(arc
					(start 207.649572 -69.85)
					(mid 207.613651 -69.864879)
					(end 207.598772 -69.9008)
				)
				(arc
					(start 207.598772 -70.104)
					(mid 207.613651 -70.139921)
					(end 207.649572 -70.1548)
				)
				(arc
					(start 208.462372 -70.1548)
					(mid 208.498293 -70.139921)
					(end 208.513172 -70.104)
				)
			)
		)
		(polygon
			(pts
				(arc
					(start 208.513172 -69.342)
					(mid 208.498293 -69.306079)
					(end 208.462372 -69.2912)
				)
				(arc
					(start 207.649572 -69.2912)
					(mid 207.613651 -69.306079)
					(end 207.598772 -69.342)
				)
				(arc
					(start 207.598772 -69.5452)
					(mid 207.613651 -69.581121)
					(end 207.649572 -69.596)
				)
				(arc
					(start 208.462372 -69.596)
					(mid 208.498293 -69.581121)
					(end 208.513172 -69.5452)
				)
			)
		)
		(polygon
			(pts
				(arc
					(start 201.978768 -69.097398)
					(mid 201.58837 -68.720716)
					(end 201.211688 -69.111114)
				)
				(arc
					(start 201.225658 -69.906388)
					(mid 201.615929 -70.283322)
					(end 201.992738 -69.892926)
				)
			)
		)
		(polygon
			(pts
				(arc
					(start 215.303354 -68.953126)
					(mid 215.303354 -68.414646)
					(end 214.764874 -68.414646)
				)
				(xy 214.76462 -68.414392) (xy 213.956392 -69.22262)
				(arc
					(start 213.956646 -69.222874)
					(mid 213.956646 -69.761354)
					(end 214.495126 -69.761354)
				)
				(xy 214.49538 -69.761608) (xy 215.303354 -68.95338)
			)
		)
		(polygon
			(pts
				(arc
					(start 208.513172 -68.2244)
					(mid 208.498293 -68.188479)
					(end 208.462372 -68.1736)
				)
				(arc
					(start 207.649572 -68.1736)
					(mid 207.613651 -68.188479)
					(end 207.598772 -68.2244)
				)
				(arc
					(start 207.598772 -68.4276)
					(mid 207.613651 -68.463521)
					(end 207.649572 -68.4784)
				)
				(arc
					(start 208.462372 -68.4784)
					(mid 208.498293 -68.463521)
					(end 208.513172 -68.4276)
				)
			)
		)
		(polygon
			(pts
				(arc
					(start 201.599546 -67.911726)
					(mid 201.212197 -68.291329)
					(end 201.591672 -68.678806)
				)
				(arc
					(start 202.39609 -68.68668)
					(mid 202.78344 -68.30695)
					(end 202.40371 -67.9196)
				)
			)
		)
		(polygon
			(pts
				(arc
					(start 208.513172 -67.6656)
					(mid 208.498293 -67.629679)
					(end 208.462372 -67.6148)
				)
				(arc
					(start 207.649572 -67.6148)
					(mid 207.613651 -67.629679)
					(end 207.598772 -67.6656)
				)
				(arc
					(start 207.598772 -67.8688)
					(mid 207.613651 -67.904721)
					(end 207.649572 -67.9196)
				)
				(arc
					(start 208.462372 -67.9196)
					(mid 208.498293 -67.904721)
					(end 208.513172 -67.8688)
				)
			)
		)
		(polygon
			(pts
				(xy 76.503784 -67.096132) (xy 74.446384 -67.096132) (xy 74.446384 -68.403978) (xy 76.503784 -68.403978)
			)
		)
		(polygon
			(pts
				(arc
					(start 77.658214 -67.321938)
					(mid 77.274547 -66.938652)
					(end 76.891134 -67.322192)
				)
				(arc
					(start 76.891134 -68.211192)
					(mid 77.274674 -68.594732)
					(end 77.658214 -68.211192)
				)
			)
		)
		(polygon
			(pts
				(arc
					(start 213.779354 -67.479926)
					(mid 213.779354 -66.941446)
					(end 213.240874 -66.941446)
				)
				(xy 213.24062 -66.941192) (xy 212.432392 -67.74942)
				(arc
					(start 212.432646 -67.749674)
					(mid 212.432646 -68.288154)
					(end 212.971126 -68.288154)
				)
				(xy 212.97138 -68.288408) (xy 213.779354 -67.48018)
			)
		)
		(polygon
			(pts
				(arc
					(start 208.513172 -66.548)
					(mid 208.498293 -66.512079)
					(end 208.462372 -66.4972)
				)
				(arc
					(start 207.649572 -66.4972)
					(mid 207.613651 -66.512079)
					(end 207.598772 -66.548)
				)
				(arc
					(start 207.598772 -66.7512)
					(mid 207.613651 -66.787121)
					(end 207.649572 -66.802)
				)
				(arc
					(start 208.462372 -66.802)
					(mid 208.498293 -66.787121)
					(end 208.513172 -66.7512)
				)
			)
		)
		(polygon
			(pts
				(arc
					(start 201.983086 -66.712084)
					(mid 201.602594 -66.325496)
					(end 201.216006 -66.705988)
				)
				(arc
					(start 201.209656 -67.49923)
					(mid 201.590021 -67.886073)
					(end 201.976736 -67.50558)
				)
			)
		)
		(polygon
			(pts
				(arc
					(start 208.513172 -65.9892)
					(mid 208.498293 -65.953279)
					(end 208.462372 -65.9384)
				)
				(arc
					(start 207.649572 -65.9384)
					(mid 207.613651 -65.953279)
					(end 207.598772 -65.9892)
				)
				(arc
					(start 207.598772 -66.1924)
					(mid 207.613651 -66.228321)
					(end 207.649572 -66.2432)
				)
				(arc
					(start 208.462372 -66.2432)
					(mid 208.498293 -66.228321)
					(end 208.513172 -66.1924)
				)
			)
		)
		(polygon
			(pts
				(arc
					(start 212.306154 -65.828926)
					(mid 212.306154 -65.290446)
					(end 211.767674 -65.290446)
				)
				(xy 211.76742 -65.290192) (xy 210.959192 -66.09842)
				(arc
					(start 210.959446 -66.098674)
					(mid 210.959446 -66.637154)
					(end 211.497926 -66.637154)
				)
				(xy 211.49818 -66.637408) (xy 212.306154 -65.82918)
			)
		)
		(polygon
			(pts
				(arc
					(start 208.513172 -64.8716)
					(mid 208.498293 -64.835679)
					(end 208.462372 -64.8208)
				)
				(arc
					(start 207.649572 -64.8208)
					(mid 207.613651 -64.835679)
					(end 207.598772 -64.8716)
				)
				(arc
					(start 207.598772 -65.0748)
					(mid 207.613651 -65.110721)
					(end 207.649572 -65.1256)
				)
				(arc
					(start 208.462372 -65.1256)
					(mid 208.498293 -65.110721)
					(end 208.513172 -65.0748)
				)
			)
		)
		(polygon
			(pts
				(arc
					(start 208.513172 -64.3128)
					(mid 208.498293 -64.276879)
					(end 208.462372 -64.262)
				)
				(arc
					(start 207.649572 -64.262)
					(mid 207.613651 -64.276879)
					(end 207.598772 -64.3128)
				)
				(arc
					(start 207.598772 -64.516)
					(mid 207.613651 -64.551921)
					(end 207.649572 -64.5668)
				)
				(arc
					(start 208.462372 -64.5668)
					(mid 208.498293 -64.551921)
					(end 208.513172 -64.516)
				)
			)
		)
		(polygon
			(pts
				(arc
					(start 212.137498 -63.3857)
					(mid 212.137498 -62.84722)
					(end 211.599018 -62.84722)
				)
				(xy 211.598764 -62.846966) (xy 210.790536 -63.655194)
				(arc
					(start 210.79079 -63.655448)
					(mid 210.79079 -64.193928)
					(end 211.32927 -64.193928)
				)
				(xy 211.329524 -64.194182) (xy 212.137498 -63.385954)
			)
		)
		(polygon
			(pts
				(arc
					(start 139.984988 -36.799774)
					(mid 139.499721 -36.314888)
					(end 139.014708 -36.800028)
				)
				(arc
					(start 139.014708 -38.200076)
					(mid 139.499848 -38.685216)
					(end 139.984988 -38.200076)
				)
			)
		)
		(polygon
			(pts
				(arc
					(start 136.385046 -36.799774)
					(mid 135.899779 -36.314888)
					(end 135.414766 -36.800028)
				)
				(arc
					(start 135.414766 -38.200076)
					(mid 135.899906 -38.685216)
					(end 136.385046 -38.200076)
				)
			)
		)
		(polygon
			(pts
				(arc
					(start 132.785104 -36.799774)
					(mid 132.299837 -36.314888)
					(end 131.814824 -36.800028)
				)
				(arc
					(start 131.814824 -38.200076)
					(mid 132.299964 -38.685216)
					(end 132.785104 -38.200076)
				)
			)
		)
		(polygon
			(pts
				(arc
					(start 129.185162 -36.799774)
					(mid 128.699895 -36.314888)
					(end 128.214882 -36.800028)
				)
				(arc
					(start 128.214882 -38.200076)
					(mid 128.700022 -38.685216)
					(end 129.185162 -38.200076)
				)
			)
		)
		(polygon
			(pts
				(arc
					(start 118.385082 -36.799774)
					(mid 117.899815 -36.314888)
					(end 117.414802 -36.800028)
				)
				(arc
					(start 117.414802 -38.200076)
					(mid 117.899942 -38.685216)
					(end 118.385082 -38.200076)
				)
			)
		)
		(polygon
			(pts
				(arc
					(start 114.78514 -36.799774)
					(mid 114.299873 -36.314888)
					(end 113.81486 -36.800028)
				)
				(arc
					(start 113.81486 -38.200076)
					(mid 114.3 -38.685216)
					(end 114.78514 -38.200076)
				)
			)
		)
		(polygon
			(pts
				(arc
					(start 111.185198 -36.799774)
					(mid 110.699931 -36.314888)
					(end 110.214918 -36.800028)
				)
				(arc
					(start 110.214918 -38.200076)
					(mid 110.700058 -38.685216)
					(end 111.185198 -38.200076)
				)
			)
		)
		(polygon
			(pts
				(arc
					(start 107.585002 -36.799774)
					(mid 107.099735 -36.314888)
					(end 106.614722 -36.800028)
				)
				(arc
					(start 106.614722 -38.200076)
					(mid 107.099862 -38.685216)
					(end 107.585002 -38.200076)
				)
			)
		)
		(polygon
			(pts
				(arc
					(start 141.785086 -35.599878)
					(mid 141.299819 -35.114992)
					(end 140.814806 -35.600132)
				)
				(arc
					(start 140.814806 -37.00018)
					(mid 141.299946 -37.48532)
					(end 141.785086 -37.00018)
				)
			)
		)
		(polygon
			(pts
				(arc
					(start 138.185144 -35.599878)
					(mid 137.699877 -35.114992)
					(end 137.214864 -35.600132)
				)
				(arc
					(start 137.214864 -37.00018)
					(mid 137.700004 -37.48532)
					(end 138.185144 -37.00018)
				)
			)
		)
		(polygon
			(pts
				(arc
					(start 134.585202 -35.599878)
					(mid 134.099935 -35.114992)
					(end 133.614922 -35.600132)
				)
				(arc
					(start 133.614922 -37.00018)
					(mid 134.100062 -37.48532)
					(end 134.585202 -37.00018)
				)
			)
		)
		(polygon
			(pts
				(arc
					(start 130.985006 -35.599878)
					(mid 130.499739 -35.114992)
					(end 130.014726 -35.600132)
				)
				(arc
					(start 130.014726 -37.00018)
					(mid 130.499866 -37.48532)
					(end 130.985006 -37.00018)
				)
			)
		)
		(polygon
			(pts
				(arc
					(start 120.18518 -35.599878)
					(mid 119.699913 -35.114992)
					(end 119.2149 -35.600132)
				)
				(arc
					(start 119.2149 -37.00018)
					(mid 119.70004 -37.48532)
					(end 120.18518 -37.00018)
				)
			)
		)
		(polygon
			(pts
				(arc
					(start 116.584984 -35.599878)
					(mid 116.099717 -35.114992)
					(end 115.614704 -35.600132)
				)
				(arc
					(start 115.614704 -37.00018)
					(mid 116.099844 -37.48532)
					(end 116.584984 -37.00018)
				)
			)
		)
		(polygon
			(pts
				(arc
					(start 112.985042 -35.599878)
					(mid 112.499775 -35.114992)
					(end 112.014762 -35.600132)
				)
				(arc
					(start 112.014762 -37.00018)
					(mid 112.499902 -37.48532)
					(end 112.985042 -37.00018)
				)
			)
		)
		(polygon
			(pts
				(arc
					(start 109.3851 -35.599878)
					(mid 108.899833 -35.114992)
					(end 108.41482 -35.600132)
				)
				(arc
					(start 108.41482 -37.00018)
					(mid 108.89996 -37.48532)
					(end 109.3851 -37.00018)
				)
			)
		)
		(polygon
			(pts
				(arc
					(start 139.984988 -33.199832)
					(mid 139.499721 -32.714946)
					(end 139.014708 -33.200086)
				)
				(arc
					(start 139.014708 -34.600134)
					(mid 139.499848 -35.085274)
					(end 139.984988 -34.600134)
				)
			)
		)
		(polygon
			(pts
				(arc
					(start 136.385046 -33.199832)
					(mid 135.899779 -32.714946)
					(end 135.414766 -33.200086)
				)
				(arc
					(start 135.414766 -34.600134)
					(mid 135.899906 -35.085274)
					(end 136.385046 -34.600134)
				)
			)
		)
		(polygon
			(pts
				(arc
					(start 132.785104 -33.199832)
					(mid 132.299837 -32.714946)
					(end 131.814824 -33.200086)
				)
				(arc
					(start 131.814824 -34.600134)
					(mid 132.299964 -35.085274)
					(end 132.785104 -34.600134)
				)
			)
		)
		(polygon
			(pts
				(arc
					(start 129.185162 -33.199832)
					(mid 128.699895 -32.714946)
					(end 128.214882 -33.200086)
				)
				(arc
					(start 128.214882 -34.600134)
					(mid 128.700022 -35.085274)
					(end 129.185162 -34.600134)
				)
			)
		)
		(polygon
			(pts
				(arc
					(start 118.385082 -33.199832)
					(mid 117.899815 -32.714946)
					(end 117.414802 -33.200086)
				)
				(arc
					(start 117.414802 -34.600134)
					(mid 117.899942 -35.085274)
					(end 118.385082 -34.600134)
				)
			)
		)
		(polygon
			(pts
				(arc
					(start 114.78514 -33.199832)
					(mid 114.299873 -32.714946)
					(end 113.81486 -33.200086)
				)
				(arc
					(start 113.81486 -34.600134)
					(mid 114.3 -35.085274)
					(end 114.78514 -34.600134)
				)
			)
		)
		(polygon
			(pts
				(arc
					(start 111.185198 -33.199832)
					(mid 110.699931 -32.714946)
					(end 110.214918 -33.200086)
				)
				(arc
					(start 110.214918 -34.600134)
					(mid 110.700058 -35.085274)
					(end 111.185198 -34.600134)
				)
			)
		)
		(polygon
			(pts
				(arc
					(start 107.585002 -33.199832)
					(mid 107.099735 -32.714946)
					(end 106.614722 -33.200086)
				)
				(arc
					(start 106.614722 -34.600134)
					(mid 107.099862 -35.085274)
					(end 107.585002 -34.600134)
				)
			)
		)
		(polygon
			(pts
				(arc
					(start 141.785086 -31.999936)
					(mid 141.299819 -31.51505)
					(end 140.814806 -32.00019)
				)
				(arc
					(start 140.814806 -33.399984)
					(mid 141.299946 -33.885124)
					(end 141.785086 -33.399984)
				)
			)
		)
		(polygon
			(pts
				(arc
					(start 138.185144 -31.999936)
					(mid 137.699877 -31.51505)
					(end 137.214864 -32.00019)
				)
				(arc
					(start 137.214864 -33.399984)
					(mid 137.700004 -33.885124)
					(end 138.185144 -33.399984)
				)
			)
		)
		(polygon
			(pts
				(arc
					(start 134.585202 -31.999936)
					(mid 134.099935 -31.51505)
					(end 133.614922 -32.00019)
				)
				(arc
					(start 133.614922 -33.399984)
					(mid 134.100062 -33.885124)
					(end 134.585202 -33.399984)
				)
			)
		)
		(polygon
			(pts
				(arc
					(start 130.985006 -31.999936)
					(mid 130.499739 -31.51505)
					(end 130.014726 -32.00019)
				)
				(arc
					(start 130.014726 -33.399984)
					(mid 130.499866 -33.885124)
					(end 130.985006 -33.399984)
				)
			)
		)
		(polygon
			(pts
				(arc
					(start 120.18518 -31.999936)
					(mid 119.699913 -31.51505)
					(end 119.2149 -32.00019)
				)
				(arc
					(start 119.2149 -33.399984)
					(mid 119.70004 -33.885124)
					(end 120.18518 -33.399984)
				)
			)
		)
		(polygon
			(pts
				(arc
					(start 116.584984 -31.999936)
					(mid 116.099717 -31.51505)
					(end 115.614704 -32.00019)
				)
				(arc
					(start 115.614704 -33.399984)
					(mid 116.099844 -33.885124)
					(end 116.584984 -33.399984)
				)
			)
		)
		(polygon
			(pts
				(arc
					(start 112.985042 -31.999936)
					(mid 112.499775 -31.51505)
					(end 112.014762 -32.00019)
				)
				(arc
					(start 112.014762 -33.399984)
					(mid 112.499902 -33.885124)
					(end 112.985042 -33.399984)
				)
			)
		)
		(polygon
			(pts
				(arc
					(start 109.3851 -31.999936)
					(mid 108.899833 -31.51505)
					(end 108.41482 -32.00019)
				)
				(arc
					(start 108.41482 -33.399984)
					(mid 108.89996 -33.885124)
					(end 109.3851 -33.399984)
				)
			)
		)
		(polygon
			(pts
				(arc
					(start 182.663592 -29.328618)
					(mid 182.47589 -28.684976)
					(end 181.83352 -28.877006)
				)
				(arc
					(start 181.083458 -30.277054)
					(mid 181.277006 -30.916626)
					(end 181.916578 -30.723078)
				)
			)
		)
		(polygon
			(pts
				(arc
					(start 180.413406 -29.328618)
					(mid 180.225704 -28.684976)
					(end 179.583334 -28.877006)
				)
				(arc
					(start 178.833526 -30.277054)
					(mid 179.027074 -30.916626)
					(end 179.666646 -30.723078)
				)
			)
		)
		(polygon
			(pts
				(arc
					(start 162.663632 -29.328618)
					(mid 162.47593 -28.684976)
					(end 161.83356 -28.877006)
				)
				(arc
					(start 161.083498 -30.277054)
					(mid 161.277046 -30.916626)
					(end 161.916618 -30.723078)
				)
			)
		)
		(polygon
			(pts
				(arc
					(start 160.413446 -29.328618)
					(mid 160.225744 -28.684976)
					(end 159.583374 -28.877006)
				)
				(arc
					(start 158.833566 -30.277054)
					(mid 159.027114 -30.916626)
					(end 159.666686 -30.723078)
				)
			)
		)
		(polygon
			(pts
				(arc
					(start 162.663632 -25.528524)
					(mid 162.47593 -24.884882)
					(end 161.83356 -25.076912)
				)
				(arc
					(start 161.083498 -26.47696)
					(mid 161.277046 -27.116532)
					(end 161.916618 -26.922984)
				)
			)
		)
		(polygon
			(pts
				(arc
					(start 160.413446 -25.528524)
					(mid 160.225744 -24.884882)
					(end 159.583374 -25.076912)
				)
				(arc
					(start 158.833566 -26.47696)
					(mid 159.027114 -27.116532)
					(end 159.666686 -26.922984)
				)
			)
		)
		(polygon
			(pts
				(arc
					(start 180.43398 -25.543764)
					(mid 180.239312 -24.863383)
					(end 179.560982 -25.064974)
				)
				(arc
					(start 178.811174 -26.465022)
					(mid 179.015136 -27.138884)
					(end 179.688998 -26.934922)
				)
			)
		)
		(polygon
			(pts
				(arc
					(start 182.684166 -25.543764)
					(mid 182.489596 -24.863437)
					(end 181.811168 -25.06472)
				)
				(arc
					(start 181.061106 -26.464768)
					(mid 181.264814 -27.138884)
					(end 181.93893 -26.935176)
				)
			)
		)
		(polygon
			(pts
				(arc
					(start 182.666386 -21.72335)
					(mid 182.473247 -21.083725)
					(end 181.833774 -21.277072)
				)
				(xy 181.831488 -21.275802) (xy 181.081426 -22.675596)
				(arc
					(start 181.083712 -22.676866)
					(mid 181.277006 -23.316184)
					(end 181.916324 -23.12289)
				)
				(xy 181.91861 -23.12416) (xy 182.668672 -21.72462) (xy 182.668418 -21.724366)
			)
		)
		(polygon
			(pts
				(arc
					(start 162.666426 -21.72335)
					(mid 162.473287 -21.083725)
					(end 161.833814 -21.277072)
				)
				(xy 161.831528 -21.275802) (xy 161.081466 -22.675596)
				(arc
					(start 161.083752 -22.676866)
					(mid 161.277046 -23.316184)
					(end 161.916364 -23.12289)
				)
				(xy 161.91865 -23.12416) (xy 162.668712 -21.72462) (xy 162.668458 -21.724366)
			)
		)
		(polygon
			(pts
				(arc
					(start 180.416454 -21.723096)
					(mid 180.222906 -21.083524)
					(end 179.583334 -21.277072)
				)
				(arc
					(start 178.836574 -22.671278)
					(mid 179.024276 -23.31492)
					(end 179.666646 -23.12289)
				)
			)
		)
		(polygon
			(pts
				(arc
					(start 160.416494 -21.723096)
					(mid 160.222946 -21.083524)
					(end 159.583374 -21.277072)
				)
				(arc
					(start 158.836614 -22.671278)
					(mid 159.024316 -23.31492)
					(end 159.666686 -23.12289)
				)
			)
		)
		(polygon
			(pts
				(arc
					(start 182.663592 -17.92859)
					(mid 182.47589 -17.284948)
					(end 181.83352 -17.476978)
				)
				(arc
					(start 181.083458 -18.877026)
					(mid 181.277006 -19.516598)
					(end 181.916578 -19.32305)
				)
			)
		)
		(polygon
			(pts
				(arc
					(start 180.413406 -17.92859)
					(mid 180.225704 -17.284948)
					(end 179.583334 -17.476978)
				)
				(arc
					(start 178.833526 -18.877026)
					(mid 179.027074 -19.516598)
					(end 179.666646 -19.32305)
				)
			)
		)
		(polygon
			(pts
				(arc
					(start 162.663632 -17.92859)
					(mid 162.47593 -17.284948)
					(end 161.83356 -17.476978)
				)
				(arc
					(start 161.083498 -18.877026)
					(mid 161.277046 -19.516598)
					(end 161.916618 -19.32305)
				)
			)
		)
		(polygon
			(pts
				(arc
					(start 160.413446 -17.92859)
					(mid 160.225744 -17.284948)
					(end 159.583374 -17.476978)
				)
				(arc
					(start 158.833566 -18.877026)
					(mid 159.027114 -19.516598)
					(end 159.666686 -19.32305)
				)
			)
		)
		(polygon
			(pts
				(xy 126.513844 -3.854958) (xy 119.696738 -3.854958) (xy 119.21617 -4.335526) (xy 111.81842 -4.335526)
				(xy 109.54766 -6.606286) (xy 109.54766 -15.273274) (xy 110.847886 -16.5735) (xy 120.456706 -16.5735)
				(xy 120.523 -16.639794) (xy 120.523 -17.833594) (xy 121.282206 -18.5928) (xy 126.850394 -18.5928)
				(xy 128.905 -16.538194) (xy 128.905 -11.965686) (xy 126.839218 -9.899904) (xy 126.839218 -4.180332)
			)
		)
	)
	(zone
		(layers "In1.Cu" "In2.Cu")
		(hatch none 0.5)
		(connect_pads
			(clearance 0)
		)
		(min_thickness 0.25)
		(keepout
			(tracks not_allowed)
			(vias allowed)
			(pads allowed)
			(copperpour not_allowed)
			(footprints allowed)
		)
		(placement
			(enabled no)
			(sheetname "")
		)
		(fill yes
			(thermal_gap 0.5)
			(thermal_bridge_width 0.5)
			(island_removal_mode 0)
		)
		(polygon
			(pts
				(arc
					(start 207.649572 -66.4972)
					(mid 207.613651 -66.512079)
					(end 207.598772 -66.548)
				)
				(arc
					(start 207.598772 -66.7512)
					(mid 207.613651 -66.787121)
					(end 207.649572 -66.802)
				)
				(arc
					(start 208.462372 -66.802)
					(mid 208.498293 -66.787121)
					(end 208.513172 -66.7512)
				)
				(arc
					(start 208.513172 -66.548)
					(mid 208.498293 -66.512079)
					(end 208.462372 -66.4972)
				)
			)
		)
	)
	(zone
		(layers "In1.Cu" "In2.Cu")
		(hatch none 0.5)
		(connect_pads
			(clearance 0)
		)
		(min_thickness 0.25)
		(keepout
			(tracks not_allowed)
			(vias allowed)
			(pads allowed)
			(copperpour not_allowed)
			(footprints allowed)
		)
		(placement
			(enabled no)
			(sheetname "")
		)
		(fill yes
			(thermal_gap 0.5)
			(thermal_bridge_width 0.5)
			(island_removal_mode 0)
		)
		(polygon
			(pts
				(arc
					(start 207.649572 -74.3204)
					(mid 207.613651 -74.335279)
					(end 207.598772 -74.3712)
				)
				(arc
					(start 207.598772 -74.5744)
					(mid 207.613651 -74.610321)
					(end 207.649572 -74.6252)
				)
				(arc
					(start 208.462372 -74.6252)
					(mid 208.498293 -74.610321)
					(end 208.513172 -74.5744)
				)
				(arc
					(start 208.513172 -74.3712)
					(mid 208.498293 -74.335279)
					(end 208.462372 -74.3204)
				)
			)
		)
	)
	(zone
		(layers "In1.Cu" "In2.Cu")
		(hatch none 0.5)
		(connect_pads
			(clearance 0)
		)
		(min_thickness 0.25)
		(keepout
			(tracks not_allowed)
			(vias allowed)
			(pads allowed)
			(copperpour not_allowed)
			(footprints allowed)
		)
		(placement
			(enabled no)
			(sheetname "")
		)
		(fill yes
			(thermal_gap 0.5)
			(thermal_bridge_width 0.5)
			(island_removal_mode 0)
		)
		(polygon
			(pts
				(arc
					(start 207.649572 -73.2028)
					(mid 207.613651 -73.217679)
					(end 207.598772 -73.2536)
				)
				(arc
					(start 207.598772 -73.4568)
					(mid 207.613651 -73.492721)
					(end 207.649572 -73.5076)
				)
				(arc
					(start 208.462372 -73.5076)
					(mid 208.498293 -73.492721)
					(end 208.513172 -73.4568)
				)
				(arc
					(start 208.513172 -73.2536)
					(mid 208.498293 -73.217679)
					(end 208.462372 -73.2028)
				)
			)
		)
	)
	(zone
		(layers "In1.Cu" "In2.Cu")
		(hatch none 0.5)
		(connect_pads
			(clearance 0)
		)
		(min_thickness 0.25)
		(keepout
			(tracks not_allowed)
			(vias allowed)
			(pads allowed)
			(copperpour not_allowed)
			(footprints allowed)
		)
		(placement
			(enabled no)
			(sheetname "")
		)
		(fill yes
			(thermal_gap 0.5)
			(thermal_bridge_width 0.5)
			(island_removal_mode 0)
		)
		(polygon
			(pts
				(arc
					(start 207.649572 -74.8792)
					(mid 207.613651 -74.894079)
					(end 207.598772 -74.93)
				)
				(arc
					(start 207.598772 -75.1332)
					(mid 207.613651 -75.169121)
					(end 207.649572 -75.184)
				)
				(arc
					(start 208.462372 -75.184)
					(mid 208.498293 -75.169121)
					(end 208.513172 -75.1332)
				)
				(arc
					(start 208.513172 -74.93)
					(mid 208.498293 -74.894079)
					(end 208.462372 -74.8792)
				)
			)
		)
	)
	(zone
		(layers "In1.Cu" "In2.Cu")
		(hatch none 0.5)
		(connect_pads
			(clearance 0)
		)
		(min_thickness 0.25)
		(keepout
			(tracks not_allowed)
			(vias allowed)
			(pads allowed)
			(copperpour not_allowed)
			(footprints allowed)
		)
		(placement
			(enabled no)
			(sheetname "")
		)
		(fill yes
			(thermal_gap 0.5)
			(thermal_bridge_width 0.5)
			(island_removal_mode 0)
		)
		(polygon
			(pts
				(xy 78.896464 -81.4959) (xy 80.953864 -81.4959) (xy 80.953864 -82.804) (xy 78.896464 -82.804)
			)
		)
	)
	(zone
		(layers "In1.Cu" "In2.Cu")
		(hatch none 0.5)
		(connect_pads
			(clearance 0)
		)
		(min_thickness 0.25)
		(keepout
			(tracks not_allowed)
			(vias allowed)
			(pads allowed)
			(copperpour not_allowed)
			(footprints allowed)
		)
		(placement
			(enabled no)
			(sheetname "")
		)
		(fill yes
			(thermal_gap 0.5)
			(thermal_bridge_width 0.5)
			(island_removal_mode 0)
		)
		(polygon
			(pts
				(arc
					(start 207.649572 -72.644)
					(mid 207.613651 -72.658879)
					(end 207.598772 -72.6948)
				)
				(arc
					(start 207.598772 -72.898)
					(mid 207.613651 -72.933921)
					(end 207.649572 -72.9488)
				)
				(arc
					(start 208.462372 -72.9488)
					(mid 208.498293 -72.933921)
					(end 208.513172 -72.898)
				)
				(arc
					(start 208.513172 -72.6948)
					(mid 208.498293 -72.658879)
					(end 208.462372 -72.644)
				)
			)
		)
	)
	(zone
		(layers "In1.Cu" "In2.Cu")
		(hatch none 0.5)
		(connect_pads
			(clearance 0)
		)
		(min_thickness 0.25)
		(keepout
			(tracks not_allowed)
			(vias allowed)
			(pads allowed)
			(copperpour not_allowed)
			(footprints allowed)
		)
		(placement
			(enabled no)
			(sheetname "")
		)
		(fill yes
			(thermal_gap 0.5)
			(thermal_bridge_width 0.5)
			(island_removal_mode 0)
		)
		(polygon
			(pts
				(arc
					(start 207.649572 -64.8208)
					(mid 207.613651 -64.835679)
					(end 207.598772 -64.8716)
				)
				(arc
					(start 207.598772 -65.0748)
					(mid 207.613651 -65.110721)
					(end 207.649572 -65.1256)
				)
				(arc
					(start 208.462372 -65.1256)
					(mid 208.498293 -65.110721)
					(end 208.513172 -65.0748)
				)
				(arc
					(start 208.513172 -64.8716)
					(mid 208.498293 -64.835679)
					(end 208.462372 -64.8208)
				)
			)
		)
	)
	(zone
		(layers "In1.Cu" "In2.Cu")
		(hatch none 0.5)
		(connect_pads
			(clearance 0)
		)
		(min_thickness 0.25)
		(keepout
			(tracks not_allowed)
			(vias allowed)
			(pads allowed)
			(copperpour not_allowed)
			(footprints allowed)
		)
		(placement
			(enabled no)
			(sheetname "")
		)
		(fill yes
			(thermal_gap 0.5)
			(thermal_bridge_width 0.5)
			(island_removal_mode 0)
		)
		(polygon
			(pts
				(arc
					(start 207.649572 -70.9676)
					(mid 207.613651 -70.982479)
					(end 207.598772 -71.0184)
				)
				(arc
					(start 207.598772 -71.2216)
					(mid 207.613651 -71.257521)
					(end 207.649572 -71.2724)
				)
				(arc
					(start 208.462372 -71.2724)
					(mid 208.498293 -71.257521)
					(end 208.513172 -71.2216)
				)
				(arc
					(start 208.513172 -71.0184)
					(mid 208.498293 -70.982479)
					(end 208.462372 -70.9676)
				)
			)
		)
	)
	(zone
		(layers "In1.Cu" "In2.Cu")
		(hatch none 0.5)
		(connect_pads
			(clearance 0)
		)
		(min_thickness 0.25)
		(keepout
			(tracks not_allowed)
			(vias allowed)
			(pads allowed)
			(copperpour not_allowed)
			(footprints allowed)
		)
		(placement
			(enabled no)
			(sheetname "")
		)
		(fill yes
			(thermal_gap 0.5)
			(thermal_bridge_width 0.5)
			(island_removal_mode 0)
		)
		(polygon
			(pts
				(xy 74.446384 -92.69603) (xy 76.503784 -92.69603) (xy 76.503784 -94.00413) (xy 74.446384 -94.00413)
			)
		)
	)
	(zone
		(layers "In1.Cu" "In2.Cu")
		(hatch none 0.5)
		(connect_pads
			(clearance 0)
		)
		(min_thickness 0.25)
		(keepout
			(tracks not_allowed)
			(vias allowed)
			(pads allowed)
			(copperpour not_allowed)
			(footprints allowed)
		)
		(placement
			(enabled no)
			(sheetname "")
		)
		(fill yes
			(thermal_gap 0.5)
			(thermal_bridge_width 0.5)
			(island_removal_mode 0)
		)
		(polygon
			(pts
				(xy 74.446384 -70.296024) (xy 76.503784 -70.296024) (xy 76.503784 -71.604124) (xy 74.446384 -71.604124)
			)
		)
	)
	(zone
		(layers "In1.Cu" "In2.Cu")
		(hatch none 0.5)
		(connect_pads
			(clearance 0)
		)
		(min_thickness 0.25)
		(keepout
			(tracks not_allowed)
			(vias allowed)
			(pads allowed)
			(copperpour not_allowed)
			(footprints allowed)
		)
		(placement
			(enabled no)
			(sheetname "")
		)
		(fill yes
			(thermal_gap 0.5)
			(thermal_bridge_width 0.5)
			(island_removal_mode 0)
		)
		(polygon
			(pts
				(arc
					(start 207.649572 -69.2912)
					(mid 207.613651 -69.306079)
					(end 207.598772 -69.342)
				)
				(arc
					(start 207.598772 -69.5452)
					(mid 207.613651 -69.581121)
					(end 207.649572 -69.596)
				)
				(arc
					(start 208.462372 -69.596)
					(mid 208.498293 -69.581121)
					(end 208.513172 -69.5452)
				)
				(arc
					(start 208.513172 -69.342)
					(mid 208.498293 -69.306079)
					(end 208.462372 -69.2912)
				)
			)
		)
	)
	(zone
		(layers "In1.Cu" "In2.Cu")
		(hatch none 0.5)
		(connect_pads
			(clearance 0)
		)
		(min_thickness 0.25)
		(keepout
			(tracks not_allowed)
			(vias allowed)
			(pads allowed)
			(copperpour not_allowed)
			(footprints allowed)
		)
		(placement
			(enabled no)
			(sheetname "")
		)
		(fill yes
			(thermal_gap 0.5)
			(thermal_bridge_width 0.5)
			(island_removal_mode 0)
		)
		(polygon
			(pts
				(arc
					(start 207.649572 -76.5556)
					(mid 207.613651 -76.570479)
					(end 207.598772 -76.6064)
				)
				(arc
					(start 207.598772 -76.8096)
					(mid 207.613651 -76.845521)
					(end 207.649572 -76.8604)
				)
				(arc
					(start 208.462372 -76.8604)
					(mid 208.498293 -76.845521)
					(end 208.513172 -76.8096)
				)
				(arc
					(start 208.513172 -76.6064)
					(mid 208.498293 -76.570479)
					(end 208.462372 -76.5556)
				)
			)
		)
	)
	(zone
		(layers "In1.Cu" "In2.Cu")
		(hatch none 0.5)
		(connect_pads
			(clearance 0)
		)
		(min_thickness 0.25)
		(keepout
			(tracks not_allowed)
			(vias allowed)
			(pads allowed)
			(copperpour not_allowed)
			(footprints allowed)
		)
		(placement
			(enabled no)
			(sheetname "")
		)
		(fill yes
			(thermal_gap 0.5)
			(thermal_bridge_width 0.5)
			(island_removal_mode 0)
		)
		(polygon
			(pts
				(xy 74.446384 -79.895954) (xy 76.503784 -79.895954) (xy 76.503784 -81.204054) (xy 74.446384 -81.204054)
			)
		)
	)
	(zone
		(layers "In1.Cu" "In2.Cu")
		(hatch none 0.5)
		(connect_pads
			(clearance 0)
		)
		(min_thickness 0.25)
		(keepout
			(tracks not_allowed)
			(vias allowed)
			(pads allowed)
			(copperpour not_allowed)
			(footprints allowed)
		)
		(placement
			(enabled no)
			(sheetname "")
		)
		(fill yes
			(thermal_gap 0.5)
			(thermal_bridge_width 0.5)
			(island_removal_mode 0)
		)
		(polygon
			(pts
				(arc
					(start 207.649572 -75.9968)
					(mid 207.613651 -76.011679)
					(end 207.598772 -76.0476)
				)
				(arc
					(start 207.598772 -76.2508)
					(mid 207.613651 -76.286721)
					(end 207.649572 -76.3016)
				)
				(arc
					(start 208.462372 -76.3016)
					(mid 208.498293 -76.286721)
					(end 208.513172 -76.2508)
				)
				(arc
					(start 208.513172 -76.0476)
					(mid 208.498293 -76.011679)
					(end 208.462372 -75.9968)
				)
			)
		)
	)
	(zone
		(layers "In1.Cu" "In2.Cu")
		(hatch none 0.5)
		(connect_pads
			(clearance 0)
		)
		(min_thickness 0.25)
		(keepout
			(tracks not_allowed)
			(vias allowed)
			(pads allowed)
			(copperpour not_allowed)
			(footprints allowed)
		)
		(placement
			(enabled no)
			(sheetname "")
		)
		(fill yes
			(thermal_gap 0.5)
			(thermal_bridge_width 0.5)
			(island_removal_mode 0)
		)
		(polygon
			(pts
				(xy 74.446384 -86.295992) (xy 76.503784 -86.295992) (xy 76.503784 -87.604092) (xy 74.446384 -87.604092)
			)
		)
	)
	(zone
		(layers "In1.Cu" "In2.Cu")
		(hatch none 0.5)
		(connect_pads
			(clearance 0)
		)
		(min_thickness 0.25)
		(keepout
			(tracks not_allowed)
			(vias allowed)
			(pads allowed)
			(copperpour not_allowed)
			(footprints allowed)
		)
		(placement
			(enabled no)
			(sheetname "")
		)
		(fill yes
			(thermal_gap 0.5)
			(thermal_bridge_width 0.5)
			(island_removal_mode 0)
		)
		(polygon
			(pts
				(xy 74.446384 -89.496138) (xy 76.503784 -89.496138) (xy 76.503784 -90.803984) (xy 74.446384 -90.803984)
			)
		)
	)
	(zone
		(layers "In1.Cu" "In2.Cu")
		(hatch none 0.5)
		(connect_pads
			(clearance 0)
		)
		(min_thickness 0.25)
		(keepout
			(tracks not_allowed)
			(vias allowed)
			(pads allowed)
			(copperpour not_allowed)
			(footprints allowed)
		)
		(placement
			(enabled no)
			(sheetname "")
		)
		(fill yes
			(thermal_gap 0.5)
			(thermal_bridge_width 0.5)
			(island_removal_mode 0)
		)
		(polygon
			(pts
				(xy 74.446384 -76.696062) (xy 76.503784 -76.696062) (xy 76.503784 -78.003908) (xy 74.446384 -78.003908)
			)
		)
	)
	(zone
		(layers "In1.Cu" "In2.Cu")
		(hatch none 0.5)
		(connect_pads
			(clearance 0)
		)
		(min_thickness 0.25)
		(keepout
			(tracks not_allowed)
			(vias allowed)
			(pads allowed)
			(copperpour not_allowed)
			(footprints allowed)
		)
		(placement
			(enabled no)
			(sheetname "")
		)
		(fill yes
			(thermal_gap 0.5)
			(thermal_bridge_width 0.5)
			(island_removal_mode 0)
		)
		(polygon
			(pts
				(xy 78.896464 -78.296008) (xy 80.953864 -78.296008) (xy 80.953864 -79.604108) (xy 78.896464 -79.604108)
			)
		)
	)
	(zone
		(layers "In1.Cu" "In2.Cu")
		(hatch none 0.5)
		(connect_pads
			(clearance 0)
		)
		(min_thickness 0.25)
		(keepout
			(tracks not_allowed)
			(vias allowed)
			(pads allowed)
			(copperpour not_allowed)
			(footprints allowed)
		)
		(placement
			(enabled no)
			(sheetname "")
		)
		(fill yes
			(thermal_gap 0.5)
			(thermal_bridge_width 0.5)
			(island_removal_mode 0)
		)
		(polygon
			(pts
				(xy 78.896464 -71.89597) (xy 80.953864 -71.89597) (xy 80.953864 -73.20407) (xy 78.896464 -73.20407)
			)
		)
	)
	(zone
		(layers "In1.Cu" "In2.Cu")
		(hatch none 0.5)
		(connect_pads
			(clearance 0)
		)
		(min_thickness 0.25)
		(keepout
			(tracks not_allowed)
			(vias allowed)
			(pads allowed)
			(copperpour not_allowed)
			(footprints allowed)
		)
		(placement
			(enabled no)
			(sheetname "")
		)
		(fill yes
			(thermal_gap 0.5)
			(thermal_bridge_width 0.5)
			(island_removal_mode 0)
		)
		(polygon
			(pts
				(arc
					(start 207.649572 -67.6148)
					(mid 207.613651 -67.629679)
					(end 207.598772 -67.6656)
				)
				(arc
					(start 207.598772 -67.8688)
					(mid 207.613651 -67.904721)
					(end 207.649572 -67.9196)
				)
				(arc
					(start 208.462372 -67.9196)
					(mid 208.498293 -67.904721)
					(end 208.513172 -67.8688)
				)
				(arc
					(start 208.513172 -67.6656)
					(mid 208.498293 -67.629679)
					(end 208.462372 -67.6148)
				)
			)
		)
	)
	(zone
		(layers "In1.Cu" "In2.Cu")
		(hatch none 0.5)
		(connect_pads
			(clearance 0)
		)
		(min_thickness 0.25)
		(keepout
			(tracks not_allowed)
			(vias allowed)
			(pads allowed)
			(copperpour not_allowed)
			(footprints allowed)
		)
		(placement
			(enabled no)
			(sheetname "")
		)
		(fill yes
			(thermal_gap 0.5)
			(thermal_bridge_width 0.5)
			(island_removal_mode 0)
		)
		(polygon
			(pts
				(xy 78.896464 -87.895938) (xy 80.953864 -87.895938) (xy 80.953864 -89.204038) (xy 78.896464 -89.204038)
			)
		)
	)
	(zone
		(layers "In1.Cu" "In2.Cu")
		(hatch none 0.5)
		(connect_pads
			(clearance 0)
		)
		(min_thickness 0.25)
		(keepout
			(tracks not_allowed)
			(vias allowed)
			(pads allowed)
			(copperpour not_allowed)
			(footprints allowed)
		)
		(placement
			(enabled no)
			(sheetname "")
		)
		(fill yes
			(thermal_gap 0.5)
			(thermal_bridge_width 0.5)
			(island_removal_mode 0)
		)
		(polygon
			(pts
				(arc
					(start 207.649572 -65.9384)
					(mid 207.613651 -65.953279)
					(end 207.598772 -65.9892)
				)
				(arc
					(start 207.598772 -66.1924)
					(mid 207.613651 -66.228321)
					(end 207.649572 -66.2432)
				)
				(arc
					(start 208.462372 -66.2432)
					(mid 208.498293 -66.228321)
					(end 208.513172 -66.1924)
				)
				(arc
					(start 208.513172 -65.9892)
					(mid 208.498293 -65.953279)
					(end 208.462372 -65.9384)
				)
			)
		)
	)
	(zone
		(layers "In1.Cu" "In2.Cu")
		(hatch none 0.5)
		(connect_pads
			(clearance 0)
		)
		(min_thickness 0.25)
		(keepout
			(tracks not_allowed)
			(vias allowed)
			(pads allowed)
			(copperpour not_allowed)
			(footprints allowed)
		)
		(placement
			(enabled no)
			(sheetname "")
		)
		(fill yes
			(thermal_gap 0.5)
			(thermal_bridge_width 0.5)
			(island_removal_mode 0)
		)
		(polygon
			(pts
				(xy 74.446384 -73.495916) (xy 76.503784 -73.495916) (xy 76.503784 -74.804016) (xy 74.446384 -74.804016)
			)
		)
	)
	(zone
		(layers "In1.Cu" "In2.Cu")
		(hatch none 0.5)
		(connect_pads
			(clearance 0)
		)
		(min_thickness 0.25)
		(keepout
			(tracks not_allowed)
			(vias allowed)
			(pads allowed)
			(copperpour not_allowed)
			(footprints allowed)
		)
		(placement
			(enabled no)
			(sheetname "")
		)
		(fill yes
			(thermal_gap 0.5)
			(thermal_bridge_width 0.5)
			(island_removal_mode 0)
		)
		(polygon
			(pts
				(xy 74.446384 -67.096132) (xy 76.503784 -67.096132) (xy 76.503784 -68.403978) (xy 74.446384 -68.403978)
			)
		)
	)
	(zone
		(layers "In1.Cu" "In2.Cu")
		(hatch none 0.5)
		(connect_pads
			(clearance 0)
		)
		(min_thickness 0.25)
		(keepout
			(tracks not_allowed)
			(vias allowed)
			(pads allowed)
			(copperpour not_allowed)
			(footprints allowed)
		)
		(placement
			(enabled no)
			(sheetname "")
		)
		(fill yes
			(thermal_gap 0.5)
			(thermal_bridge_width 0.5)
			(island_removal_mode 0)
		)
		(polygon
			(pts
				(arc
					(start 207.649572 -71.5264)
					(mid 207.613651 -71.541279)
					(end 207.598772 -71.5772)
				)
				(arc
					(start 207.598772 -71.7804)
					(mid 207.613651 -71.816321)
					(end 207.649572 -71.8312)
				)
				(arc
					(start 208.462372 -71.8312)
					(mid 208.498293 -71.816321)
					(end 208.513172 -71.7804)
				)
				(arc
					(start 208.513172 -71.5772)
					(mid 208.498293 -71.541279)
					(end 208.462372 -71.5264)
				)
			)
		)
	)
	(zone
		(layers "In1.Cu" "In2.Cu")
		(hatch none 0.5)
		(connect_pads
			(clearance 0)
		)
		(min_thickness 0.25)
		(keepout
			(tracks not_allowed)
			(vias allowed)
			(pads allowed)
			(copperpour not_allowed)
			(footprints allowed)
		)
		(placement
			(enabled no)
			(sheetname "")
		)
		(fill yes
			(thermal_gap 0.5)
			(thermal_bridge_width 0.5)
			(island_removal_mode 0)
		)
		(polygon
			(pts
				(xy 78.896464 -91.096084) (xy 80.953864 -91.096084) (xy 80.953864 -92.40393) (xy 78.896464 -92.40393)
			)
		)
	)
	(zone
		(layers "In1.Cu" "In2.Cu")
		(hatch none 0.5)
		(connect_pads
			(clearance 0)
		)
		(min_thickness 0.25)
		(keepout
			(tracks not_allowed)
			(vias allowed)
			(pads allowed)
			(copperpour not_allowed)
			(footprints allowed)
		)
		(placement
			(enabled no)
			(sheetname "")
		)
		(fill yes
			(thermal_gap 0.5)
			(thermal_bridge_width 0.5)
			(island_removal_mode 0)
		)
		(polygon
			(pts
				(xy 78.896464 -84.696046) (xy 80.953864 -84.696046) (xy 80.953864 -86.004146) (xy 78.896464 -86.004146)
			)
		)
	)
	(zone
		(layers "In1.Cu" "In2.Cu")
		(hatch none 0.5)
		(connect_pads
			(clearance 0)
		)
		(min_thickness 0.25)
		(keepout
			(tracks not_allowed)
			(vias allowed)
			(pads allowed)
			(copperpour not_allowed)
			(footprints allowed)
		)
		(placement
			(enabled no)
			(sheetname "")
		)
		(fill yes
			(thermal_gap 0.5)
			(thermal_bridge_width 0.5)
			(island_removal_mode 0)
		)
		(polygon
			(pts
				(xy 78.896464 -75.096116) (xy 80.953864 -75.096116) (xy 80.953864 -76.403962) (xy 78.896464 -76.403962)
			)
		)
	)
	(zone
		(layers "In1.Cu" "In2.Cu")
		(hatch none 0.5)
		(connect_pads
			(clearance 0)
		)
		(min_thickness 0.25)
		(keepout
			(tracks not_allowed)
			(vias allowed)
			(pads allowed)
			(copperpour not_allowed)
			(footprints allowed)
		)
		(placement
			(enabled no)
			(sheetname "")
		)
		(fill yes
			(thermal_gap 0.5)
			(thermal_bridge_width 0.5)
			(island_removal_mode 0)
		)
		(polygon
			(pts
				(xy 78.896464 -94.295976) (xy 80.953864 -94.295976) (xy 80.953864 -95.604076) (xy 78.896464 -95.604076)
			)
		)
	)
	(zone
		(layers "In1.Cu" "In2.Cu")
		(hatch none 0.5)
		(connect_pads
			(clearance 0)
		)
		(min_thickness 0.25)
		(keepout
			(tracks not_allowed)
			(vias allowed)
			(pads allowed)
			(copperpour not_allowed)
			(footprints allowed)
		)
		(placement
			(enabled no)
			(sheetname "")
		)
		(fill yes
			(thermal_gap 0.5)
			(thermal_bridge_width 0.5)
			(island_removal_mode 0)
		)
		(polygon
			(pts
				(arc
					(start 207.649572 -68.1736)
					(mid 207.613651 -68.188479)
					(end 207.598772 -68.2244)
				)
				(arc
					(start 207.598772 -68.4276)
					(mid 207.613651 -68.463521)
					(end 207.649572 -68.4784)
				)
				(arc
					(start 208.462372 -68.4784)
					(mid 208.498293 -68.463521)
					(end 208.513172 -68.4276)
				)
				(arc
					(start 208.513172 -68.2244)
					(mid 208.498293 -68.188479)
					(end 208.462372 -68.1736)
				)
			)
		)
	)
	(zone
		(layers "In1.Cu" "In2.Cu")
		(hatch none 0.5)
		(connect_pads
			(clearance 0)
		)
		(min_thickness 0.25)
		(keepout
			(tracks not_allowed)
			(vias allowed)
			(pads allowed)
			(copperpour not_allowed)
			(footprints allowed)
		)
		(placement
			(enabled no)
			(sheetname "")
		)
		(fill yes
			(thermal_gap 0.5)
			(thermal_bridge_width 0.5)
			(island_removal_mode 0)
		)
		(polygon
			(pts
				(arc
					(start 207.649572 -64.262)
					(mid 207.613651 -64.276879)
					(end 207.598772 -64.3128)
				)
				(arc
					(start 207.598772 -64.516)
					(mid 207.613651 -64.551921)
					(end 207.649572 -64.5668)
				)
				(arc
					(start 208.462372 -64.5668)
					(mid 208.498293 -64.551921)
					(end 208.513172 -64.516)
				)
				(arc
					(start 208.513172 -64.3128)
					(mid 208.498293 -64.276879)
					(end 208.462372 -64.262)
				)
			)
		)
	)
	(zone
		(layers "In1.Cu" "In2.Cu")
		(hatch none 0.5)
		(connect_pads
			(clearance 0)
		)
		(min_thickness 0.25)
		(keepout
			(tracks not_allowed)
			(vias allowed)
			(pads allowed)
			(copperpour not_allowed)
			(footprints allowed)
		)
		(placement
			(enabled no)
			(sheetname "")
		)
		(fill yes
			(thermal_gap 0.5)
			(thermal_bridge_width 0.5)
			(island_removal_mode 0)
		)
		(polygon
			(pts
				(arc
					(start 207.649572 -69.85)
					(mid 207.613651 -69.864879)
					(end 207.598772 -69.9008)
				)
				(arc
					(start 207.598772 -70.104)
					(mid 207.613651 -70.139921)
					(end 207.649572 -70.1548)
				)
				(arc
					(start 208.462372 -70.1548)
					(mid 208.498293 -70.139921)
					(end 208.513172 -70.104)
				)
				(arc
					(start 208.513172 -69.9008)
					(mid 208.498293 -69.864879)
					(end 208.462372 -69.85)
				)
			)
		)
	)
	(zone
		(layers "In1.Cu" "In2.Cu")
		(hatch none 0.5)
		(connect_pads
			(clearance 0)
		)
		(min_thickness 0.25)
		(keepout
			(tracks not_allowed)
			(vias allowed)
			(pads allowed)
			(copperpour not_allowed)
			(footprints allowed)
		)
		(placement
			(enabled no)
			(sheetname "")
		)
		(fill yes
			(thermal_gap 0.5)
			(thermal_bridge_width 0.5)
			(island_removal_mode 0)
		)
		(polygon
			(pts
				(xy 74.446384 -83.0961) (xy 76.503784 -83.0961) (xy 76.503784 -84.403946) (xy 74.446384 -84.403946)
			)
		)
	)
	(zone
		(layers "In1.Cu" "In2.Cu" "In3.Cu" "In4.Cu" "In5.Cu" "In6.Cu")
		(hatch none 0.5)
		(connect_pads
			(clearance 0)
		)
		(min_thickness 0.25)
		(keepout
			(tracks not_allowed)
			(vias allowed)
			(pads allowed)
			(copperpour not_allowed)
			(footprints allowed)
		)
		(placement
			(enabled no)
			(sheetname "")
		)
		(fill yes
			(thermal_gap 0.5)
			(thermal_bridge_width 0.5)
			(island_removal_mode 0)
		)
		(polygon
			(pts
				(arc
					(start 227.270564 -14.99997)
					(mid 217.729816 -14.99997)
					(end 227.270564 -14.99997)
				)
			)
		)
	)
	(zone
		(layers "In1.Cu" "In2.Cu" "In3.Cu" "In4.Cu" "In5.Cu" "In6.Cu")
		(hatch none 0.5)
		(connect_pads
			(clearance 0)
		)
		(min_thickness 0.25)
		(keepout
			(tracks not_allowed)
			(vias allowed)
			(pads allowed)
			(copperpour not_allowed)
			(footprints allowed)
		)
		(placement
			(enabled no)
			(sheetname "")
		)
		(fill yes
			(thermal_gap 0.5)
			(thermal_bridge_width 0.5)
			(island_removal_mode 0)
		)
		(polygon
			(pts
				(arc
					(start 17.270476 -187.999878)
					(mid 7.729728 -187.999878)
					(end 17.270476 -187.999878)
				)
			)
		)
	)
	(zone
		(layers "In1.Cu" "In2.Cu" "In3.Cu" "In4.Cu" "In5.Cu" "In6.Cu")
		(hatch none 0.5)
		(connect_pads
			(clearance 0)
		)
		(min_thickness 0.25)
		(keepout
			(tracks not_allowed)
			(vias allowed)
			(pads allowed)
			(copperpour not_allowed)
			(footprints allowed)
		)
		(placement
			(enabled no)
			(sheetname "")
		)
		(fill yes
			(thermal_gap 0.5)
			(thermal_bridge_width 0.5)
			(island_removal_mode 0)
		)
		(polygon
			(pts
				(arc
					(start 45.213778 -169.999914)
					(mid 37.686234 -169.999914)
					(end 45.213778 -169.999914)
				)
			)
		)
	)
	(zone
		(layers "In1.Cu" "In3.Cu" "In4.Cu" "In6.Cu")
		(hatch none 0.5)
		(connect_pads
			(clearance 0)
		)
		(min_thickness 0.25)
		(keepout
			(tracks not_allowed)
			(vias allowed)
			(pads allowed)
			(copperpour not_allowed)
			(footprints allowed)
		)
		(placement
			(enabled no)
			(sheetname "")
		)
		(fill yes
			(thermal_gap 0.5)
			(thermal_bridge_width 0.5)
			(island_removal_mode 0)
		)
		(polygon
			(pts
				(arc
					(start 118.385082 -33.20034)
					(mid 117.900069 -32.714946)
					(end 117.414802 -33.200086)
				)
				(arc
					(start 117.414802 -34.600134)
					(mid 117.899942 -35.085274)
					(end 118.385082 -34.600134)
				)
			)
		)
	)
	(zone
		(layers "In1.Cu" "In3.Cu" "In4.Cu" "In6.Cu")
		(hatch none 0.5)
		(connect_pads
			(clearance 0)
		)
		(min_thickness 0.25)
		(keepout
			(tracks not_allowed)
			(vias allowed)
			(pads allowed)
			(copperpour not_allowed)
			(footprints allowed)
		)
		(placement
			(enabled no)
			(sheetname "")
		)
		(fill yes
			(thermal_gap 0.5)
			(thermal_bridge_width 0.5)
			(island_removal_mode 0)
		)
		(polygon
			(pts
				(arc
					(start 204.698092 -85.146896)
					(mid 204.698092 -84.607908)
					(end 204.159104 -84.607908)
				)
				(arc
					(start 203.535534 -85.231732)
					(mid 203.528455 -85.772846)
					(end 204.069696 -85.775292)
				)
			)
		)
	)
	(zone
		(layers "In1.Cu" "In3.Cu" "In4.Cu" "In6.Cu")
		(hatch none 0.5)
		(connect_pads
			(clearance 0)
		)
		(min_thickness 0.25)
		(keepout
			(tracks not_allowed)
			(vias allowed)
			(pads allowed)
			(copperpour not_allowed)
			(footprints allowed)
		)
		(placement
			(enabled no)
			(sheetname "")
		)
		(fill yes
			(thermal_gap 0.5)
			(thermal_bridge_width 0.5)
			(island_removal_mode 0)
		)
		(polygon
			(pts
				(arc
					(start 134.585202 -32.000444)
					(mid 134.100189 -31.51505)
					(end 133.614922 -32.00019)
				)
				(arc
					(start 133.614922 -33.399984)
					(mid 134.100062 -33.885124)
					(end 134.585202 -33.399984)
				)
			)
		)
	)
	(zone
		(layers "In1.Cu" "In3.Cu" "In4.Cu" "In6.Cu")
		(hatch none 0.5)
		(connect_pads
			(clearance 0)
		)
		(min_thickness 0.25)
		(keepout
			(tracks not_allowed)
			(vias allowed)
			(pads allowed)
			(copperpour not_allowed)
			(footprints allowed)
		)
		(placement
			(enabled no)
			(sheetname "")
		)
		(fill yes
			(thermal_gap 0.5)
			(thermal_bridge_width 0.5)
			(island_removal_mode 0)
		)
		(polygon
			(pts
				(arc
					(start 116.584984 -32.000444)
					(mid 116.099971 -31.51505)
					(end 115.614704 -32.00019)
				)
				(arc
					(start 115.614704 -33.399984)
					(mid 116.099844 -33.885124)
					(end 116.584984 -33.399984)
				)
			)
		)
	)
	(zone
		(layers "In1.Cu" "In3.Cu" "In4.Cu" "In6.Cu")
		(hatch none 0.5)
		(connect_pads
			(clearance 0)
		)
		(min_thickness 0.25)
		(keepout
			(tracks not_allowed)
			(vias allowed)
			(pads allowed)
			(copperpour not_allowed)
			(footprints allowed)
		)
		(placement
			(enabled no)
			(sheetname "")
		)
		(fill yes
			(thermal_gap 0.5)
			(thermal_bridge_width 0.5)
			(island_removal_mode 0)
		)
		(polygon
			(pts
				(arc
					(start 181.083458 -18.877026)
					(mid 181.277006 -19.516598)
					(end 181.916578 -19.32305)
				)
				(arc
					(start 182.663592 -17.92859)
					(mid 182.47589 -17.284948)
					(end 181.83352 -17.476978)
				)
			)
		)
	)
	(zone
		(layers "In1.Cu" "In3.Cu" "In4.Cu" "In6.Cu")
		(hatch none 0.5)
		(connect_pads
			(clearance 0)
		)
		(min_thickness 0.25)
		(keepout
			(tracks not_allowed)
			(vias allowed)
			(pads allowed)
			(copperpour not_allowed)
			(footprints allowed)
		)
		(placement
			(enabled no)
			(sheetname "")
		)
		(fill yes
			(thermal_gap 0.5)
			(thermal_bridge_width 0.5)
			(island_removal_mode 0)
		)
		(polygon
			(pts
				(arc
					(start 158.836614 -22.671278)
					(mid 159.024316 -23.31492)
					(end 159.666686 -23.12289)
				)
				(arc
					(start 160.416494 -21.723096)
					(mid 160.222946 -21.083524)
					(end 159.583374 -21.277072)
				)
			)
		)
	)
	(zone
		(layers "In1.Cu" "In3.Cu" "In4.Cu" "In6.Cu")
		(hatch none 0.5)
		(connect_pads
			(clearance 0)
		)
		(min_thickness 0.25)
		(keepout
			(tracks not_allowed)
			(vias allowed)
			(pads allowed)
			(copperpour not_allowed)
			(footprints allowed)
		)
		(placement
			(enabled no)
			(sheetname "")
		)
		(fill yes
			(thermal_gap 0.5)
			(thermal_bridge_width 0.5)
			(island_removal_mode 0)
		)
		(polygon
			(pts
				(arc
					(start 114.78514 -36.800282)
					(mid 114.300127 -36.314888)
					(end 113.81486 -36.800028)
				)
				(arc
					(start 113.81486 -38.200076)
					(mid 114.3 -38.685216)
					(end 114.78514 -38.200076)
				)
			)
		)
	)
	(zone
		(layers "In1.Cu" "In3.Cu" "In4.Cu" "In6.Cu")
		(hatch none 0.5)
		(connect_pads
			(clearance 0)
		)
		(min_thickness 0.25)
		(keepout
			(tracks not_allowed)
			(vias allowed)
			(pads allowed)
			(copperpour not_allowed)
			(footprints allowed)
		)
		(placement
			(enabled no)
			(sheetname "")
		)
		(fill yes
			(thermal_gap 0.5)
			(thermal_bridge_width 0.5)
			(island_removal_mode 0)
		)
		(polygon
			(pts
				(arc
					(start 132.785104 -36.800282)
					(mid 132.300091 -36.314888)
					(end 131.814824 -36.800028)
				)
				(arc
					(start 131.814824 -38.200076)
					(mid 132.299964 -38.685216)
					(end 132.785104 -38.200076)
				)
			)
		)
	)
	(zone
		(layers "In1.Cu" "In3.Cu" "In4.Cu" "In6.Cu")
		(hatch none 0.5)
		(connect_pads
			(clearance 0)
		)
		(min_thickness 0.25)
		(keepout
			(tracks not_allowed)
			(vias allowed)
			(pads allowed)
			(copperpour not_allowed)
			(footprints allowed)
		)
		(placement
			(enabled no)
			(sheetname "")
		)
		(fill yes
			(thermal_gap 0.5)
			(thermal_bridge_width 0.5)
			(island_removal_mode 0)
		)
		(polygon
			(pts
				(arc
					(start 112.985042 -35.600386)
					(mid 112.500029 -35.114992)
					(end 112.014762 -35.600132)
				)
				(arc
					(start 112.014762 -37.00018)
					(mid 112.499902 -37.48532)
					(end 112.985042 -37.00018)
				)
			)
		)
	)
	(zone
		(layers "In1.Cu" "In3.Cu" "In4.Cu" "In6.Cu")
		(hatch none 0.5)
		(connect_pads
			(clearance 0)
		)
		(min_thickness 0.25)
		(keepout
			(tracks not_allowed)
			(vias allowed)
			(pads allowed)
			(copperpour not_allowed)
			(footprints allowed)
		)
		(placement
			(enabled no)
			(sheetname "")
		)
		(fill yes
			(thermal_gap 0.5)
			(thermal_bridge_width 0.5)
			(island_removal_mode 0)
		)
		(polygon
			(pts
				(arc
					(start 194.944492 -83.927696)
					(mid 194.944492 -83.388708)
					(end 194.405504 -83.388708)
				)
				(arc
					(start 193.781934 -84.012532)
					(mid 193.774855 -84.553646)
					(end 194.316096 -84.556092)
				)
			)
		)
	)
	(zone
		(layers "In1.Cu" "In3.Cu" "In4.Cu" "In6.Cu")
		(hatch none 0.5)
		(connect_pads
			(clearance 0)
		)
		(min_thickness 0.25)
		(keepout
			(tracks not_allowed)
			(vias allowed)
			(pads allowed)
			(copperpour not_allowed)
			(footprints allowed)
		)
		(placement
			(enabled no)
			(sheetname "")
		)
		(fill yes
			(thermal_gap 0.5)
			(thermal_bridge_width 0.5)
			(island_removal_mode 0)
		)
		(polygon
			(pts
				(arc
					(start 83.741768 -75.305158)
					(mid 83.358228 -74.921618)
					(end 82.974688 -75.305158)
				)
				(arc
					(start 82.974688 -76.193904)
					(mid 83.358101 -76.577698)
					(end 83.741768 -76.194158)
				)
			)
		)
	)
	(zone
		(layers "In1.Cu" "In3.Cu" "In4.Cu" "In6.Cu")
		(hatch none 0.5)
		(connect_pads
			(clearance 0)
		)
		(min_thickness 0.25)
		(keepout
			(tracks not_allowed)
			(vias allowed)
			(pads allowed)
			(copperpour not_allowed)
			(footprints allowed)
		)
		(placement
			(enabled no)
			(sheetname "")
		)
		(fill yes
			(thermal_gap 0.5)
			(thermal_bridge_width 0.5)
			(island_removal_mode 0)
		)
		(polygon
			(pts
				(arc
					(start 112.985042 -32.000444)
					(mid 112.500029 -31.51505)
					(end 112.014762 -32.00019)
				)
				(arc
					(start 112.014762 -33.399984)
					(mid 112.499902 -33.885124)
					(end 112.985042 -33.399984)
				)
			)
		)
	)
	(zone
		(layers "In1.Cu" "In3.Cu" "In4.Cu" "In6.Cu")
		(hatch none 0.5)
		(connect_pads
			(clearance 0)
		)
		(min_thickness 0.25)
		(keepout
			(tracks not_allowed)
			(vias allowed)
			(pads allowed)
			(copperpour not_allowed)
			(footprints allowed)
		)
		(placement
			(enabled no)
			(sheetname "")
		)
		(fill yes
			(thermal_gap 0.5)
			(thermal_bridge_width 0.5)
			(island_removal_mode 0)
		)
		(polygon
			(pts
				(arc
					(start 111.185198 -33.20034)
					(mid 110.700185 -32.714946)
					(end 110.214918 -33.200086)
				)
				(arc
					(start 110.214918 -34.600134)
					(mid 110.700058 -35.085274)
					(end 111.185198 -34.600134)
				)
			)
		)
	)
	(zone
		(layers "In1.Cu" "In3.Cu" "In4.Cu" "In6.Cu")
		(hatch none 0.5)
		(connect_pads
			(clearance 0)
		)
		(min_thickness 0.25)
		(keepout
			(tracks not_allowed)
			(vias allowed)
			(pads allowed)
			(copperpour not_allowed)
			(footprints allowed)
		)
		(placement
			(enabled no)
			(sheetname "")
		)
		(fill yes
			(thermal_gap 0.5)
			(thermal_bridge_width 0.5)
			(island_removal_mode 0)
		)
		(polygon
			(pts
				(arc
					(start 85.367368 -78.504796)
					(mid 84.983828 -78.121256)
					(end 84.600288 -78.504796)
				)
				(arc
					(start 84.600288 -79.393542)
					(mid 84.983701 -79.777336)
					(end 85.367368 -79.393796)
				)
			)
		)
	)
	(zone
		(layers "In1.Cu" "In3.Cu" "In4.Cu" "In6.Cu")
		(hatch none 0.5)
		(connect_pads
			(clearance 0)
		)
		(min_thickness 0.25)
		(keepout
			(tracks not_allowed)
			(vias allowed)
			(pads allowed)
			(copperpour not_allowed)
			(footprints allowed)
		)
		(placement
			(enabled no)
			(sheetname "")
		)
		(fill yes
			(thermal_gap 0.5)
			(thermal_bridge_width 0.5)
			(island_removal_mode 0)
		)
		(polygon
			(pts
				(arc
					(start 139.984988 -36.800282)
					(mid 139.499975 -36.314888)
					(end 139.014708 -36.800028)
				)
				(arc
					(start 139.014708 -38.200076)
					(mid 139.499848 -38.685216)
					(end 139.984988 -38.200076)
				)
			)
		)
	)
	(zone
		(layers "In1.Cu" "In3.Cu" "In4.Cu" "In6.Cu")
		(hatch none 0.5)
		(connect_pads
			(clearance 0)
		)
		(min_thickness 0.25)
		(keepout
			(tracks not_allowed)
			(vias allowed)
			(pads allowed)
			(copperpour not_allowed)
			(footprints allowed)
		)
		(placement
			(enabled no)
			(sheetname "")
		)
		(fill yes
			(thermal_gap 0.5)
			(thermal_bridge_width 0.5)
			(island_removal_mode 0)
		)
		(polygon
			(pts
				(arc
					(start 77.658214 -67.322446)
					(mid 77.274801 -66.938652)
					(end 76.891134 -67.322192)
				)
				(arc
					(start 76.891134 -68.211192)
					(mid 77.274674 -68.594732)
					(end 77.658214 -68.211192)
				)
			)
		)
	)
	(zone
		(layers "In1.Cu" "In3.Cu" "In4.Cu" "In6.Cu")
		(hatch none 0.5)
		(connect_pads
			(clearance 0)
		)
		(min_thickness 0.25)
		(keepout
			(tracks not_allowed)
			(vias allowed)
			(pads allowed)
			(copperpour not_allowed)
			(footprints allowed)
		)
		(placement
			(enabled no)
			(sheetname "")
		)
		(fill yes
			(thermal_gap 0.5)
			(thermal_bridge_width 0.5)
			(island_removal_mode 0)
		)
		(polygon
			(pts
				(xy 212.97138 -68.288408) (xy 213.779354 -67.48018)
				(arc
					(start 213.779354 -67.479926)
					(mid 213.779354 -66.941446)
					(end 213.240874 -66.941446)
				)
				(xy 213.24062 -66.941192) (xy 212.432392 -67.74942)
				(arc
					(start 212.432646 -67.749674)
					(mid 212.432646 -68.288154)
					(end 212.971126 -68.288154)
				)
			)
		)
	)
	(zone
		(layers "In1.Cu" "In3.Cu" "In4.Cu" "In6.Cu")
		(hatch none 0.5)
		(connect_pads
			(clearance 0)
		)
		(min_thickness 0.25)
		(keepout
			(tracks not_allowed)
			(vias allowed)
			(pads allowed)
			(copperpour not_allowed)
			(footprints allowed)
		)
		(placement
			(enabled no)
			(sheetname "")
		)
		(fill yes
			(thermal_gap 0.5)
			(thermal_bridge_width 0.5)
			(island_removal_mode 0)
		)
		(polygon
			(pts
				(arc
					(start 161.083498 -18.877026)
					(mid 161.277046 -19.516598)
					(end 161.916618 -19.32305)
				)
				(arc
					(start 162.663632 -17.92859)
					(mid 162.47593 -17.284948)
					(end 161.83356 -17.476978)
				)
			)
		)
	)
	(zone
		(layers "In1.Cu" "In3.Cu" "In4.Cu" "In6.Cu")
		(hatch none 0.5)
		(connect_pads
			(clearance 0)
		)
		(min_thickness 0.25)
		(keepout
			(tracks not_allowed)
			(vias allowed)
			(pads allowed)
			(copperpour not_allowed)
			(footprints allowed)
		)
		(placement
			(enabled no)
			(sheetname "")
		)
		(fill yes
			(thermal_gap 0.5)
			(thermal_bridge_width 0.5)
			(island_removal_mode 0)
		)
		(polygon
			(pts
				(arc
					(start 141.785086 -35.600386)
					(mid 141.300073 -35.114992)
					(end 140.814806 -35.600132)
				)
				(arc
					(start 140.814806 -37.00018)
					(mid 141.299946 -37.48532)
					(end 141.785086 -37.00018)
				)
			)
		)
	)
	(zone
		(layers "In1.Cu" "In3.Cu" "In4.Cu" "In6.Cu")
		(hatch none 0.5)
		(connect_pads
			(clearance 0)
		)
		(min_thickness 0.25)
		(keepout
			(tracks not_allowed)
			(vias allowed)
			(pads allowed)
			(copperpour not_allowed)
			(footprints allowed)
		)
		(placement
			(enabled no)
			(sheetname "")
		)
		(fill yes
			(thermal_gap 0.5)
			(thermal_bridge_width 0.5)
			(island_removal_mode 0)
		)
		(polygon
			(pts
				(arc
					(start 178.833526 -30.277054)
					(mid 179.027074 -30.916626)
					(end 179.666646 -30.723078)
				)
				(arc
					(start 180.413406 -29.328618)
					(mid 180.225704 -28.684976)
					(end 179.583334 -28.877006)
				)
			)
		)
	)
	(zone
		(layers "In1.Cu" "In3.Cu" "In4.Cu" "In6.Cu")
		(hatch none 0.5)
		(connect_pads
			(clearance 0)
		)
		(min_thickness 0.25)
		(keepout
			(tracks not_allowed)
			(vias allowed)
			(pads allowed)
			(copperpour not_allowed)
			(footprints allowed)
		)
		(placement
			(enabled no)
			(sheetname "")
		)
		(fill yes
			(thermal_gap 0.5)
			(thermal_bridge_width 0.5)
			(island_removal_mode 0)
		)
		(polygon
			(pts
				(arc
					(start 197.793864 -85.604096)
					(mid 197.793864 -85.065108)
					(end 197.254876 -85.065108)
				)
				(arc
					(start 196.631306 -85.688932)
					(mid 196.624227 -86.230046)
					(end 197.165468 -86.232492)
				)
			)
		)
	)
	(zone
		(layers "In1.Cu" "In3.Cu" "In4.Cu" "In6.Cu")
		(hatch none 0.5)
		(connect_pads
			(clearance 0)
		)
		(min_thickness 0.25)
		(keepout
			(tracks not_allowed)
			(vias allowed)
			(pads allowed)
			(copperpour not_allowed)
			(footprints allowed)
		)
		(placement
			(enabled no)
			(sheetname "")
		)
		(fill yes
			(thermal_gap 0.5)
			(thermal_bridge_width 0.5)
			(island_removal_mode 0)
		)
		(polygon
			(pts
				(arc
					(start 138.185144 -35.600386)
					(mid 137.700131 -35.114992)
					(end 137.214864 -35.600132)
				)
				(arc
					(start 137.214864 -37.00018)
					(mid 137.700004 -37.48532)
					(end 138.185144 -37.00018)
				)
			)
		)
	)
	(zone
		(layers "In1.Cu" "In3.Cu" "In4.Cu" "In6.Cu")
		(hatch none 0.5)
		(connect_pads
			(clearance 0)
		)
		(min_thickness 0.25)
		(keepout
			(tracks not_allowed)
			(vias allowed)
			(pads allowed)
			(copperpour not_allowed)
			(footprints allowed)
		)
		(placement
			(enabled no)
			(sheetname "")
		)
		(fill yes
			(thermal_gap 0.5)
			(thermal_bridge_width 0.5)
			(island_removal_mode 0)
		)
		(polygon
			(pts
				(arc
					(start 85.367368 -84.904834)
					(mid 84.983828 -84.521294)
					(end 84.600288 -84.904834)
				)
				(arc
					(start 84.600288 -85.79358)
					(mid 84.983701 -86.177374)
					(end 85.367368 -85.793834)
				)
			)
		)
	)
	(zone
		(layers "In1.Cu" "In3.Cu" "In4.Cu" "In6.Cu")
		(hatch none 0.5)
		(connect_pads
			(clearance 0)
		)
		(min_thickness 0.25)
		(keepout
			(tracks not_allowed)
			(vias allowed)
			(pads allowed)
			(copperpour not_allowed)
			(footprints allowed)
		)
		(placement
			(enabled no)
			(sheetname "")
		)
		(fill yes
			(thermal_gap 0.5)
			(thermal_bridge_width 0.5)
			(island_removal_mode 0)
		)
		(polygon
			(pts
				(arc
					(start 161.083498 -26.47696)
					(mid 161.277046 -27.116532)
					(end 161.916618 -26.922984)
				)
				(arc
					(start 162.663632 -25.528524)
					(mid 162.47593 -24.884882)
					(end 161.83356 -25.076912)
				)
			)
		)
	)
	(zone
		(layers "In1.Cu" "In3.Cu" "In4.Cu" "In6.Cu")
		(hatch none 0.5)
		(connect_pads
			(clearance 0)
		)
		(min_thickness 0.25)
		(keepout
			(tracks not_allowed)
			(vias allowed)
			(pads allowed)
			(copperpour not_allowed)
			(footprints allowed)
		)
		(placement
			(enabled no)
			(sheetname "")
		)
		(fill yes
			(thermal_gap 0.5)
			(thermal_bridge_width 0.5)
			(island_removal_mode 0)
		)
		(polygon
			(pts
				(xy 211.329524 -64.194182) (xy 212.137498 -63.385954)
				(arc
					(start 212.137498 -63.3857)
					(mid 212.137498 -62.84722)
					(end 211.599018 -62.84722)
				)
				(xy 211.598764 -62.846966) (xy 210.790536 -63.655194)
				(arc
					(start 210.79079 -63.655448)
					(mid 210.79079 -64.193928)
					(end 211.32927 -64.193928)
				)
			)
		)
	)
	(zone
		(layers "In1.Cu" "In3.Cu" "In4.Cu" "In6.Cu")
		(hatch none 0.5)
		(connect_pads
			(clearance 0)
		)
		(min_thickness 0.25)
		(keepout
			(tracks not_allowed)
			(vias allowed)
			(pads allowed)
			(copperpour not_allowed)
			(footprints allowed)
		)
		(placement
			(enabled no)
			(sheetname "")
		)
		(fill yes
			(thermal_gap 0.5)
			(thermal_bridge_width 0.5)
			(island_removal_mode 0)
		)
		(polygon
			(pts
				(arc
					(start 178.836574 -22.671278)
					(mid 179.024276 -23.31492)
					(end 179.666646 -23.12289)
				)
				(arc
					(start 180.416454 -21.723096)
					(mid 180.222906 -21.083524)
					(end 179.583334 -21.277072)
				)
			)
		)
	)
	(zone
		(layers "In1.Cu" "In3.Cu" "In4.Cu" "In6.Cu")
		(hatch none 0.5)
		(connect_pads
			(clearance 0)
		)
		(min_thickness 0.25)
		(keepout
			(tracks not_allowed)
			(vias allowed)
			(pads allowed)
			(copperpour not_allowed)
			(footprints allowed)
		)
		(placement
			(enabled no)
			(sheetname "")
		)
		(fill yes
			(thermal_gap 0.5)
			(thermal_bridge_width 0.5)
			(island_removal_mode 0)
		)
		(polygon
			(pts
				(arc
					(start 78.505558 -83.335368)
					(mid 78.122018 -82.951828)
					(end 77.738478 -83.335368)
				)
				(arc
					(start 77.738478 -84.224114)
					(mid 78.121891 -84.607908)
					(end 78.505558 -84.224368)
				)
			)
		)
	)
	(zone
		(layers "In1.Cu" "In3.Cu" "In4.Cu" "In6.Cu")
		(hatch none 0.5)
		(connect_pads
			(clearance 0)
		)
		(min_thickness 0.25)
		(keepout
			(tracks not_allowed)
			(vias allowed)
			(pads allowed)
			(copperpour not_allowed)
			(footprints allowed)
		)
		(placement
			(enabled no)
			(sheetname "")
		)
		(fill yes
			(thermal_gap 0.5)
			(thermal_bridge_width 0.5)
			(island_removal_mode 0)
		)
		(polygon
			(pts
				(arc
					(start 134.585202 -35.600386)
					(mid 134.100189 -35.114992)
					(end 133.614922 -35.600132)
				)
				(arc
					(start 133.614922 -37.00018)
					(mid 134.100062 -37.48532)
					(end 134.585202 -37.00018)
				)
			)
		)
	)
	(zone
		(layers "In1.Cu" "In3.Cu" "In4.Cu" "In6.Cu")
		(hatch none 0.5)
		(connect_pads
			(clearance 0)
		)
		(min_thickness 0.25)
		(keepout
			(tracks not_allowed)
			(vias allowed)
			(pads allowed)
			(copperpour not_allowed)
			(footprints allowed)
		)
		(placement
			(enabled no)
			(sheetname "")
		)
		(fill yes
			(thermal_gap 0.5)
			(thermal_bridge_width 0.5)
			(island_removal_mode 0)
		)
		(polygon
			(pts
				(arc
					(start 178.811174 -26.465022)
					(mid 179.015136 -27.138884)
					(end 179.688998 -26.934922)
				)
				(arc
					(start 180.43398 -25.543764)
					(mid 180.239312 -24.863383)
					(end 179.560982 -25.064974)
				)
			)
		)
	)
	(zone
		(layers "In1.Cu" "In3.Cu" "In4.Cu" "In6.Cu")
		(hatch none 0.5)
		(connect_pads
			(clearance 0)
		)
		(min_thickness 0.25)
		(keepout
			(tracks not_allowed)
			(vias allowed)
			(pads allowed)
			(copperpour not_allowed)
			(footprints allowed)
		)
		(placement
			(enabled no)
			(sheetname "")
		)
		(fill yes
			(thermal_gap 0.5)
			(thermal_bridge_width 0.5)
			(island_removal_mode 0)
		)
		(polygon
			(pts
				(arc
					(start 107.585002 -33.20034)
					(mid 107.099989 -32.714946)
					(end 106.614722 -33.200086)
				)
				(arc
					(start 106.614722 -34.600134)
					(mid 107.099862 -35.085274)
					(end 107.585002 -34.600134)
				)
			)
		)
	)
	(zone
		(layers "In1.Cu" "In3.Cu" "In4.Cu" "In6.Cu")
		(hatch none 0.5)
		(connect_pads
			(clearance 0)
		)
		(min_thickness 0.25)
		(keepout
			(tracks not_allowed)
			(vias allowed)
			(pads allowed)
			(copperpour not_allowed)
			(footprints allowed)
		)
		(placement
			(enabled no)
			(sheetname "")
		)
		(fill yes
			(thermal_gap 0.5)
			(thermal_bridge_width 0.5)
			(island_removal_mode 0)
		)
		(polygon
			(pts
				(xy 211.49818 -66.637408) (xy 212.306154 -65.82918)
				(arc
					(start 212.306154 -65.828926)
					(mid 212.306154 -65.290446)
					(end 211.767674 -65.290446)
				)
				(xy 211.76742 -65.290192) (xy 210.959192 -66.09842)
				(arc
					(start 210.959446 -66.098674)
					(mid 210.959446 -66.637154)
					(end 211.497926 -66.637154)
				)
			)
		)
	)
	(zone
		(layers "In1.Cu" "In3.Cu" "In4.Cu" "In6.Cu")
		(hatch none 0.5)
		(connect_pads
			(clearance 0)
		)
		(min_thickness 0.25)
		(keepout
			(tracks not_allowed)
			(vias allowed)
			(pads allowed)
			(copperpour not_allowed)
			(footprints allowed)
		)
		(placement
			(enabled no)
			(sheetname "")
		)
		(fill yes
			(thermal_gap 0.5)
			(thermal_bridge_width 0.5)
			(island_removal_mode 0)
		)
		(polygon
			(pts
				(arc
					(start 181.061106 -26.464768)
					(mid 181.264814 -27.138884)
					(end 181.93893 -26.935176)
				)
				(arc
					(start 182.684166 -25.543764)
					(mid 182.489596 -24.863437)
					(end 181.811168 -25.06472)
				)
			)
		)
	)
	(zone
		(layers "In1.Cu" "In3.Cu" "In4.Cu" "In6.Cu")
		(hatch none 0.5)
		(connect_pads
			(clearance 0)
		)
		(min_thickness 0.25)
		(keepout
			(tracks not_allowed)
			(vias allowed)
			(pads allowed)
			(copperpour not_allowed)
			(footprints allowed)
		)
		(placement
			(enabled no)
			(sheetname "")
		)
		(fill yes
			(thermal_gap 0.5)
			(thermal_bridge_width 0.5)
			(island_removal_mode 0)
		)
		(polygon
			(pts
				(arc
					(start 77.667358 -73.708768)
					(mid 77.283818 -73.325228)
					(end 76.900278 -73.708768)
				)
				(arc
					(start 76.900278 -74.597514)
					(mid 77.283691 -74.981308)
					(end 77.667358 -74.597768)
				)
			)
		)
	)
	(zone
		(layers "In1.Cu" "In3.Cu" "In4.Cu" "In6.Cu")
		(hatch none 0.5)
		(connect_pads
			(clearance 0)
		)
		(min_thickness 0.25)
		(keepout
			(tracks not_allowed)
			(vias allowed)
			(pads allowed)
			(copperpour not_allowed)
			(footprints allowed)
		)
		(placement
			(enabled no)
			(sheetname "")
		)
		(fill yes
			(thermal_gap 0.5)
			(thermal_bridge_width 0.5)
			(island_removal_mode 0)
		)
		(polygon
			(pts
				(arc
					(start 138.185144 -32.000444)
					(mid 137.700131 -31.51505)
					(end 137.214864 -32.00019)
				)
				(arc
					(start 137.214864 -33.399984)
					(mid 137.700004 -33.885124)
					(end 138.185144 -33.399984)
				)
			)
		)
	)
	(zone
		(layers "In1.Cu" "In3.Cu" "In4.Cu" "In6.Cu")
		(hatch none 0.5)
		(connect_pads
			(clearance 0)
		)
		(min_thickness 0.25)
		(keepout
			(tracks not_allowed)
			(vias allowed)
			(pads allowed)
			(copperpour not_allowed)
			(footprints allowed)
		)
		(placement
			(enabled no)
			(sheetname "")
		)
		(fill yes
			(thermal_gap 0.5)
			(thermal_bridge_width 0.5)
			(island_removal_mode 0)
		)
		(polygon
			(pts
				(arc
					(start 190.448692 -84.156296)
					(mid 190.448692 -83.617308)
					(end 189.909704 -83.617308)
				)
				(arc
					(start 189.286134 -84.241132)
					(mid 189.279055 -84.782246)
					(end 189.820296 -84.784692)
				)
			)
		)
	)
	(zone
		(layers "In1.Cu" "In3.Cu" "In4.Cu" "In6.Cu")
		(hatch none 0.5)
		(connect_pads
			(clearance 0)
		)
		(min_thickness 0.25)
		(keepout
			(tracks not_allowed)
			(vias allowed)
			(pads allowed)
			(copperpour not_allowed)
			(footprints allowed)
		)
		(placement
			(enabled no)
			(sheetname "")
		)
		(fill yes
			(thermal_gap 0.5)
			(thermal_bridge_width 0.5)
			(island_removal_mode 0)
		)
		(polygon
			(pts
				(arc
					(start 158.833566 -18.877026)
					(mid 159.027114 -19.516598)
					(end 159.666686 -19.32305)
				)
				(arc
					(start 160.413446 -17.92859)
					(mid 160.225744 -17.284948)
					(end 159.583374 -17.476978)
				)
			)
		)
	)
	(zone
		(layers "In1.Cu" "In3.Cu" "In4.Cu" "In6.Cu")
		(hatch none 0.5)
		(connect_pads
			(clearance 0)
		)
		(min_thickness 0.25)
		(keepout
			(tracks not_allowed)
			(vias allowed)
			(pads allowed)
			(copperpour not_allowed)
			(footprints allowed)
		)
		(placement
			(enabled no)
			(sheetname "")
		)
		(fill yes
			(thermal_gap 0.5)
			(thermal_bridge_width 0.5)
			(island_removal_mode 0)
		)
		(polygon
			(pts
				(arc
					(start 129.185162 -36.800282)
					(mid 128.700149 -36.314888)
					(end 128.214882 -36.800028)
				)
				(arc
					(start 128.214882 -38.200076)
					(mid 128.700022 -38.685216)
					(end 129.185162 -38.200076)
				)
			)
		)
	)
	(zone
		(layers "In1.Cu" "In3.Cu" "In4.Cu" "In6.Cu")
		(hatch none 0.5)
		(connect_pads
			(clearance 0)
		)
		(min_thickness 0.25)
		(keepout
			(tracks not_allowed)
			(vias allowed)
			(pads allowed)
			(copperpour not_allowed)
			(footprints allowed)
		)
		(placement
			(enabled no)
			(sheetname "")
		)
		(fill yes
			(thermal_gap 0.5)
			(thermal_bridge_width 0.5)
			(island_removal_mode 0)
		)
		(polygon
			(pts
				(arc
					(start 129.185162 -33.20034)
					(mid 128.700149 -32.714946)
					(end 128.214882 -33.200086)
				)
				(arc
					(start 128.214882 -34.600134)
					(mid 128.700022 -35.085274)
					(end 129.185162 -34.600134)
				)
			)
		)
	)
	(zone
		(layers "In1.Cu" "In3.Cu" "In4.Cu" "In6.Cu")
		(hatch none 0.5)
		(connect_pads
			(clearance 0)
		)
		(min_thickness 0.25)
		(keepout
			(tracks not_allowed)
			(vias allowed)
			(pads allowed)
			(copperpour not_allowed)
			(footprints allowed)
		)
		(placement
			(enabled no)
			(sheetname "")
		)
		(fill yes
			(thermal_gap 0.5)
			(thermal_bridge_width 0.5)
			(island_removal_mode 0)
		)
		(polygon
			(pts
				(arc
					(start 78.505558 -70.508368)
					(mid 78.122018 -70.124828)
					(end 77.738478 -70.508368)
				)
				(arc
					(start 77.738478 -71.397114)
					(mid 78.121891 -71.780908)
					(end 78.505558 -71.397368)
				)
			)
		)
	)
	(zone
		(layers "In1.Cu" "In3.Cu" "In4.Cu" "In6.Cu")
		(hatch none 0.5)
		(connect_pads
			(clearance 0)
		)
		(min_thickness 0.25)
		(keepout
			(tracks not_allowed)
			(vias allowed)
			(pads allowed)
			(copperpour not_allowed)
			(footprints allowed)
		)
		(placement
			(enabled no)
			(sheetname "")
		)
		(fill yes
			(thermal_gap 0.5)
			(thermal_bridge_width 0.5)
			(island_removal_mode 0)
		)
		(polygon
			(pts
				(arc
					(start 178.833526 -18.877026)
					(mid 179.027074 -19.516598)
					(end 179.666646 -19.32305)
				)
				(arc
					(start 180.413406 -17.92859)
					(mid 180.225704 -17.284948)
					(end 179.583334 -17.476978)
				)
			)
		)
	)
	(zone
		(layers "In1.Cu" "In3.Cu" "In4.Cu" "In6.Cu")
		(hatch none 0.5)
		(connect_pads
			(clearance 0)
		)
		(min_thickness 0.25)
		(keepout
			(tracks not_allowed)
			(vias allowed)
			(pads allowed)
			(copperpour not_allowed)
			(footprints allowed)
		)
		(placement
			(enabled no)
			(sheetname "")
		)
		(fill yes
			(thermal_gap 0.5)
			(thermal_bridge_width 0.5)
			(island_removal_mode 0)
		)
		(polygon
			(pts
				(arc
					(start 109.3851 -35.600386)
					(mid 108.900087 -35.114992)
					(end 108.41482 -35.600132)
				)
				(arc
					(start 108.41482 -37.00018)
					(mid 108.89996 -37.48532)
					(end 109.3851 -37.00018)
				)
			)
		)
	)
	(zone
		(layers "In1.Cu" "In3.Cu" "In4.Cu" "In6.Cu")
		(hatch none 0.5)
		(connect_pads
			(clearance 0)
		)
		(min_thickness 0.25)
		(keepout
			(tracks not_allowed)
			(vias allowed)
			(pads allowed)
			(copperpour not_allowed)
			(footprints allowed)
		)
		(placement
			(enabled no)
			(sheetname "")
		)
		(fill yes
			(thermal_gap 0.5)
			(thermal_bridge_width 0.5)
			(island_removal_mode 0)
		)
		(polygon
			(pts
				(arc
					(start 161.083498 -30.277054)
					(mid 161.277046 -30.916626)
					(end 161.916618 -30.723078)
				)
				(arc
					(start 162.663632 -29.328618)
					(mid 162.47593 -28.684976)
					(end 161.83356 -28.877006)
				)
			)
		)
	)
	(zone
		(layers "In1.Cu" "In3.Cu" "In4.Cu" "In6.Cu")
		(hatch none 0.5)
		(connect_pads
			(clearance 0)
		)
		(min_thickness 0.25)
		(keepout
			(tracks not_allowed)
			(vias allowed)
			(pads allowed)
			(copperpour not_allowed)
			(footprints allowed)
		)
		(placement
			(enabled no)
			(sheetname "")
		)
		(fill yes
			(thermal_gap 0.5)
			(thermal_bridge_width 0.5)
			(island_removal_mode 0)
		)
		(polygon
			(pts
				(arc
					(start 78.505558 -89.710768)
					(mid 78.122018 -89.327228)
					(end 77.738478 -89.710768)
				)
				(arc
					(start 77.738478 -90.599514)
					(mid 78.121891 -90.983308)
					(end 78.505558 -90.599768)
				)
			)
		)
	)
	(zone
		(layers "In1.Cu" "In3.Cu" "In4.Cu" "In6.Cu")
		(hatch none 0.5)
		(connect_pads
			(clearance 0)
		)
		(min_thickness 0.25)
		(keepout
			(tracks not_allowed)
			(vias allowed)
			(pads allowed)
			(copperpour not_allowed)
			(footprints allowed)
		)
		(placement
			(enabled no)
			(sheetname "")
		)
		(fill yes
			(thermal_gap 0.5)
			(thermal_bridge_width 0.5)
			(island_removal_mode 0)
		)
		(polygon
			(pts
				(arc
					(start 78.505558 -76.909168)
					(mid 78.122018 -76.525628)
					(end 77.738478 -76.909168)
				)
				(arc
					(start 77.738478 -77.797914)
					(mid 78.121891 -78.181708)
					(end 78.505558 -77.798168)
				)
			)
		)
	)
	(zone
		(layers "In1.Cu" "In3.Cu" "In4.Cu" "In6.Cu")
		(hatch none 0.5)
		(connect_pads
			(clearance 0)
		)
		(min_thickness 0.25)
		(keepout
			(tracks not_allowed)
			(vias allowed)
			(pads allowed)
			(copperpour not_allowed)
			(footprints allowed)
		)
		(placement
			(enabled no)
			(sheetname "")
		)
		(fill yes
			(thermal_gap 0.5)
			(thermal_bridge_width 0.5)
			(island_removal_mode 0)
		)
		(polygon
			(pts
				(arc
					(start 85.367368 -72.08139)
					(mid 84.983955 -71.697596)
					(end 84.600288 -72.081136)
				)
				(arc
					(start 84.600288 -72.970136)
					(mid 84.983828 -73.353676)
					(end 85.367368 -72.970136)
				)
			)
		)
	)
	(zone
		(layers "In1.Cu" "In3.Cu" "In4.Cu" "In6.Cu")
		(hatch none 0.5)
		(connect_pads
			(clearance 0)
		)
		(min_thickness 0.25)
		(keepout
			(tracks not_allowed)
			(vias allowed)
			(pads allowed)
			(copperpour not_allowed)
			(footprints allowed)
		)
		(placement
			(enabled no)
			(sheetname "")
		)
		(fill yes
			(thermal_gap 0.5)
			(thermal_bridge_width 0.5)
			(island_removal_mode 0)
		)
		(polygon
			(pts
				(arc
					(start 83.741768 -81.705196)
					(mid 83.358228 -81.321656)
					(end 82.974688 -81.705196)
				)
				(arc
					(start 82.974688 -82.593942)
					(mid 83.358101 -82.977736)
					(end 83.741768 -82.594196)
				)
			)
		)
	)
	(zone
		(layers "In1.Cu" "In3.Cu" "In4.Cu" "In6.Cu")
		(hatch none 0.5)
		(connect_pads
			(clearance 0)
		)
		(min_thickness 0.25)
		(keepout
			(tracks not_allowed)
			(vias allowed)
			(pads allowed)
			(copperpour not_allowed)
			(footprints allowed)
		)
		(placement
			(enabled no)
			(sheetname "")
		)
		(fill yes
			(thermal_gap 0.5)
			(thermal_bridge_width 0.5)
			(island_removal_mode 0)
		)
		(polygon
			(pts
				(arc
					(start 77.667358 -86.510368)
					(mid 77.283818 -86.126828)
					(end 76.900278 -86.510368)
				)
				(arc
					(start 76.900278 -87.399114)
					(mid 77.283691 -87.782908)
					(end 77.667358 -87.399368)
				)
			)
		)
	)
	(zone
		(layers "In1.Cu" "In3.Cu" "In4.Cu" "In6.Cu")
		(hatch none 0.5)
		(connect_pads
			(clearance 0)
		)
		(min_thickness 0.25)
		(keepout
			(tracks not_allowed)
			(vias allowed)
			(pads allowed)
			(copperpour not_allowed)
			(footprints allowed)
		)
		(placement
			(enabled no)
			(sheetname "")
		)
		(fill yes
			(thermal_gap 0.5)
			(thermal_bridge_width 0.5)
			(island_removal_mode 0)
		)
		(polygon
			(pts
				(arc
					(start 114.78514 -33.20034)
					(mid 114.300127 -32.714946)
					(end 113.81486 -33.200086)
				)
				(arc
					(start 113.81486 -34.600134)
					(mid 114.3 -35.085274)
					(end 114.78514 -34.600134)
				)
			)
		)
	)
	(zone
		(layers "In1.Cu" "In3.Cu" "In4.Cu" "In6.Cu")
		(hatch none 0.5)
		(connect_pads
			(clearance 0)
		)
		(min_thickness 0.25)
		(keepout
			(tracks not_allowed)
			(vias allowed)
			(pads allowed)
			(copperpour not_allowed)
			(footprints allowed)
		)
		(placement
			(enabled no)
			(sheetname "")
		)
		(fill yes
			(thermal_gap 0.5)
			(thermal_bridge_width 0.5)
			(island_removal_mode 0)
		)
		(polygon
			(pts
				(xy 215.76538 -79.921608) (xy 216.573354 -79.11338)
				(arc
					(start 216.573354 -79.113126)
					(mid 216.573354 -78.574646)
					(end 216.034874 -78.574646)
				)
				(xy 216.03462 -78.574392) (xy 215.226392 -79.38262)
				(arc
					(start 215.226646 -79.382874)
					(mid 215.226646 -79.921354)
					(end 215.765126 -79.921354)
				)
			)
		)
	)
	(zone
		(layers "In1.Cu" "In3.Cu" "In4.Cu" "In6.Cu")
		(hatch none 0.5)
		(connect_pads
			(clearance 0)
		)
		(min_thickness 0.25)
		(keepout
			(tracks not_allowed)
			(vias allowed)
			(pads allowed)
			(copperpour not_allowed)
			(footprints allowed)
		)
		(placement
			(enabled no)
			(sheetname "")
		)
		(fill yes
			(thermal_gap 0.5)
			(thermal_bridge_width 0.5)
			(island_removal_mode 0)
		)
		(polygon
			(pts
				(arc
					(start 107.585002 -36.800282)
					(mid 107.099989 -36.314888)
					(end 106.614722 -36.800028)
				)
				(arc
					(start 106.614722 -38.200076)
					(mid 107.099862 -38.685216)
					(end 107.585002 -38.200076)
				)
			)
		)
	)
	(zone
		(layers "In1.Cu" "In3.Cu" "In4.Cu" "In6.Cu")
		(hatch none 0.5)
		(connect_pads
			(clearance 0)
		)
		(min_thickness 0.25)
		(keepout
			(tracks not_allowed)
			(vias allowed)
			(pads allowed)
			(copperpour not_allowed)
			(footprints allowed)
		)
		(placement
			(enabled no)
			(sheetname "")
		)
		(fill yes
			(thermal_gap 0.5)
			(thermal_bridge_width 0.5)
			(island_removal_mode 0)
		)
		(polygon
			(pts
				(xy 161.91865 -23.12416) (xy 162.668712 -21.72462) (xy 162.668458 -21.724366)
				(arc
					(start 162.666426 -21.72335)
					(mid 162.473287 -21.083725)
					(end 161.833814 -21.277072)
				)
				(xy 161.831528 -21.275802) (xy 161.081466 -22.675596)
				(arc
					(start 161.083752 -22.676866)
					(mid 161.277046 -23.316184)
					(end 161.916364 -23.12289)
				)
			)
		)
	)
	(zone
		(layers "In1.Cu" "In3.Cu" "In4.Cu" "In6.Cu")
		(hatch none 0.5)
		(connect_pads
			(clearance 0)
		)
		(min_thickness 0.25)
		(keepout
			(tracks not_allowed)
			(vias allowed)
			(pads allowed)
			(copperpour not_allowed)
			(footprints allowed)
		)
		(placement
			(enabled no)
			(sheetname "")
		)
		(fill yes
			(thermal_gap 0.5)
			(thermal_bridge_width 0.5)
			(island_removal_mode 0)
		)
		(polygon
			(pts
				(arc
					(start 118.385082 -36.800282)
					(mid 117.900069 -36.314888)
					(end 117.414802 -36.800028)
				)
				(arc
					(start 117.414802 -38.200076)
					(mid 117.899942 -38.685216)
					(end 118.385082 -38.200076)
				)
			)
		)
	)
	(zone
		(layers "In1.Cu" "In3.Cu" "In4.Cu" "In6.Cu")
		(hatch none 0.5)
		(connect_pads
			(clearance 0)
		)
		(min_thickness 0.25)
		(keepout
			(tracks not_allowed)
			(vias allowed)
			(pads allowed)
			(copperpour not_allowed)
			(footprints allowed)
		)
		(placement
			(enabled no)
			(sheetname "")
		)
		(fill yes
			(thermal_gap 0.5)
			(thermal_bridge_width 0.5)
			(island_removal_mode 0)
		)
		(polygon
			(pts
				(arc
					(start 191.998092 -86.950296)
					(mid 191.998092 -86.411308)
					(end 191.459104 -86.411308)
				)
				(arc
					(start 190.835534 -87.035132)
					(mid 190.828455 -87.576246)
					(end 191.369696 -87.578692)
				)
			)
		)
	)
	(zone
		(layers "In1.Cu" "In3.Cu" "In4.Cu" "In6.Cu")
		(hatch none 0.5)
		(connect_pads
			(clearance 0)
		)
		(min_thickness 0.25)
		(keepout
			(tracks not_allowed)
			(vias allowed)
			(pads allowed)
			(copperpour not_allowed)
			(footprints allowed)
		)
		(placement
			(enabled no)
			(sheetname "")
		)
		(fill yes
			(thermal_gap 0.5)
			(thermal_bridge_width 0.5)
			(island_removal_mode 0)
		)
		(polygon
			(pts
				(arc
					(start 130.985006 -35.600386)
					(mid 130.499993 -35.114992)
					(end 130.014726 -35.600132)
				)
				(arc
					(start 130.014726 -37.00018)
					(mid 130.499866 -37.48532)
					(end 130.985006 -37.00018)
				)
			)
		)
	)
	(zone
		(layers "In1.Cu" "In3.Cu" "In4.Cu" "In6.Cu")
		(hatch none 0.5)
		(connect_pads
			(clearance 0)
		)
		(min_thickness 0.25)
		(keepout
			(tracks not_allowed)
			(vias allowed)
			(pads allowed)
			(copperpour not_allowed)
			(footprints allowed)
		)
		(placement
			(enabled no)
			(sheetname "")
		)
		(fill yes
			(thermal_gap 0.5)
			(thermal_bridge_width 0.5)
			(island_removal_mode 0)
		)
		(polygon
			(pts
				(arc
					(start 136.385046 -36.800282)
					(mid 135.900033 -36.314888)
					(end 135.414766 -36.800028)
				)
				(arc
					(start 135.414766 -38.200076)
					(mid 135.899906 -38.685216)
					(end 136.385046 -38.200076)
				)
			)
		)
	)
	(zone
		(layers "In1.Cu" "In3.Cu" "In4.Cu" "In6.Cu")
		(hatch none 0.5)
		(connect_pads
			(clearance 0)
		)
		(min_thickness 0.25)
		(keepout
			(tracks not_allowed)
			(vias allowed)
			(pads allowed)
			(copperpour not_allowed)
			(footprints allowed)
		)
		(placement
			(enabled no)
			(sheetname "")
		)
		(fill yes
			(thermal_gap 0.5)
			(thermal_bridge_width 0.5)
			(island_removal_mode 0)
		)
		(polygon
			(pts
				(arc
					(start 77.667358 -92.911168)
					(mid 77.283818 -92.527628)
					(end 76.900278 -92.911168)
				)
				(arc
					(start 76.900278 -93.799914)
					(mid 77.283691 -94.183708)
					(end 77.667358 -93.800168)
				)
			)
		)
	)
	(zone
		(layers "In1.Cu" "In3.Cu" "In4.Cu" "In6.Cu")
		(hatch none 0.5)
		(connect_pads
			(clearance 0)
		)
		(min_thickness 0.25)
		(keepout
			(tracks not_allowed)
			(vias allowed)
			(pads allowed)
			(copperpour not_allowed)
			(footprints allowed)
		)
		(placement
			(enabled no)
			(sheetname "")
		)
		(fill yes
			(thermal_gap 0.5)
			(thermal_bridge_width 0.5)
			(island_removal_mode 0)
		)
		(polygon
			(pts
				(xy 181.91861 -23.12416) (xy 182.668672 -21.72462) (xy 182.668418 -21.724366)
				(arc
					(start 182.666386 -21.72335)
					(mid 182.473247 -21.083725)
					(end 181.833774 -21.277072)
				)
				(xy 181.831488 -21.275802) (xy 181.081426 -22.675596)
				(arc
					(start 181.083712 -22.676866)
					(mid 181.277006 -23.316184)
					(end 181.916324 -23.12289)
				)
			)
		)
	)
	(zone
		(layers "In1.Cu" "In3.Cu" "In4.Cu" "In6.Cu")
		(hatch none 0.5)
		(connect_pads
			(clearance 0)
		)
		(min_thickness 0.25)
		(keepout
			(tracks not_allowed)
			(vias allowed)
			(pads allowed)
			(copperpour not_allowed)
			(footprints allowed)
		)
		(placement
			(enabled no)
			(sheetname "")
		)
		(fill yes
			(thermal_gap 0.5)
			(thermal_bridge_width 0.5)
			(island_removal_mode 0)
		)
		(polygon
			(pts
				(arc
					(start 109.3851 -32.000444)
					(mid 108.900087 -31.51505)
					(end 108.41482 -32.00019)
				)
				(arc
					(start 108.41482 -33.399984)
					(mid 108.89996 -33.885124)
					(end 109.3851 -33.399984)
				)
			)
		)
	)
	(zone
		(layers "In1.Cu" "In3.Cu" "In4.Cu" "In6.Cu")
		(hatch none 0.5)
		(connect_pads
			(clearance 0)
		)
		(min_thickness 0.25)
		(keepout
			(tracks not_allowed)
			(vias allowed)
			(pads allowed)
			(copperpour not_allowed)
			(footprints allowed)
		)
		(placement
			(enabled no)
			(sheetname "")
		)
		(fill yes
			(thermal_gap 0.5)
			(thermal_bridge_width 0.5)
			(island_removal_mode 0)
		)
		(polygon
			(pts
				(arc
					(start 85.367368 -91.306396)
					(mid 84.983828 -90.922856)
					(end 84.600288 -91.306396)
				)
				(arc
					(start 84.600288 -92.195142)
					(mid 84.983701 -92.578936)
					(end 85.367368 -92.195396)
				)
			)
		)
	)
	(zone
		(layers "In1.Cu" "In3.Cu" "In4.Cu" "In6.Cu")
		(hatch none 0.5)
		(connect_pads
			(clearance 0)
		)
		(min_thickness 0.25)
		(keepout
			(tracks not_allowed)
			(vias allowed)
			(pads allowed)
			(copperpour not_allowed)
			(footprints allowed)
		)
		(placement
			(enabled no)
			(sheetname "")
		)
		(fill yes
			(thermal_gap 0.5)
			(thermal_bridge_width 0.5)
			(island_removal_mode 0)
		)
		(polygon
			(pts
				(arc
					(start 111.185198 -36.800282)
					(mid 110.700185 -36.314888)
					(end 110.214918 -36.800028)
				)
				(arc
					(start 110.214918 -38.200076)
					(mid 110.700058 -38.685216)
					(end 111.185198 -38.200076)
				)
			)
		)
	)
	(zone
		(layers "In1.Cu" "In3.Cu" "In4.Cu" "In6.Cu")
		(hatch none 0.5)
		(connect_pads
			(clearance 0)
		)
		(min_thickness 0.25)
		(keepout
			(tracks not_allowed)
			(vias allowed)
			(pads allowed)
			(copperpour not_allowed)
			(footprints allowed)
		)
		(placement
			(enabled no)
			(sheetname "")
		)
		(fill yes
			(thermal_gap 0.5)
			(thermal_bridge_width 0.5)
			(island_removal_mode 0)
		)
		(polygon
			(pts
				(arc
					(start 120.18518 -35.600386)
					(mid 119.700167 -35.114992)
					(end 119.2149 -35.600132)
				)
				(arc
					(start 119.2149 -37.00018)
					(mid 119.70004 -37.48532)
					(end 120.18518 -37.00018)
				)
			)
		)
	)
	(zone
		(layers "In1.Cu" "In3.Cu" "In4.Cu" "In6.Cu")
		(hatch none 0.5)
		(connect_pads
			(clearance 0)
		)
		(min_thickness 0.25)
		(keepout
			(tracks not_allowed)
			(vias allowed)
			(pads allowed)
			(copperpour not_allowed)
			(footprints allowed)
		)
		(placement
			(enabled no)
			(sheetname "")
		)
		(fill yes
			(thermal_gap 0.5)
			(thermal_bridge_width 0.5)
			(island_removal_mode 0)
		)
		(polygon
			(pts
				(arc
					(start 116.584984 -35.600386)
					(mid 116.099971 -35.114992)
					(end 115.614704 -35.600132)
				)
				(arc
					(start 115.614704 -37.00018)
					(mid 116.099844 -37.48532)
					(end 116.584984 -37.00018)
				)
			)
		)
	)
	(zone
		(layers "In1.Cu" "In3.Cu" "In4.Cu" "In6.Cu")
		(hatch none 0.5)
		(connect_pads
			(clearance 0)
		)
		(min_thickness 0.25)
		(keepout
			(tracks not_allowed)
			(vias allowed)
			(pads allowed)
			(copperpour not_allowed)
			(footprints allowed)
		)
		(placement
			(enabled no)
			(sheetname "")
		)
		(fill yes
			(thermal_gap 0.5)
			(thermal_bridge_width 0.5)
			(island_removal_mode 0)
		)
		(polygon
			(pts
				(arc
					(start 83.741768 -94.492572)
					(mid 83.358228 -94.109032)
					(end 82.974688 -94.492572)
				)
				(arc
					(start 82.974688 -95.381318)
					(mid 83.358101 -95.765112)
					(end 83.741768 -95.381572)
				)
			)
		)
	)
	(zone
		(layers "In1.Cu" "In3.Cu" "In4.Cu" "In6.Cu")
		(hatch none 0.5)
		(connect_pads
			(clearance 0)
		)
		(min_thickness 0.25)
		(keepout
			(tracks not_allowed)
			(vias allowed)
			(pads allowed)
			(copperpour not_allowed)
			(footprints allowed)
		)
		(placement
			(enabled no)
			(sheetname "")
		)
		(fill yes
			(thermal_gap 0.5)
			(thermal_bridge_width 0.5)
			(island_removal_mode 0)
		)
		(polygon
			(pts
				(arc
					(start 181.083458 -30.277054)
					(mid 181.277006 -30.916626)
					(end 181.916578 -30.723078)
				)
				(arc
					(start 182.663592 -29.328618)
					(mid 182.47589 -28.684976)
					(end 181.83352 -28.877006)
				)
			)
		)
	)
	(zone
		(layers "In1.Cu" "In3.Cu" "In4.Cu" "In6.Cu")
		(hatch none 0.5)
		(connect_pads
			(clearance 0)
		)
		(min_thickness 0.25)
		(keepout
			(tracks not_allowed)
			(vias allowed)
			(pads allowed)
			(copperpour not_allowed)
			(footprints allowed)
		)
		(placement
			(enabled no)
			(sheetname "")
		)
		(fill yes
			(thermal_gap 0.5)
			(thermal_bridge_width 0.5)
			(island_removal_mode 0)
		)
		(polygon
			(pts
				(arc
					(start 158.833566 -26.47696)
					(mid 159.027114 -27.116532)
					(end 159.666686 -26.922984)
				)
				(arc
					(start 160.413446 -25.528524)
					(mid 160.225744 -24.884882)
					(end 159.583374 -25.076912)
				)
			)
		)
	)
	(zone
		(layers "In1.Cu" "In3.Cu" "In4.Cu" "In6.Cu")
		(hatch none 0.5)
		(connect_pads
			(clearance 0)
		)
		(min_thickness 0.25)
		(keepout
			(tracks not_allowed)
			(vias allowed)
			(pads allowed)
			(copperpour not_allowed)
			(footprints allowed)
		)
		(placement
			(enabled no)
			(sheetname "")
		)
		(fill yes
			(thermal_gap 0.5)
			(thermal_bridge_width 0.5)
			(island_removal_mode 0)
		)
		(polygon
			(pts
				(arc
					(start 130.985006 -32.000444)
					(mid 130.499993 -31.51505)
					(end 130.014726 -32.00019)
				)
				(arc
					(start 130.014726 -33.399984)
					(mid 130.499866 -33.885124)
					(end 130.985006 -33.399984)
				)
			)
		)
	)
	(zone
		(layers "In1.Cu" "In3.Cu" "In4.Cu" "In6.Cu")
		(hatch none 0.5)
		(connect_pads
			(clearance 0)
		)
		(min_thickness 0.25)
		(keepout
			(tracks not_allowed)
			(vias allowed)
			(pads allowed)
			(copperpour not_allowed)
			(footprints allowed)
		)
		(placement
			(enabled no)
			(sheetname "")
		)
		(fill yes
			(thermal_gap 0.5)
			(thermal_bridge_width 0.5)
			(island_removal_mode 0)
		)
		(polygon
			(pts
				(xy 216.90838 -75.984608) (xy 217.716354 -75.17638)
				(arc
					(start 217.716354 -75.176126)
					(mid 217.716354 -74.637646)
					(end 217.177874 -74.637646)
				)
				(xy 217.17762 -74.637392) (xy 216.369392 -75.44562)
				(arc
					(start 216.369646 -75.445874)
					(mid 216.369646 -75.984354)
					(end 216.908126 -75.984354)
				)
			)
		)
	)
	(zone
		(layers "In1.Cu" "In3.Cu" "In4.Cu" "In6.Cu")
		(hatch none 0.5)
		(connect_pads
			(clearance 0)
		)
		(min_thickness 0.25)
		(keepout
			(tracks not_allowed)
			(vias allowed)
			(pads allowed)
			(copperpour not_allowed)
			(footprints allowed)
		)
		(placement
			(enabled no)
			(sheetname "")
		)
		(fill yes
			(thermal_gap 0.5)
			(thermal_bridge_width 0.5)
			(island_removal_mode 0)
		)
		(polygon
			(pts
				(arc
					(start 199.084692 -88.728296)
					(mid 199.084692 -88.189308)
					(end 198.545704 -88.189308)
				)
				(arc
					(start 197.922134 -88.813132)
					(mid 197.915055 -89.354246)
					(end 198.456296 -89.356692)
				)
			)
		)
	)
	(zone
		(layers "In1.Cu" "In3.Cu" "In4.Cu" "In6.Cu")
		(hatch none 0.5)
		(connect_pads
			(clearance 0)
		)
		(min_thickness 0.25)
		(keepout
			(tracks not_allowed)
			(vias allowed)
			(pads allowed)
			(copperpour not_allowed)
			(footprints allowed)
		)
		(placement
			(enabled no)
			(sheetname "")
		)
		(fill yes
			(thermal_gap 0.5)
			(thermal_bridge_width 0.5)
			(island_removal_mode 0)
		)
		(polygon
			(pts
				(arc
					(start 83.741768 -88.105488)
					(mid 83.358355 -87.721694)
					(end 82.974688 -88.105234)
				)
				(arc
					(start 82.974688 -88.994234)
					(mid 83.358228 -89.377774)
					(end 83.741768 -88.994234)
				)
			)
		)
	)
	(zone
		(layers "In1.Cu" "In3.Cu" "In4.Cu" "In6.Cu")
		(hatch none 0.5)
		(connect_pads
			(clearance 0)
		)
		(min_thickness 0.25)
		(keepout
			(tracks not_allowed)
			(vias allowed)
			(pads allowed)
			(copperpour not_allowed)
			(footprints allowed)
		)
		(placement
			(enabled no)
			(sheetname "")
		)
		(fill yes
			(thermal_gap 0.5)
			(thermal_bridge_width 0.5)
			(island_removal_mode 0)
		)
		(polygon
			(pts
				(xy 215.38438 -74.460608) (xy 216.192354 -73.65238)
				(arc
					(start 216.192354 -73.652126)
					(mid 216.192354 -73.113646)
					(end 215.653874 -73.113646)
				)
				(xy 215.65362 -73.113392) (xy 214.845392 -73.92162)
				(arc
					(start 214.845646 -73.921874)
					(mid 214.845646 -74.460354)
					(end 215.384126 -74.460354)
				)
			)
		)
	)
	(zone
		(layers "In1.Cu" "In3.Cu" "In4.Cu" "In6.Cu")
		(hatch none 0.5)
		(connect_pads
			(clearance 0)
		)
		(min_thickness 0.25)
		(keepout
			(tracks not_allowed)
			(vias allowed)
			(pads allowed)
			(copperpour not_allowed)
			(footprints allowed)
		)
		(placement
			(enabled no)
			(sheetname "")
		)
		(fill yes
			(thermal_gap 0.5)
			(thermal_bridge_width 0.5)
			(island_removal_mode 0)
		)
		(polygon
			(pts
				(arc
					(start 139.984988 -33.20034)
					(mid 139.499975 -32.714946)
					(end 139.014708 -33.200086)
				)
				(arc
					(start 139.014708 -34.600134)
					(mid 139.499848 -35.085274)
					(end 139.984988 -34.600134)
				)
			)
		)
	)
	(zone
		(layers "In1.Cu" "In3.Cu" "In4.Cu" "In6.Cu")
		(hatch none 0.5)
		(connect_pads
			(clearance 0)
		)
		(min_thickness 0.25)
		(keepout
			(tracks not_allowed)
			(vias allowed)
			(pads allowed)
			(copperpour not_allowed)
			(footprints allowed)
		)
		(placement
			(enabled no)
			(sheetname "")
		)
		(fill yes
			(thermal_gap 0.5)
			(thermal_bridge_width 0.5)
			(island_removal_mode 0)
		)
		(polygon
			(pts
				(arc
					(start 158.833566 -30.277054)
					(mid 159.027114 -30.916626)
					(end 159.666686 -30.723078)
				)
				(arc
					(start 160.413446 -29.328618)
					(mid 160.225744 -28.684976)
					(end 159.583374 -28.877006)
				)
			)
		)
	)
	(zone
		(layers "In1.Cu" "In3.Cu" "In4.Cu" "In6.Cu")
		(hatch none 0.5)
		(connect_pads
			(clearance 0)
		)
		(min_thickness 0.25)
		(keepout
			(tracks not_allowed)
			(vias allowed)
			(pads allowed)
			(copperpour not_allowed)
			(footprints allowed)
		)
		(placement
			(enabled no)
			(sheetname "")
		)
		(fill yes
			(thermal_gap 0.5)
			(thermal_bridge_width 0.5)
			(island_removal_mode 0)
		)
		(polygon
			(pts
				(xy 213.98738 -73.063608) (xy 214.795354 -72.25538)
				(arc
					(start 214.795354 -72.255126)
					(mid 214.795354 -71.716646)
					(end 214.256874 -71.716646)
				)
				(xy 214.25662 -71.716392) (xy 213.448392 -72.52462)
				(arc
					(start 213.448646 -72.524874)
					(mid 213.448646 -73.063354)
					(end 213.987126 -73.063354)
				)
			)
		)
	)
	(zone
		(layers "In1.Cu" "In3.Cu" "In4.Cu" "In6.Cu")
		(hatch none 0.5)
		(connect_pads
			(clearance 0)
		)
		(min_thickness 0.25)
		(keepout
			(tracks not_allowed)
			(vias allowed)
			(pads allowed)
			(copperpour not_allowed)
			(footprints allowed)
		)
		(placement
			(enabled no)
			(sheetname "")
		)
		(fill yes
			(thermal_gap 0.5)
			(thermal_bridge_width 0.5)
			(island_removal_mode 0)
		)
		(polygon
			(pts
				(arc
					(start 120.18518 -32.000444)
					(mid 119.700167 -31.51505)
					(end 119.2149 -32.00019)
				)
				(arc
					(start 119.2149 -33.399984)
					(mid 119.70004 -33.885124)
					(end 120.18518 -33.399984)
				)
			)
		)
	)
	(zone
		(layers "In1.Cu" "In3.Cu" "In4.Cu" "In6.Cu")
		(hatch none 0.5)
		(connect_pads
			(clearance 0)
		)
		(min_thickness 0.25)
		(keepout
			(tracks not_allowed)
			(vias allowed)
			(pads allowed)
			(copperpour not_allowed)
			(footprints allowed)
		)
		(placement
			(enabled no)
			(sheetname "")
		)
		(fill yes
			(thermal_gap 0.5)
			(thermal_bridge_width 0.5)
			(island_removal_mode 0)
		)
		(polygon
			(pts
				(arc
					(start 202.107292 -85.731096)
					(mid 202.107292 -85.192108)
					(end 201.568304 -85.192108)
				)
				(arc
					(start 200.944734 -85.815932)
					(mid 200.937655 -86.357046)
					(end 201.478896 -86.359492)
				)
			)
		)
	)
	(zone
		(layers "In1.Cu" "In3.Cu" "In4.Cu" "In6.Cu")
		(hatch none 0.5)
		(connect_pads
			(clearance 0)
		)
		(min_thickness 0.25)
		(keepout
			(tracks not_allowed)
			(vias allowed)
			(pads allowed)
			(copperpour not_allowed)
			(footprints allowed)
		)
		(placement
			(enabled no)
			(sheetname "")
		)
		(fill yes
			(thermal_gap 0.5)
			(thermal_bridge_width 0.5)
			(island_removal_mode 0)
		)
		(polygon
			(pts
				(arc
					(start 141.785086 -32.000444)
					(mid 141.300073 -31.51505)
					(end 140.814806 -32.00019)
				)
				(arc
					(start 140.814806 -33.399984)
					(mid 141.299946 -33.885124)
					(end 141.785086 -33.399984)
				)
			)
		)
	)
	(zone
		(layers "In1.Cu" "In3.Cu" "In4.Cu" "In6.Cu")
		(hatch none 0.5)
		(connect_pads
			(clearance 0)
		)
		(min_thickness 0.25)
		(keepout
			(tracks not_allowed)
			(vias allowed)
			(pads allowed)
			(copperpour not_allowed)
			(footprints allowed)
		)
		(placement
			(enabled no)
			(sheetname "")
		)
		(fill yes
			(thermal_gap 0.5)
			(thermal_bridge_width 0.5)
			(island_removal_mode 0)
		)
		(polygon
			(pts
				(arc
					(start 77.667358 -80.109568)
					(mid 77.283818 -79.726028)
					(end 76.900278 -80.109568)
				)
				(arc
					(start 76.900278 -80.998314)
					(mid 77.283691 -81.382108)
					(end 77.667358 -80.998568)
				)
			)
		)
	)
	(zone
		(layers "In1.Cu" "In3.Cu" "In4.Cu" "In6.Cu")
		(hatch none 0.5)
		(connect_pads
			(clearance 0)
		)
		(min_thickness 0.25)
		(keepout
			(tracks not_allowed)
			(vias allowed)
			(pads allowed)
			(copperpour not_allowed)
			(footprints allowed)
		)
		(placement
			(enabled no)
			(sheetname "")
		)
		(fill yes
			(thermal_gap 0.5)
			(thermal_bridge_width 0.5)
			(island_removal_mode 0)
		)
		(polygon
			(pts
				(arc
					(start 132.785104 -33.20034)
					(mid 132.300091 -32.714946)
					(end 131.814824 -33.200086)
				)
				(arc
					(start 131.814824 -34.600134)
					(mid 132.299964 -35.085274)
					(end 132.785104 -34.600134)
				)
			)
		)
	)
	(zone
		(layers "In1.Cu" "In3.Cu" "In4.Cu" "In6.Cu")
		(hatch none 0.5)
		(connect_pads
			(clearance 0)
		)
		(min_thickness 0.25)
		(keepout
			(tracks not_allowed)
			(vias allowed)
			(pads allowed)
			(copperpour not_allowed)
			(footprints allowed)
		)
		(placement
			(enabled no)
			(sheetname "")
		)
		(fill yes
			(thermal_gap 0.5)
			(thermal_bridge_width 0.5)
			(island_removal_mode 0)
		)
		(polygon
			(pts
				(arc
					(start 136.385046 -33.20034)
					(mid 135.900033 -32.714946)
					(end 135.414766 -33.200086)
				)
				(arc
					(start 135.414766 -34.600134)
					(mid 135.899906 -35.085274)
					(end 136.385046 -34.600134)
				)
			)
		)
	)
	(zone
		(layers "In1.Cu" "In3.Cu" "In4.Cu" "In6.Cu")
		(hatch none 0.5)
		(connect_pads
			(clearance 0)
		)
		(min_thickness 0.25)
		(keepout
			(tracks not_allowed)
			(vias allowed)
			(pads allowed)
			(copperpour not_allowed)
			(footprints allowed)
		)
		(placement
			(enabled no)
			(sheetname "")
		)
		(fill yes
			(thermal_gap 0.5)
			(thermal_bridge_width 0.5)
			(island_removal_mode 0)
		)
		(polygon
			(pts
				(xy 214.49538 -69.761608) (xy 215.303354 -68.95338)
				(arc
					(start 215.303354 -68.953126)
					(mid 215.303354 -68.414646)
					(end 214.764874 -68.414646)
				)
				(xy 214.76462 -68.414392) (xy 213.956392 -69.22262)
				(arc
					(start 213.956646 -69.222874)
					(mid 213.956646 -69.761354)
					(end 214.495126 -69.761354)
				)
			)
		)
	)
	(zone
		(layers "In1.Cu" "In3.Cu" "In4.Cu" "In6.Cu")
		(hatch none 0.5)
		(connect_pads
			(clearance 0)
		)
		(min_thickness 0.25)
		(keepout
			(tracks not_allowed)
			(vias allowed)
			(pads allowed)
			(copperpour not_allowed)
			(footprints allowed)
		)
		(placement
			(enabled no)
			(sheetname "")
		)
		(fill yes
			(thermal_gap 0.5)
			(thermal_bridge_width 0.5)
			(island_removal_mode 0)
		)
		(polygon
			(pts
				(arc
					(start 194.720464 -88.652096)
					(mid 194.720464 -88.113108)
					(end 194.181476 -88.113108)
				)
				(arc
					(start 193.557906 -88.736932)
					(mid 193.550827 -89.278046)
					(end 194.092068 -89.280492)
				)
			)
		)
	)
	(zone
		(layers "In1.Cu" "In6.Cu")
		(hatch none 0.5)
		(connect_pads
			(clearance 0)
		)
		(min_thickness 0.25)
		(keepout
			(tracks not_allowed)
			(vias allowed)
			(pads allowed)
			(copperpour not_allowed)
			(footprints allowed)
		)
		(placement
			(enabled no)
			(sheetname "")
		)
		(fill yes
			(thermal_gap 0.5)
			(thermal_bridge_width 0.5)
			(island_removal_mode 0)
		)
		(polygon
			(pts
				(arc
					(start 227.26904 -187.999878)
					(mid 217.73134 -187.999878)
					(end 227.26904 -187.999878)
				)
			)
		)
	)
	(zone
		(layers "In1.Cu" "In6.Cu")
		(hatch none 0.5)
		(connect_pads
			(clearance 0)
		)
		(min_thickness 0.25)
		(keepout
			(tracks not_allowed)
			(vias allowed)
			(pads allowed)
			(copperpour not_allowed)
			(footprints allowed)
		)
		(placement
			(enabled no)
			(sheetname "")
		)
		(fill yes
			(thermal_gap 0.5)
			(thermal_bridge_width 0.5)
			(island_removal_mode 0)
		)
		(polygon
			(pts
				(arc
					(start 160.26892 -187.999878)
					(mid 150.73122 -187.999878)
					(end 160.26892 -187.999878)
				)
			)
		)
	)
	(zone
		(layers "In1.Cu" "In6.Cu")
		(hatch none 0.5)
		(connect_pads
			(clearance 0)
		)
		(min_thickness 0.25)
		(keepout
			(tracks not_allowed)
			(vias allowed)
			(pads allowed)
			(copperpour not_allowed)
			(footprints allowed)
		)
		(placement
			(enabled no)
			(sheetname "")
		)
		(fill yes
			(thermal_gap 0.5)
			(thermal_bridge_width 0.5)
			(island_removal_mode 0)
		)
		(polygon
			(pts
				(arc
					(start 84.768944 -120.000014)
					(mid 75.231244 -120.000014)
					(end 84.768944 -120.000014)
				)
			)
		)
	)
	(zone
		(layers "In1.Cu" "In6.Cu")
		(hatch none 0.5)
		(connect_pads
			(clearance 0)
		)
		(min_thickness 0.25)
		(keepout
			(tracks not_allowed)
			(vias allowed)
			(pads allowed)
			(copperpour not_allowed)
			(footprints allowed)
		)
		(placement
			(enabled no)
			(sheetname "")
		)
		(fill yes
			(thermal_gap 0.5)
			(thermal_bridge_width 0.5)
			(island_removal_mode 0)
		)
		(polygon
			(pts
				(arc
					(start 22.768814 -120.000014)
					(mid 13.231114 -120.000014)
					(end 22.768814 -120.000014)
				)
			)
		)
	)
	(zone
		(layers "In1.Cu" "In6.Cu")
		(hatch none 0.5)
		(connect_pads
			(clearance 0)
		)
		(min_thickness 0.25)
		(keepout
			(tracks not_allowed)
			(vias allowed)
			(pads allowed)
			(copperpour not_allowed)
			(footprints allowed)
		)
		(placement
			(enabled no)
			(sheetname "")
		)
		(fill yes
			(thermal_gap 0.5)
			(thermal_bridge_width 0.5)
			(island_removal_mode 0)
		)
		(polygon
			(pts
				(arc
					(start 22.768814 -24.99995)
					(mid 13.231114 -24.99995)
					(end 22.768814 -24.99995)
				)
			)
		)
	)
	(zone
		(layers "In1.Cu" "In6.Cu")
		(hatch none 0.5)
		(connect_pads
			(clearance 0)
		)
		(min_thickness 0.25)
		(keepout
			(tracks not_allowed)
			(vias allowed)
			(pads allowed)
			(copperpour not_allowed)
			(footprints allowed)
		)
		(placement
			(enabled no)
			(sheetname "")
		)
		(fill yes
			(thermal_gap 0.5)
			(thermal_bridge_width 0.5)
			(island_removal_mode 0)
		)
		(polygon
			(pts
				(arc
					(start 107.768898 -9.99998)
					(mid 98.231198 -9.99998)
					(end 107.768898 -9.99998)
				)
			)
		)
	)
	(zone
		(layers "In1.Cu" "In6.Cu")
		(hatch none 0.5)
		(connect_pads
			(clearance 0)
		)
		(min_thickness 0.25)
		(keepout
			(tracks not_allowed)
			(vias allowed)
			(pads allowed)
			(copperpour not_allowed)
			(footprints allowed)
		)
		(placement
			(enabled no)
			(sheetname "")
		)
		(fill yes
			(thermal_gap 0.5)
			(thermal_bridge_width 0.5)
			(island_removal_mode 0)
		)
		(polygon
			(pts
				(arc
					(start 227.268786 -110.000034)
					(mid 217.731086 -110.000034)
					(end 227.268786 -110.000034)
				)
			)
		)
	)
	(zone
		(layers "In1.Cu" "In6.Cu")
		(hatch none 0.5)
		(connect_pads
			(clearance 0)
		)
		(min_thickness 0.25)
		(keepout
			(tracks not_allowed)
			(vias allowed)
			(pads allowed)
			(copperpour not_allowed)
			(footprints allowed)
		)
		(placement
			(enabled no)
			(sheetname "")
		)
		(fill yes
			(thermal_gap 0.5)
			(thermal_bridge_width 0.5)
			(island_removal_mode 0)
		)
		(polygon
			(pts
				(arc
					(start 160.26892 -110.000034)
					(mid 150.73122 -110.000034)
					(end 160.26892 -110.000034)
				)
			)
		)
	)
	(zone
		(layers "In1.Cu" "In6.Cu")
		(hatch none 0.5)
		(connect_pads
			(clearance 0)
		)
		(min_thickness 0.25)
		(keepout
			(tracks not_allowed)
			(vias allowed)
			(pads allowed)
			(copperpour not_allowed)
			(footprints allowed)
		)
		(placement
			(enabled no)
			(sheetname "")
		)
		(fill yes
			(thermal_gap 0.5)
			(thermal_bridge_width 0.5)
			(island_removal_mode 0)
		)
		(polygon
			(pts
				(arc
					(start 97.268792 -187.999878)
					(mid 87.731092 -187.999878)
					(end 97.268792 -187.999878)
				)
			)
		)
	)
	(zone
		(net "P1V5")
		(layer "In2.Cu")
		(hatch none 0.5)
		(connect_pads
			(clearance 0.5)
		)
		(min_thickness 0.25)
		(fill yes
			(thermal_gap 0.5)
			(thermal_bridge_width 0.5)
			(island_removal_mode 0)
		)
		(polygon
			(pts
				(xy 204.748384 -93.989144) (xy 204.73924 -93.98) (xy 204.017118 -94.702122) (xy 204.017118 -95.261176)
				(xy 204.047852 -95.29191) (xy 204.047852 -95.690436) (xy 203.450698 -96.28759) (xy 203.450698 -101.897688)
				(xy 204.4065 -102.85349) (xy 204.4065 -103.8225) (xy 205.8924 -105.3084) (xy 212.598 -112.014) (xy 212.598 -118.5164)
				(xy 214.3506 -120.269) (xy 216.0524 -120.269) (xy 216.3826 -119.9388) (xy 216.3826 -105.62336) (xy 216.196164 -105.436924)
				(xy 216.196164 -105.426764) (xy 215.56218 -104.79278) (xy 215.56218 -102.565708) (xy 215.56218 -95.861886)
				(xy 213.689438 -93.989144) (xy 208.738216 -93.989144)
			)
		)
	)
	(zone
		(net "P1V8")
		(layer "In2.Cu")
		(hatch none 0.5)
		(connect_pads
			(clearance 0.5)
		)
		(min_thickness 0.25)
		(fill yes
			(thermal_gap 0.5)
			(thermal_bridge_width 0.5)
			(island_removal_mode 0)
		)
		(polygon
			(pts
				(xy 181.8132 -83.6676) (xy 183.7944 -85.6488) (xy 183.7944 -90.805) (xy 183.7436 -90.805) (xy 183.4642 -91.0844)
				(xy 182.3974 -91.0844) (xy 181.7116 -91.7702) (xy 181.7116 -92.2274) (xy 181.5338 -92.4052) (xy 180.8226 -92.4052)
				(xy 179.9082 -91.4908) (xy 178.9684 -90.551) (xy 178.9684 -84.8868) (xy 178.9684 -83.7184) (xy 179.0192 -83.6676)
				(xy 179.8574 -82.8294) (xy 180.975 -82.8294)
			)
		)
	)
	(zone
		(net "SAS0_AVDD")
		(layer "In2.Cu")
		(hatch none 0.5)
		(connect_pads
			(clearance 0.5)
		)
		(min_thickness 0.25)
		(fill yes
			(thermal_gap 0.5)
			(thermal_bridge_width 0.5)
			(island_removal_mode 0)
		)
		(polygon
			(pts
				(xy 204.3684 -68.1228) (xy 204.3684 -75.9968) (xy 203.5048 -76.8604) (xy 203.5048 -77.5462) (xy 204.216 -78.2574)
				(xy 204.4954 -78.2574) (xy 204.978 -78.2574) (xy 207.6704 -80.9498) (xy 207.6704 -83.449668) (xy 207.38338 -83.736688)
				(xy 207.38338 -84.334096) (xy 207.034384 -84.683092) (xy 207.034384 -85.884258) (xy 208.249012 -87.098886)
				(xy 208.249012 -89.275412) (xy 208.275428 -89.301828) (xy 208.275428 -90.199972) (xy 208.669128 -90.593672)
				(xy 210.378294 -90.593672) (xy 210.700366 -90.915744) (xy 210.700366 -92.594176) (xy 210.53171 -92.762832)
				(xy 206.13243 -92.762832) (xy 205.2574 -91.887802) (xy 205.2574 -91.260422) (xy 205.2574 -89.916)
				(xy 205.2574 -83.82) (xy 205.2574 -83.4898) (xy 204.7748 -83.0072) (xy 201.3712 -83.0072) (xy 200.2282 -81.8642)
				(xy 200.2282 -76.7842) (xy 200.1647 -76.7207) (xy 200.1647 -75.9079) (xy 200.406 -75.6666) (xy 200.406 -74.7522)
				(xy 200.8378 -74.3204) (xy 201.7776 -74.3204) (xy 201.9808 -74.1172) (xy 202.015852 -74.082148)
				(xy 202.015852 -73.777348) (xy 202.2856 -73.5076) (xy 202.6158 -73.5076) (xy 202.8444 -73.279) (xy 202.8444 -72.9996)
				(xy 202.5142 -72.6694) (xy 202.1078 -72.6694) (xy 201.9808 -72.5424) (xy 201.9808 -71.1708) (xy 202.057 -71.0946)
				(xy 203.3778 -71.0946) (xy 203.581 -70.8914) (xy 203.581 -70.5358) (xy 203.3524 -70.3072) (xy 202.057 -70.3072)
				(xy 201.9808 -70.231) (xy 201.9808 -68.7832) (xy 202.057 -68.707) (xy 202.5904 -68.707) (xy 202.7936 -68.5038)
				(xy 202.7936 -68.0466) (xy 202.8952 -67.945) (xy 204.1906 -67.945)
			)
		)
	)
	(zone
		(net "GND")
		(layer "In2.Cu")
		(hatch none 0.5)
		(connect_pads
			(clearance 0.5)
		)
		(min_thickness 0.25)
		(fill yes
			(thermal_gap 0.5)
			(thermal_bridge_width 0.5)
			(island_removal_mode 0)
		)
		(polygon
			(pts
				(xy 226.4918 -61.5442) (xy 226.949 -61.5442) (xy 227.1014 -61.3918) (xy 227.1014 -58.0898) (xy 227.0252 -58.0136)
				(xy 226.5426 -58.0136) (xy 225.8568 -57.3278) (xy 225.5012 -57.3278) (xy 225.2599 -57.5691) (xy 225.2599 -60.7187)
				(xy 225.3488 -60.8076) (xy 225.7552 -60.8076)
			)
		)
	)
	(zone
		(net "GND")
		(layer "In2.Cu")
		(hatch none 0.5)
		(connect_pads
			(clearance 0.5)
		)
		(min_thickness 0.25)
		(fill yes
			(thermal_gap 0.5)
			(thermal_bridge_width 0.5)
			(island_removal_mode 0)
		)
		(polygon
			(pts
				(xy 90.0938 -166.1668) (xy 94.4118 -166.1668) (xy 94.5896 -165.989) (xy 94.5896 -165.0238) (xy 95.2373 -164.3761)
				(xy 95.2373 -163.9951) (xy 94.7166 -163.4744) (xy 90.9066 -163.4744) (xy 90.6272 -163.7538) (xy 90.6272 -164.6428)
				(xy 90.6272 -164.8206) (xy 90.6272 -164.8714) (xy 90.6145 -164.8841) (xy 90.0176 -165.481) (xy 90.0176 -166.0906)
			)
		)
	)
	(zone
		(net "SAS0_VDDH")
		(layer "In2.Cu")
		(hatch none 0.5)
		(connect_pads
			(clearance 0.5)
		)
		(min_thickness 0.25)
		(fill yes
			(thermal_gap 0.5)
			(thermal_bridge_width 0.5)
			(island_removal_mode 0)
		)
		(polygon
			(pts
				(xy 203.24572 -62.61608) (xy 202.7428 -63.119) (xy 202.0316 -63.119) (xy 201.7776 -62.865) (xy 201.168 -62.865)
				(xy 200.914 -63.119) (xy 199.771 -64.262) (xy 199.771 -66.8528) (xy 199.644 -66.9798) (xy 199.644 -68.9102)
				(xy 199.644 -69.2658) (xy 199.8726 -69.4944) (xy 200.1266 -69.4944) (xy 200.3806 -69.7484) (xy 200.3806 -70.993)
				(xy 200.5838 -71.1962) (xy 200.9902 -71.1962) (xy 201.1426 -71.0438) (xy 201.1426 -70.231) (xy 201.1426 -69.6468)
				(xy 200.533 -69.0372) (xy 200.533 -67.4116) (xy 201.4728 -66.4718) (xy 203.454 -66.4718) (xy 204.6732 -67.691)
				(xy 204.6732 -76.6572) (xy 205.232 -77.216) (xy 206.8576 -77.216) (xy 208.3308 -78.6892) (xy 208.3308 -80.7212)
				(xy 208.3308 -82.10677) (xy 208.587848 -82.363818) (xy 209.803238 -82.363818) (xy 210.300824 -82.861404)
				(xy 210.300824 -83.623912) (xy 210.271106 -83.623912) (xy 209.2198 -84.675218) (xy 209.2198 -84.8106)
				(xy 208.7372 -85.2932) (xy 208.7372 -89.2556) (xy 209.6516 -90.17) (xy 211.3026 -90.17) (xy 211.963 -89.5096)
				(xy 211.963 -86.487) (xy 211.963 -81.296764) (xy 210.031076 -79.36484) (xy 210.031076 -77.041502)
				(xy 208.30286 -75.313032) (xy 207.726026 -75.313032) (xy 207.57896 -75.165966) (xy 207.57896 -65.108328)
				(xy 205.086712 -62.61608)
			)
		)
	)
	(zone
		(net "GND")
		(layer "In2.Cu")
		(hatch none 0.5)
		(connect_pads
			(clearance 0.5)
		)
		(min_thickness 0.25)
		(fill yes
			(thermal_gap 0.5)
			(thermal_bridge_width 0.5)
			(island_removal_mode 0)
		)
		(polygon
			(pts
				(arc
					(start 0.999998 -0.763016)
					(mid 0.832426 -0.832426)
					(end 0.763016 -0.999998)
				)
				(arc
					(start 0.763016 -183.76392)
					(mid 0.769411 -183.818347)
					(end 0.788162 -183.869838)
				)
				(arc
					(start 5.406136 -193.10604)
					(mid 5.493436 -193.201687)
					(end 5.617972 -193.237104)
				)
				(arc
					(start 98.0821 -193.237104)
					(mid 98.206591 -193.201614)
					(end 98.293936 -193.10604)
				)
				(arc
					(start 102.91191 -183.869838)
					(mid 102.930633 -183.818341)
					(end 102.937056 -183.76392)
				)
				(xy 102.937056 -183.403748) (xy 100.874322 -183.403748) (xy 96.97339 -191.20612) (xy 6.726682 -191.20612)
				(xy 2.82575 -183.403748) (xy 2.767584 -183.403748) (xy 2.7305 -183.366664) (xy 2.7305 -183.313832)
				(xy 2.767584 -183.276748) (xy 2.794 -183.276748) (xy 2.794 -2.794) (xy 27.736038 -2.794)
				(arc
					(start 27.736038 -109.050074)
					(mid 28.847274 -111.732836)
					(end 31.530036 -112.844072)
				)
				(xy 52.136294 -112.844072) (xy 52.136294 -111.304324) (xy 52.199032 -111.304324) (xy 52.199032 -111.06912)
				(xy 69.578474 -111.06912) (xy 69.578474 -112.844072)
				(arc
					(start 72.030082 -112.844072)
					(mid 73.584114 -112.511202)
					(end 74.865484 -111.571024)
				)
				(xy 73.562718 -111.571024)
				(arc
					(start 73.562718 -109.921294)
					(mid 72.916671 -110.573871)
					(end 72.030082 -110.813088)
				)
				(arc
					(start 31.530036 -110.813088)
					(mid 30.283397 -110.296713)
					(end 29.767022 -109.050074)
				)
				(arc
					(start 29.767022 -0.999998)
					(mid 29.697612 -0.832426)
					(end 29.53004 -0.763016)
				)
			)
		)
	)
	(zone
		(net "P2V5_STBY")
		(layer "In2.Cu")
		(hatch none 0.5)
		(connect_pads
			(clearance 0.5)
		)
		(min_thickness 0.25)
		(fill yes
			(thermal_gap 0.5)
			(thermal_bridge_width 0.5)
			(island_removal_mode 0)
		)
		(polygon
			(pts
				(xy 25.1587 -135.9027) (xy 25.908 -135.1534) (xy 26.1874 -134.874) (xy 26.1874 -134.493) (xy 25.8826 -134.1882)
				(xy 25.273 -134.1882) (xy 25.2222 -134.239) (xy 24.0792 -135.382) (xy 24.0792 -135.7884) (xy 24.257 -135.9662)
				(xy 24.2697 -135.9535) (xy 25.1079 -135.9535)
			)
		)
	)
	(zone
		(net "GND")
		(layer "In2.Cu")
		(hatch none 0.5)
		(connect_pads
			(clearance 0.5)
		)
		(min_thickness 0.25)
		(fill yes
			(thermal_gap 0.5)
			(thermal_bridge_width 0.5)
			(island_removal_mode 0)
		)
		(polygon
			(pts
				(xy 70.0024 -157.607) (xy 71.7296 -157.607) (xy 71.755 -157.5816) (xy 71.8058 -157.5308) (xy 71.8058 -154.9908)
				(xy 71.755 -154.94) (xy 71.7296 -154.9146) (xy 71.12 -154.305) (xy 67.6148 -154.305) (xy 67.5386 -154.3812)
				(xy 67.5386 -157.5562) (xy 67.7672 -157.7848) (xy 68.4403 -158.4579) (xy 68.8086 -158.4579) (xy 69.6595 -157.607)
			)
		)
	)
	(zone
		(net "GND")
		(layer "In2.Cu")
		(hatch none 0.5)
		(connect_pads
			(clearance 0.5)
		)
		(min_thickness 0.25)
		(fill yes
			(thermal_gap 0.5)
			(thermal_bridge_width 0.5)
			(island_removal_mode 0)
		)
		(polygon
			(pts
				(xy 44.720764 -147.753578) (xy 44.943268 -147.976082) (xy 44.943268 -150.04923) (xy 44.775628 -150.21687)
				(xy 42.631614 -150.21687) (xy 42.416984 -150.00224) (xy 42.416984 -148.971254) (xy 41.704768 -148.259038)
				(xy 41.704768 -147.969732) (xy 41.920922 -147.753578) (xy 42.000932 -147.673568) (xy 44.640754 -147.673568)
			)
		)
	)
	(zone
		(net "VPLLAV33")
		(layer "In2.Cu")
		(hatch none 0.5)
		(connect_pads
			(clearance 0.5)
		)
		(min_thickness 0.25)
		(fill yes
			(thermal_gap 0.5)
			(thermal_bridge_width 0.5)
			(island_removal_mode 0)
		)
		(polygon
			(pts
				(xy 49.9872 -149.3012) (xy 50.9778 -149.3012) (xy 51.181 -149.098) (xy 51.181 -148.717) (xy 51.2826 -148.6154)
				(xy 51.6636 -148.6154) (xy 51.9176 -148.6154) (xy 52.1462 -148.3868) (xy 52.1462 -147.8534) (xy 52.1462 -147.8026)
				(xy 52.07 -147.7264) (xy 50.0634 -147.7264) (xy 49.8602 -147.9296) (xy 49.8602 -148.0566) (xy 49.8602 -149.1742)
			)
		)
	)
	(zone
		(net "EXT2_CONN_GND")
		(layer "In2.Cu")
		(hatch none 0.5)
		(connect_pads
			(clearance 0.5)
		)
		(min_thickness 0.25)
		(fill yes
			(thermal_gap 0.5)
			(thermal_bridge_width 0.5)
			(island_removal_mode 0)
		)
		(polygon
			(pts
				(xy 168.0083 -34.0233) (xy 168.0083 -6.8453) (xy 165.5064 -4.3434) (xy 154.5082 -4.3434) (xy 153.8732 -4.9784)
				(xy 153.8732 -5.969) (xy 154.1145 -6.2103) (xy 154.1145 -11.6459) (xy 154.1145 -19.2151) (xy 155.6258 -20.7264)
				(xy 155.6258 -35.56) (xy 158.0134 -37.9476) (xy 164.084 -37.9476)
			)
		)
	)
	(zone
		(net "GND")
		(layer "In2.Cu")
		(hatch none 0.5)
		(connect_pads
			(clearance 0.5)
		)
		(min_thickness 0.25)
		(fill yes
			(thermal_gap 0.5)
			(thermal_bridge_width 0.5)
			(island_removal_mode 0)
		)
		(polygon
			(pts
				(xy 31.242 -132.9182) (xy 33.9344 -132.9182) (xy 33.9852 -132.9182) (xy 34.9631 -133.8961) (xy 35.4203 -133.8961)
				(xy 35.6362 -133.6802) (xy 35.6362 -133.35) (xy 35.1282 -132.842) (xy 35.1282 -129.921) (xy 34.5694 -129.3622)
				(xy 30.5054 -129.3622) (xy 30.099 -129.7686) (xy 30.099 -130.4036) (xy 31.0896 -131.3942) (xy 31.0896 -132.7658)
			)
		)
	)
	(zone
		(net "GND")
		(layer "In2.Cu")
		(hatch none 0.5)
		(connect_pads
			(clearance 0.5)
		)
		(min_thickness 0.25)
		(fill yes
			(thermal_gap 0.5)
			(thermal_bridge_width 0.5)
			(island_removal_mode 0)
		)
		(polygon
			(pts
				(xy 188.773054 -0.763016) (xy 188.773054 -2.794) (xy 232.206038 -2.794) (xy 232.206038 -183.340248)
				(xy 228.273356 -191.20612) (xy 151.026622 -191.20612) (xy 147.09394 -183.340248) (xy 147.09394 -98.269806)
				(xy 145.747486 -98.269806) (xy 145.747486 -98.019108) (xy 145.062956 -98.019108)
				(arc
					(start 145.062956 -183.76392)
					(mid 145.069351 -183.818347)
					(end 145.088102 -183.869838)
				)
				(arc
					(start 149.706076 -193.10604)
					(mid 149.793376 -193.201687)
					(end 149.917912 -193.237104)
				)
				(arc
					(start 229.382066 -193.237104)
					(mid 229.506557 -193.201614)
					(end 229.593902 -193.10604)
				)
				(arc
					(start 234.211876 -183.869838)
					(mid 234.230599 -183.818341)
					(end 234.237022 -183.76392)
				)
				(arc
					(start 234.237022 -0.999998)
					(mid 234.167612 -0.832426)
					(end 234.00004 -0.763016)
				)
			)
		)
	)
	(zone
		(net "PCE_VDDH")
		(layer "In2.Cu")
		(hatch none 0.5)
		(connect_pads
			(clearance 0.5)
		)
		(min_thickness 0.25)
		(fill yes
			(thermal_gap 0.5)
			(thermal_bridge_width 0.5)
			(island_removal_mode 0)
		)
		(polygon
			(pts
				(xy 199.900032 -77.587856) (xy 199.900032 -76.9112) (xy 199.505316 -76.516484) (xy 199.505316 -75.068684)
				(xy 199.6694 -74.9046) (xy 199.6694 -72.9488) (xy 199.4916 -72.771) (xy 199.3646 -72.771) (xy 198.247 -72.771)
				(xy 197.9676 -72.4916) (xy 197.9676 -72.1106) (xy 197.729856 -71.872856) (xy 192.649856 -71.872856)
				(xy 192.3288 -71.5518) (xy 190.9826 -71.5518) (xy 190.629032 -71.905368) (xy 190.629032 -72.634856)
				(xy 190.629032 -77.841856) (xy 191.010032 -78.222856) (xy 191.135 -78.347824) (xy 191.135 -83.947)
				(xy 188.849 -86.233) (xy 188.849 -92.837) (xy 189.6364 -93.6244) (xy 200.9648 -93.6244) (xy 201.168 -93.4212)
				(xy 202.1332 -92.456) (xy 203.679806 -90.909394) (xy 203.679806 -88.531954) (xy 202.437492 -87.28964)
				(xy 200.52284 -87.28964) (xy 199.900032 -86.666832)
			)
		)
	)
	(zone
		(net "P1V8")
		(layer "In2.Cu")
		(hatch none 0.5)
		(connect_pads
			(clearance 0.5)
		)
		(min_thickness 0.25)
		(fill yes
			(thermal_gap 0.5)
			(thermal_bridge_width 0.5)
			(island_removal_mode 0)
		)
		(polygon
			(pts
				(xy 189.865 -43.18) (xy 188.849 -44.196) (xy 188.849 -48.2473) (xy 189.6618 -49.0601) (xy 192.5701 -49.0601)
				(xy 194.4878 -50.9778) (xy 203.1238 -50.9778) (xy 203.55687 -50.9778) (xy 207.433418 -54.854348)
				(xy 207.433418 -56.701182) (xy 206.502 -57.6326) (xy 201.4982 -57.6326) (xy 201.0918 -58.039) (xy 201.0918 -61.087)
				(xy 201.5744 -61.5696) (xy 201.8284 -61.5696) (xy 202.0062 -61.7474) (xy 202.0062 -62.8269) (xy 202.1586 -62.9793)
				(xy 202.6158 -62.9793) (xy 202.78725 -62.80785) (xy 202.78725 -61.65215) (xy 202.9206 -61.5188)
				(xy 202.9206 -60.5536) (xy 204.3176 -59.1566) (xy 205.1304 -59.1566) (xy 205.428088 -59.1566) (xy 207.790288 -61.5188)
				(xy 207.94853 -61.677042) (xy 208.52257 -62.251082) (xy 208.52257 -64.477392) (xy 208.52257 -74.88174)
				(xy 210.594194 -76.953364) (xy 210.594194 -79.50962) (xy 212.399372 -81.314798) (xy 212.399372 -89.394284)
				(xy 213.203536 -90.198448) (xy 214.374476 -90.198448) (xy 215.304116 -89.268808) (xy 215.304116 -81.332578)
				(xy 212.301328 -78.32979) (xy 212.301328 -74.174096) (xy 210.933792 -72.80656) (xy 210.933792 -68.23075)
				(xy 209.86115 -67.158108) (xy 209.86115 -63.761874) (xy 212.1154 -61.507624) (xy 212.1154 -58.3184)
				(xy 212.1027 -58.3057) (xy 212.1027 -55.595774) (xy 208.183734 -51.676808) (xy 208.183734 -48.366934)
				(xy 206.5782 -46.7614) (xy 206.5782 -45.212) (xy 206.0829 -44.7167) (xy 194.0941 -44.7167) (xy 192.5574 -43.18)
			)
		)
	)
	(zone
		(net "EXT1_CONN_GND")
		(layer "In2.Cu")
		(hatch none 0.5)
		(connect_pads
			(clearance 0.5)
		)
		(min_thickness 0.25)
		(fill yes
			(thermal_gap 0.5)
			(thermal_bridge_width 0.5)
			(island_removal_mode 0)
		)
		(polygon
			(pts
				(xy 176.1744 -34.798) (xy 184.1754 -34.798) (xy 189.9412 -34.798) (xy 191.4906 -33.2486) (xy 191.4906 -27.8384)
				(xy 186.1566 -22.5044) (xy 186.1566 -5.0038) (xy 185.5978 -4.445) (xy 172.9486 -4.445) (xy 172.593 -4.8006)
				(xy 172.593 -31.2166)
			)
		)
	)
	(zone
		(net "GND")
		(layer "In2.Cu")
		(hatch none 0.5)
		(connect_pads
			(clearance 0.5)
		)
		(min_thickness 0.25)
		(fill yes
			(thermal_gap 0.5)
			(thermal_bridge_width 0.5)
			(island_removal_mode 0)
		)
		(polygon
			(pts
				(arc
					(start 74.030078 -0.763016)
					(mid 73.862506 -0.832426)
					(end 73.793096 -0.999998)
				)
				(xy 73.793096 -89.046558) (xy 74.048874 -89.046558) (xy 74.048874 -7.921244) (xy 74.472546 -7.921244)
				(xy 74.472546 -7.92099) (xy 75.82408 -7.92099) (xy 75.82408 -2.794) (xy 80.903572 -2.794) (xy 80.903572 -0.909574)
				(xy 81.154524 -0.909574) (xy 81.154524 -1.019556) (xy 83.977988 -1.019556) (xy 83.977988 -2.794)
				(xy 142.516098 -2.794) (xy 142.516098 -1.239012) (xy 168.993312 -1.239012) (xy 168.993312 -2.794)
				(xy 186.231784 -2.794) (xy 186.231784 -0.763016)
			)
		)
	)
	(zone
		(layers "In2.Cu" "In3.Cu" "In4.Cu" "In5.Cu")
		(hatch none 0.5)
		(connect_pads
			(clearance 0)
		)
		(min_thickness 0.25)
		(keepout
			(tracks not_allowed)
			(vias allowed)
			(pads allowed)
			(copperpour not_allowed)
			(footprints allowed)
		)
		(placement
			(enabled no)
			(sheetname "")
		)
		(fill yes
			(thermal_gap 0.5)
			(thermal_bridge_width 0.5)
			(island_removal_mode 0)
		)
		(polygon
			(pts
				(arc
					(start 219.799916 -81.479898)
					(mid 219.799916 -87.479886)
					(end 219.799916 -81.479898)
				)
			)
		)
	)
	(zone
		(layers "In2.Cu" "In3.Cu" "In4.Cu" "In5.Cu")
		(hatch none 0.5)
		(connect_pads
			(clearance 0)
		)
		(min_thickness 0.25)
		(keepout
			(tracks not_allowed)
			(vias allowed)
			(pads allowed)
			(copperpour not_allowed)
			(footprints allowed)
		)
		(placement
			(enabled no)
			(sheetname "")
		)
		(fill yes
			(thermal_gap 0.5)
			(thermal_bridge_width 0.5)
			(island_removal_mode 0)
		)
		(polygon
			(pts
				(arc
					(start 103.000048 -5.249926)
					(mid 103.000048 -14.750034)
					(end 103.000048 -5.249926)
				)
			)
		)
	)
	(zone
		(layers "In2.Cu" "In3.Cu" "In4.Cu" "In5.Cu")
		(hatch none 0.5)
		(connect_pads
			(clearance 0)
		)
		(min_thickness 0.25)
		(keepout
			(tracks not_allowed)
			(vias allowed)
			(pads allowed)
			(copperpour not_allowed)
			(footprints allowed)
		)
		(placement
			(enabled no)
			(sheetname "")
		)
		(fill yes
			(thermal_gap 0.5)
			(thermal_bridge_width 0.5)
			(island_removal_mode 0)
		)
		(polygon
			(pts
				(arc
					(start 155.50007 -105.24998)
					(mid 155.50007 -114.750088)
					(end 155.50007 -105.24998)
				)
			)
		)
	)
	(zone
		(layers "In2.Cu" "In3.Cu" "In4.Cu" "In5.Cu")
		(hatch none 0.5)
		(connect_pads
			(clearance 0)
		)
		(min_thickness 0.25)
		(keepout
			(tracks not_allowed)
			(vias allowed)
			(pads allowed)
			(copperpour not_allowed)
			(footprints allowed)
		)
		(placement
			(enabled no)
			(sheetname "")
		)
		(fill yes
			(thermal_gap 0.5)
			(thermal_bridge_width 0.5)
			(island_removal_mode 0)
		)
		(polygon
			(pts
				(arc
					(start 17.999964 -20.249896)
					(mid 17.999964 -29.750004)
					(end 17.999964 -20.249896)
				)
			)
		)
	)
	(zone
		(layers "In2.Cu" "In3.Cu" "In4.Cu" "In5.Cu")
		(hatch none 0.5)
		(connect_pads
			(clearance 0)
		)
		(min_thickness 0.25)
		(keepout
			(tracks not_allowed)
			(vias allowed)
			(pads allowed)
			(copperpour not_allowed)
			(footprints allowed)
		)
		(placement
			(enabled no)
			(sheetname "")
		)
		(fill yes
			(thermal_gap 0.5)
			(thermal_bridge_width 0.5)
			(island_removal_mode 0)
		)
		(polygon
			(pts
				(arc
					(start 222.499936 -105.24998)
					(mid 222.499936 -114.750088)
					(end 222.499936 -105.24998)
				)
			)
		)
	)
	(zone
		(layers "In2.Cu" "In3.Cu" "In4.Cu" "In5.Cu")
		(hatch none 0.5)
		(connect_pads
			(clearance 0)
		)
		(min_thickness 0.25)
		(keepout
			(tracks not_allowed)
			(vias allowed)
			(pads allowed)
			(copperpour not_allowed)
			(footprints allowed)
		)
		(placement
			(enabled no)
			(sheetname "")
		)
		(fill yes
			(thermal_gap 0.5)
			(thermal_bridge_width 0.5)
			(island_removal_mode 0)
		)
		(polygon
			(pts
				(arc
					(start 155.50007 -183.249824)
					(mid 155.50007 -192.749932)
					(end 155.50007 -183.249824)
				)
			)
		)
	)
	(zone
		(layers "In2.Cu" "In3.Cu" "In4.Cu" "In5.Cu")
		(hatch none 0.5)
		(connect_pads
			(clearance 0)
		)
		(min_thickness 0.25)
		(keepout
			(tracks not_allowed)
			(vias allowed)
			(pads allowed)
			(copperpour not_allowed)
			(footprints allowed)
		)
		(placement
			(enabled no)
			(sheetname "")
		)
		(fill yes
			(thermal_gap 0.5)
			(thermal_bridge_width 0.5)
			(island_removal_mode 0)
		)
		(polygon
			(pts
				(arc
					(start 222.499936 -183.249824)
					(mid 222.499936 -192.749932)
					(end 222.499936 -183.249824)
				)
			)
		)
	)
	(zone
		(layers "In2.Cu" "In3.Cu" "In4.Cu" "In5.Cu")
		(hatch none 0.5)
		(connect_pads
			(clearance 0)
		)
		(min_thickness 0.25)
		(keepout
			(tracks not_allowed)
			(vias allowed)
			(pads allowed)
			(copperpour not_allowed)
			(footprints allowed)
		)
		(placement
			(enabled no)
			(sheetname "")
		)
		(fill yes
			(thermal_gap 0.5)
			(thermal_bridge_width 0.5)
			(island_removal_mode 0)
		)
		(polygon
			(pts
				(arc
					(start 92.499942 -183.249824)
					(mid 92.499942 -192.749932)
					(end 92.499942 -183.249824)
				)
			)
		)
	)
	(zone
		(layers "In2.Cu" "In3.Cu" "In4.Cu" "In5.Cu")
		(hatch none 0.5)
		(connect_pads
			(clearance 0)
		)
		(min_thickness 0.25)
		(keepout
			(tracks not_allowed)
			(vias allowed)
			(pads allowed)
			(copperpour not_allowed)
			(footprints allowed)
		)
		(placement
			(enabled no)
			(sheetname "")
		)
		(fill yes
			(thermal_gap 0.5)
			(thermal_bridge_width 0.5)
			(island_removal_mode 0)
		)
		(polygon
			(pts
				(arc
					(start 17.999964 -115.24996)
					(mid 17.999964 -124.750068)
					(end 17.999964 -115.24996)
				)
			)
		)
	)
	(zone
		(layers "In2.Cu" "In5.Cu")
		(hatch none 0.5)
		(connect_pads
			(clearance 0)
		)
		(min_thickness 0.25)
		(keepout
			(tracks not_allowed)
			(vias allowed)
			(pads allowed)
			(copperpour not_allowed)
			(footprints allowed)
		)
		(placement
			(enabled no)
			(sheetname "")
		)
		(fill yes
			(thermal_gap 0.5)
			(thermal_bridge_width 0.5)
			(island_removal_mode 0)
		)
		(polygon
			(pts
				(arc
					(start 77.667358 -86.510368)
					(mid 77.283818 -86.126828)
					(end 76.900278 -86.510368)
				)
				(arc
					(start 76.900278 -87.399114)
					(mid 77.282421 -87.782906)
					(end 77.667358 -87.401908)
				)
				(arc
					(start 77.550518 -87.401908)
					(mid 77.283818 -87.66608)
					(end 77.017118 -87.401908)
				)
				(arc
					(start 77.017118 -87.399368)
					(mid 77.283818 -87.132668)
					(end 77.550518 -87.399368)
				)
				(xy 77.667358 -87.399368) (xy 77.667358 -86.512908)
				(arc
					(start 77.550518 -86.512908)
					(mid 77.283818 -86.77708)
					(end 77.017118 -86.512908)
				)
				(arc
					(start 77.017118 -86.510368)
					(mid 77.283818 -86.243668)
					(end 77.550518 -86.510368)
				)
			)
		)
	)
	(zone
		(layers "In2.Cu" "In5.Cu")
		(hatch none 0.5)
		(connect_pads
			(clearance 0)
		)
		(min_thickness 0.25)
		(keepout
			(tracks not_allowed)
			(vias allowed)
			(pads allowed)
			(copperpour not_allowed)
			(footprints allowed)
		)
		(placement
			(enabled no)
			(sheetname "")
		)
		(fill yes
			(thermal_gap 0.5)
			(thermal_bridge_width 0.5)
			(island_removal_mode 0)
		)
		(polygon
			(pts
				(arc
					(start 77.667358 -92.911168)
					(mid 77.283818 -92.527628)
					(end 76.900278 -92.911168)
				)
				(arc
					(start 76.900278 -93.799914)
					(mid 77.282421 -94.183706)
					(end 77.667358 -93.802708)
				)
				(arc
					(start 77.550518 -93.802708)
					(mid 77.283818 -94.06688)
					(end 77.017118 -93.802708)
				)
				(arc
					(start 77.017118 -93.800168)
					(mid 77.283818 -93.533468)
					(end 77.550518 -93.800168)
				)
				(xy 77.667358 -93.800168) (xy 77.667358 -92.913708)
				(arc
					(start 77.550518 -92.913708)
					(mid 77.283818 -93.17788)
					(end 77.017118 -92.913708)
				)
				(arc
					(start 77.017118 -92.911168)
					(mid 77.283818 -92.644468)
					(end 77.550518 -92.911168)
				)
			)
		)
	)
	(zone
		(layers "In2.Cu" "In5.Cu")
		(hatch none 0.5)
		(connect_pads
			(clearance 0)
		)
		(min_thickness 0.25)
		(keepout
			(tracks not_allowed)
			(vias allowed)
			(pads allowed)
			(copperpour not_allowed)
			(footprints allowed)
		)
		(placement
			(enabled no)
			(sheetname "")
		)
		(fill yes
			(thermal_gap 0.5)
			(thermal_bridge_width 0.5)
			(island_removal_mode 0)
		)
		(polygon
			(pts
				(arc
					(start 200.357994 -73.899268)
					(mid 199.999219 -73.54189)
					(end 199.641714 -73.900538)
				)
				(arc
					(start 199.643492 -74.695558)
					(mid 200.000743 -75.052936)
					(end 200.359772 -74.697336)
				)
				(arc
					(start 200.242932 -74.697336)
					(mid 200.001632 -74.936109)
					(end 199.760332 -74.697336)
				)
				(arc
					(start 199.760332 -74.694796)
					(mid 200.001632 -74.453496)
					(end 200.242932 -74.694796)
				)
				(xy 200.359772 -74.694796) (xy 200.359772 -74.694034) (xy 200.357994 -73.902316)
				(arc
					(start 200.241154 -73.902316)
					(mid 199.999854 -74.141089)
					(end 199.758554 -73.902316)
				)
				(arc
					(start 199.758554 -73.899776)
					(mid 199.999854 -73.658476)
					(end 200.241154 -73.899776)
				)
				(xy 200.357994 -73.899776)
			)
		)
	)
	(zone
		(layers "In2.Cu" "In5.Cu")
		(hatch none 0.5)
		(connect_pads
			(clearance 0)
		)
		(min_thickness 0.25)
		(keepout
			(tracks not_allowed)
			(vias allowed)
			(pads allowed)
			(copperpour not_allowed)
			(footprints allowed)
		)
		(placement
			(enabled no)
			(sheetname "")
		)
		(fill yes
			(thermal_gap 0.5)
			(thermal_bridge_width 0.5)
			(island_removal_mode 0)
		)
		(polygon
			(pts
				(arc
					(start 193.157856 -73.899776)
					(mid 192.799589 -73.541636)
					(end 192.441576 -73.90003)
				)
				(arc
					(start 192.44183 -74.699876)
					(mid 192.7987 -75.058014)
					(end 193.15811 -74.702416)
				)
				(arc
					(start 193.04127 -74.702416)
					(mid 192.79997 -74.941189)
					(end 192.55867 -74.702416)
				)
				(arc
					(start 192.55867 -74.699876)
					(mid 192.79997 -74.458576)
					(end 193.04127 -74.699876)
				)
				(xy 193.15811 -74.699876) (xy 193.15811 -74.699622) (xy 193.157856 -74.141076) (xy 193.157856 -73.902316)
				(arc
					(start 193.041016 -73.902316)
					(mid 192.799716 -74.141089)
					(end 192.558416 -73.902316)
				)
				(arc
					(start 192.558416 -73.899776)
					(mid 192.799716 -73.658476)
					(end 193.041016 -73.899776)
				)
			)
		)
	)
	(zone
		(layers "In2.Cu" "In5.Cu")
		(hatch none 0.5)
		(connect_pads
			(clearance 0)
		)
		(min_thickness 0.25)
		(keepout
			(tracks not_allowed)
			(vias allowed)
			(pads allowed)
			(copperpour not_allowed)
			(footprints allowed)
		)
		(placement
			(enabled no)
			(sheetname "")
		)
		(fill yes
			(thermal_gap 0.5)
			(thermal_bridge_width 0.5)
			(island_removal_mode 0)
		)
		(polygon
			(pts
				(arc
					(start 0.999998 -0.762)
					(mid 0.831708 -0.831708)
					(end 0.762 -0.999998)
				)
				(arc
					(start 0.762 -183.76392)
					(mid 0.768367 -183.818601)
					(end 0.787146 -183.870346)
				)
				(arc
					(start 5.40512 -193.106548)
					(mid 5.492861 -193.202556)
					(end 5.617972 -193.23812)
				)
				(arc
					(start 98.0821 -193.23812)
					(mid 98.207223 -193.202575)
					(end 98.294952 -193.106548)
				)
				(arc
					(start 102.912926 -183.870346)
					(mid 102.931684 -183.818596)
					(end 102.938072 -183.76392)
				)
				(xy 102.938072 -183.652668) (xy 102.169722 -183.652668) (xy 97.75825 -192.47612) (xy 5.941822 -192.47612)
				(xy 1.53035 -183.652668) (xy 1.5113 -183.652668) (xy 1.5113 -183.627268) (xy 1.524 -183.627268)
				(xy 1.524 -1.524) (xy 29.006038 -1.524)
				(arc
					(start 29.006038 -109.050074)
					(mid 29.7453 -110.83481)
					(end 31.530036 -111.574072)
				)
				(arc
					(start 72.030082 -111.574072)
					(mid 73.814818 -110.83481)
					(end 74.55408 -109.050074)
				)
				(xy 74.55408 -1.524) (xy 233.476038 -1.524) (xy 233.476038 -183.640222) (xy 229.058216 -192.47612)
				(xy 150.241762 -192.47612) (xy 145.82394 -183.640222)
				(arc
					(start 145.82394 -47.999904)
					(mid 144.636825 -46.156945)
					(end 142.468092 -46.475904)
				)
				(arc
					(start 105.53192 -46.475904)
					(mid 103.363292 -46.157176)
					(end 102.176072 -47.999904)
				)
				(xy 102.176072 -183.627268) (xy 102.938072 -183.627268)
				(arc
					(start 102.938072 -47.999904)
					(mid 103.798188 -46.803514)
					(end 105.206038 -47.237904)
				)
				(arc
					(start 142.793974 -47.237904)
					(mid 144.201748 -46.80374)
					(end 145.06194 -47.999904)
				)
				(arc
					(start 145.06194 -183.76392)
					(mid 145.068307 -183.818601)
					(end 145.087086 -183.870346)
				)
				(arc
					(start 149.70506 -193.106548)
					(mid 149.792801 -193.202556)
					(end 149.917912 -193.23812)
				)
				(arc
					(start 229.382066 -193.23812)
					(mid 229.507189 -193.202575)
					(end 229.594918 -193.106548)
				)
				(arc
					(start 234.212892 -183.870346)
					(mid 234.23165 -183.818596)
					(end 234.238038 -183.76392)
				)
				(arc
					(start 234.238038 -0.999998)
					(mid 234.16833 -0.831708)
					(end 234.00004 -0.762)
				)
				(arc
					(start 74.030078 -0.762)
					(mid 73.861788 -0.831708)
					(end 73.79208 -0.999998)
				)
				(arc
					(start 73.79208 -109.050074)
					(mid 73.276003 -110.295995)
					(end 72.030082 -110.812072)
				)
				(arc
					(start 31.530036 -110.812072)
					(mid 30.284115 -110.295995)
					(end 29.768038 -109.050074)
				)
				(arc
					(start 29.768038 -0.999998)
					(mid 29.69833 -0.831708)
					(end 29.53004 -0.762)
				)
			)
		)
	)
	(zone
		(layers "In2.Cu" "In5.Cu")
		(hatch none 0.5)
		(connect_pads
			(clearance 0)
		)
		(min_thickness 0.25)
		(keepout
			(tracks not_allowed)
			(vias allowed)
			(pads allowed)
			(copperpour not_allowed)
			(footprints allowed)
		)
		(placement
			(enabled no)
			(sheetname "")
		)
		(fill yes
			(thermal_gap 0.5)
			(thermal_bridge_width 0.5)
			(island_removal_mode 0)
		)
		(polygon
			(pts
				(arc
					(start 21.150072 -58.088022)
					(mid 18.68805 -60.550044)
					(end 21.150072 -63.012066)
				)
				(arc
					(start 24.45004 -63.012066)
					(mid 26.912062 -60.550044)
					(end 24.45004 -58.088022)
				)
			)
		)
	)
	(zone
		(layers "In2.Cu" "In5.Cu")
		(hatch none 0.5)
		(connect_pads
			(clearance 0)
		)
		(min_thickness 0.25)
		(keepout
			(tracks not_allowed)
			(vias allowed)
			(pads allowed)
			(copperpour not_allowed)
			(footprints allowed)
		)
		(placement
			(enabled no)
			(sheetname "")
		)
		(fill yes
			(thermal_gap 0.5)
			(thermal_bridge_width 0.5)
			(island_removal_mode 0)
		)
		(polygon
			(pts
				(arc
					(start 78.505558 -76.909168)
					(mid 78.122018 -76.525628)
					(end 77.738478 -76.909168)
				)
				(arc
					(start 77.738478 -77.797914)
					(mid 78.120621 -78.181706)
					(end 78.505558 -77.800708)
				)
				(arc
					(start 78.388718 -77.800708)
					(mid 78.122018 -78.06488)
					(end 77.855318 -77.800708)
				)
				(arc
					(start 77.855318 -77.798168)
					(mid 78.122018 -77.531468)
					(end 78.388718 -77.798168)
				)
				(xy 78.505558 -77.798168) (xy 78.505558 -76.911708)
				(arc
					(start 78.388718 -76.911708)
					(mid 78.122018 -77.17588)
					(end 77.855318 -76.911708)
				)
				(arc
					(start 77.855318 -76.909168)
					(mid 78.122018 -76.642468)
					(end 78.388718 -76.909168)
				)
			)
		)
	)
	(zone
		(layers "In2.Cu" "In5.Cu")
		(hatch none 0.5)
		(connect_pads
			(clearance 0)
		)
		(min_thickness 0.25)
		(keepout
			(tracks not_allowed)
			(vias allowed)
			(pads allowed)
			(copperpour not_allowed)
			(footprints allowed)
		)
		(placement
			(enabled no)
			(sheetname "")
		)
		(fill yes
			(thermal_gap 0.5)
			(thermal_bridge_width 0.5)
			(island_removal_mode 0)
		)
		(polygon
			(pts
				(arc
					(start 76.900024 -102.58806)
					(mid 74.438002 -105.050082)
					(end 76.900024 -107.512104)
				)
				(arc
					(start 80.199992 -107.512104)
					(mid 82.662014 -105.050082)
					(end 80.199992 -102.58806)
				)
			)
		)
	)
	(zone
		(layers "In2.Cu" "In5.Cu")
		(hatch none 0.5)
		(connect_pads
			(clearance 0)
		)
		(min_thickness 0.25)
		(keepout
			(tracks not_allowed)
			(vias allowed)
			(pads allowed)
			(copperpour not_allowed)
			(footprints allowed)
		)
		(placement
			(enabled no)
			(sheetname "")
		)
		(fill yes
			(thermal_gap 0.5)
			(thermal_bridge_width 0.5)
			(island_removal_mode 0)
		)
		(polygon
			(pts
				(arc
					(start 201.978006 -71.503032)
					(mid 201.59472 -71.119492)
					(end 201.210926 -71.502524)
				)
				(arc
					(start 201.20991 -72.297036)
					(mid 201.591799 -72.681335)
					(end 201.97699 -72.300338)
				)
				(arc
					(start 201.86015 -72.300338)
					(mid 201.59345 -72.56451)
					(end 201.32675 -72.300338)
				)
				(arc
					(start 201.32675 -72.297798)
					(mid 201.59345 -72.031098)
					(end 201.86015 -72.297798)
				)
				(xy 201.97699 -72.297798) (xy 201.97699 -72.297036) (xy 201.978006 -71.505572)
				(arc
					(start 201.861166 -71.505572)
					(mid 201.594466 -71.769744)
					(end 201.327766 -71.505572)
				)
				(arc
					(start 201.327766 -71.503032)
					(mid 201.594466 -71.236332)
					(end 201.861166 -71.503032)
				)
			)
		)
	)
	(zone
		(layers "In2.Cu" "In5.Cu")
		(hatch none 0.5)
		(connect_pads
			(clearance 0)
		)
		(min_thickness 0.25)
		(keepout
			(tracks not_allowed)
			(vias allowed)
			(pads allowed)
			(copperpour not_allowed)
			(footprints allowed)
		)
		(placement
			(enabled no)
			(sheetname "")
		)
		(fill yes
			(thermal_gap 0.5)
			(thermal_bridge_width 0.5)
			(island_removal_mode 0)
		)
		(polygon
			(pts
				(arc
					(start 201.983086 -66.709036)
					(mid 201.60107 -66.325499)
					(end 201.216006 -66.705988)
				)
				(arc
					(start 201.209656 -67.49923)
					(mid 201.590021 -67.886073)
					(end 201.976736 -67.50558)
				)
				(xy 201.976736 -67.505072)
				(arc
					(start 201.859896 -67.505072)
					(mid 201.593196 -67.769244)
					(end 201.326496 -67.505072)
				)
				(arc
					(start 201.326496 -67.502532)
					(mid 201.593196 -67.235832)
					(end 201.859896 -67.502532)
				)
				(xy 201.976736 -67.502532) (xy 201.983086 -66.712084) (xy 201.983086 -66.711576)
				(arc
					(start 201.866246 -66.711576)
					(mid 201.599546 -66.975748)
					(end 201.332846 -66.711576)
				)
				(arc
					(start 201.332846 -66.709036)
					(mid 201.599546 -66.442336)
					(end 201.866246 -66.709036)
				)
			)
		)
	)
	(zone
		(layers "In2.Cu" "In5.Cu")
		(hatch none 0.5)
		(connect_pads
			(clearance 0)
		)
		(min_thickness 0.25)
		(keepout
			(tracks not_allowed)
			(vias allowed)
			(pads allowed)
			(copperpour not_allowed)
			(footprints allowed)
		)
		(placement
			(enabled no)
			(sheetname "")
		)
		(fill yes
			(thermal_gap 0.5)
			(thermal_bridge_width 0.5)
			(island_removal_mode 0)
		)
		(polygon
			(pts
				(arc
					(start 78.505558 -70.508368)
					(mid 78.122018 -70.124828)
					(end 77.738478 -70.508368)
				)
				(arc
					(start 77.738478 -71.397114)
					(mid 78.120621 -71.780906)
					(end 78.505558 -71.399908)
				)
				(arc
					(start 78.388718 -71.399908)
					(mid 78.122018 -71.66408)
					(end 77.855318 -71.399908)
				)
				(arc
					(start 77.855318 -71.397368)
					(mid 78.122018 -71.130668)
					(end 78.388718 -71.397368)
				)
				(xy 78.505558 -71.397368) (xy 78.505558 -70.510908)
				(arc
					(start 78.388718 -70.510908)
					(mid 78.122018 -70.77508)
					(end 77.855318 -70.510908)
				)
				(arc
					(start 77.855318 -70.508368)
					(mid 78.122018 -70.241668)
					(end 78.388718 -70.508368)
				)
			)
		)
	)
	(zone
		(layers "In2.Cu" "In5.Cu")
		(hatch none 0.5)
		(connect_pads
			(clearance 0)
		)
		(min_thickness 0.25)
		(keepout
			(tracks not_allowed)
			(vias allowed)
			(pads allowed)
			(copperpour not_allowed)
			(footprints allowed)
		)
		(placement
			(enabled no)
			(sheetname "")
		)
		(fill yes
			(thermal_gap 0.5)
			(thermal_bridge_width 0.5)
			(island_removal_mode 0)
		)
		(polygon
			(pts
				(arc
					(start 202.780646 -73.097136)
					(mid 202.66777 -72.825394)
					(end 202.395582 -72.713596)
				)
				(arc
					(start 201.599292 -72.716898)
					(mid 201.217276 -73.101835)
					(end 201.602086 -73.483978)
				)
				(arc
					(start 202.39863 -73.480676)
					(mid 202.667952 -73.368701)
					(end 202.780646 -73.099676)
				)
				(arc
					(start 202.663806 -73.099676)
					(mid 202.398757 -73.363843)
					(end 202.130406 -73.102978)
				)
				(arc
					(start 201.867262 -73.102978)
					(mid 201.600562 -73.36715)
					(end 201.333862 -73.102978)
				)
				(arc
					(start 201.333862 -73.100438)
					(mid 201.600562 -72.833738)
					(end 201.867262 -73.100438)
				)
				(xy 202.130406 -73.100438) (xy 202.130406 -73.099676)
				(arc
					(start 202.130406 -73.097136)
					(mid 202.397106 -72.830436)
					(end 202.663806 -73.097136)
				)
			)
		)
	)
	(zone
		(layers "In2.Cu" "In5.Cu")
		(hatch none 0.5)
		(connect_pads
			(clearance 0)
		)
		(min_thickness 0.25)
		(keepout
			(tracks not_allowed)
			(vias allowed)
			(pads allowed)
			(copperpour not_allowed)
			(footprints allowed)
		)
		(placement
			(enabled no)
			(sheetname "")
		)
		(fill yes
			(thermal_gap 0.5)
			(thermal_bridge_width 0.5)
			(island_removal_mode 0)
		)
		(polygon
			(pts
				(arc
					(start 201.978768 -69.097398)
					(mid 201.58837 -68.720716)
					(end 201.211688 -69.111114)
				)
				(arc
					(start 201.225658 -69.906388)
					(mid 201.61123 -70.283375)
					(end 201.992738 -69.902324)
				)
				(arc
					(start 201.875898 -69.902324)
					(mid 201.609198 -70.166496)
					(end 201.342498 -69.902324)
				)
				(arc
					(start 201.342498 -69.899784)
					(mid 201.609198 -69.633084)
					(end 201.875898 -69.899784)
				)
				(xy 201.992738 -69.899784) (xy 201.992738 -69.892926) (xy 201.979022 -69.106796)
				(arc
					(start 201.861928 -69.106796)
					(mid 201.595228 -69.370968)
					(end 201.328528 -69.106796)
				)
				(arc
					(start 201.328528 -69.104256)
					(mid 201.595228 -68.837556)
					(end 201.861928 -69.104256)
				)
				(xy 201.978768 -69.104256)
			)
		)
	)
	(zone
		(layers "In2.Cu" "In5.Cu")
		(hatch none 0.5)
		(connect_pads
			(clearance 0)
		)
		(min_thickness 0.25)
		(keepout
			(tracks not_allowed)
			(vias allowed)
			(pads allowed)
			(copperpour not_allowed)
			(footprints allowed)
		)
		(placement
			(enabled no)
			(sheetname "")
		)
		(fill yes
			(thermal_gap 0.5)
			(thermal_bridge_width 0.5)
			(island_removal_mode 0)
		)
		(polygon
			(pts
				(arc
					(start 201.599546 -67.911726)
					(mid 201.212197 -68.291329)
					(end 201.591672 -68.678806)
				)
				(arc
					(start 202.39609 -68.68668)
					(mid 202.671655 -68.573818)
					(end 202.78344 -68.297806)
				)
				(arc
					(start 202.6666 -68.297806)
					(mid 202.3999 -68.569893)
					(end 202.1332 -68.297806)
				)
				(arc
					(start 201.862182 -68.297806)
					(mid 201.595482 -68.561978)
					(end 201.328782 -68.297806)
				)
				(arc
					(start 201.328782 -68.295266)
					(mid 201.595482 -68.028566)
					(end 201.862182 -68.295266)
				)
				(arc
					(start 202.1332 -68.295266)
					(mid 202.3999 -68.036324)
					(end 202.6666 -68.295266)
				)
				(arc
					(start 202.78344 -68.295266)
					(mid 202.66972 -68.030446)
					(end 202.40371 -67.9196)
				)
			)
		)
	)
	(zone
		(layers "In2.Cu" "In5.Cu")
		(hatch none 0.5)
		(connect_pads
			(clearance 0)
		)
		(min_thickness 0.25)
		(keepout
			(tracks not_allowed)
			(vias allowed)
			(pads allowed)
			(copperpour not_allowed)
			(footprints allowed)
		)
		(placement
			(enabled no)
			(sheetname "")
		)
		(fill yes
			(thermal_gap 0.5)
			(thermal_bridge_width 0.5)
			(island_removal_mode 0)
		)
		(polygon
			(pts
				(arc
					(start 78.505558 -89.710768)
					(mid 78.122018 -89.327228)
					(end 77.738478 -89.710768)
				)
				(arc
					(start 77.738478 -90.599514)
					(mid 78.120621 -90.983306)
					(end 78.505558 -90.602308)
				)
				(arc
					(start 78.388718 -90.602308)
					(mid 78.122018 -90.86648)
					(end 77.855318 -90.602308)
				)
				(arc
					(start 77.855318 -90.599768)
					(mid 78.122018 -90.333068)
					(end 78.388718 -90.599768)
				)
				(xy 78.505558 -90.599768) (xy 78.505558 -89.713308)
				(arc
					(start 78.388718 -89.713308)
					(mid 78.122018 -89.97748)
					(end 77.855318 -89.713308)
				)
				(arc
					(start 77.855318 -89.710768)
					(mid 78.122018 -89.444068)
					(end 78.388718 -89.710768)
				)
			)
		)
	)
	(zone
		(layers "In2.Cu" "In5.Cu")
		(hatch none 0.5)
		(connect_pads
			(clearance 0)
		)
		(min_thickness 0.25)
		(keepout
			(tracks not_allowed)
			(vias allowed)
			(pads allowed)
			(copperpour not_allowed)
			(footprints allowed)
		)
		(placement
			(enabled no)
			(sheetname "")
		)
		(fill yes
			(thermal_gap 0.5)
			(thermal_bridge_width 0.5)
			(island_removal_mode 0)
		)
		(polygon
			(pts
				(arc
					(start 200.798684 -73.520046)
					(mid 200.41489 -73.903459)
					(end 200.79843 -74.287126)
				)
				(arc
					(start 201.598276 -74.287126)
					(mid 201.86858 -74.175686)
					(end 201.981816 -73.906126)
				)
				(arc
					(start 201.864976 -73.906126)
					(mid 201.598276 -74.170298)
					(end 201.331576 -73.906126)
				)
				(arc
					(start 201.06513 -73.906126)
					(mid 200.79843 -74.170298)
					(end 200.53173 -73.906126)
				)
				(arc
					(start 200.53173 -73.903586)
					(mid 200.79843 -73.636886)
					(end 201.06513 -73.903586)
				)
				(arc
					(start 201.331576 -73.903586)
					(mid 201.598276 -73.636886)
					(end 201.864976 -73.903586)
				)
				(arc
					(start 201.981816 -73.903586)
					(mid 201.86948 -73.632382)
					(end 201.598276 -73.520046)
				)
			)
		)
	)
	(zone
		(layers "In2.Cu" "In5.Cu")
		(hatch none 0.5)
		(connect_pads
			(clearance 0)
		)
		(min_thickness 0.25)
		(keepout
			(tracks not_allowed)
			(vias allowed)
			(pads allowed)
			(copperpour not_allowed)
			(footprints allowed)
		)
		(placement
			(enabled no)
			(sheetname "")
		)
		(fill yes
			(thermal_gap 0.5)
			(thermal_bridge_width 0.5)
			(island_removal_mode 0)
		)
		(polygon
			(pts
				(arc
					(start 201.600054 -75.116182)
					(mid 201.21626 -75.499595)
					(end 201.5998 -75.883262)
				)
				(arc
					(start 202.399646 -75.883262)
					(mid 202.66995 -75.771822)
					(end 202.783186 -75.502262)
				)
				(arc
					(start 202.666346 -75.502262)
					(mid 202.399646 -75.766434)
					(end 202.132946 -75.502262)
				)
				(arc
					(start 201.8665 -75.502262)
					(mid 201.5998 -75.766434)
					(end 201.3331 -75.502262)
				)
				(arc
					(start 201.3331 -75.499722)
					(mid 201.5998 -75.233022)
					(end 201.8665 -75.499722)
				)
				(arc
					(start 202.132946 -75.499722)
					(mid 202.399646 -75.233022)
					(end 202.666346 -75.499722)
				)
				(arc
					(start 202.783186 -75.499722)
					(mid 202.67085 -75.228518)
					(end 202.399646 -75.116182)
				)
			)
		)
	)
	(zone
		(layers "In2.Cu" "In5.Cu")
		(hatch none 0.5)
		(connect_pads
			(clearance 0)
		)
		(min_thickness 0.25)
		(keepout
			(tracks not_allowed)
			(vias allowed)
			(pads allowed)
			(copperpour not_allowed)
			(footprints allowed)
		)
		(placement
			(enabled no)
			(sheetname "")
		)
		(fill yes
			(thermal_gap 0.5)
			(thermal_bridge_width 0.5)
			(island_removal_mode 0)
		)
		(polygon
			(pts
				(arc
					(start 77.667358 -73.708768)
					(mid 77.283818 -73.325228)
					(end 76.900278 -73.708768)
				)
				(arc
					(start 76.900278 -74.597514)
					(mid 77.282421 -74.981306)
					(end 77.667358 -74.600308)
				)
				(arc
					(start 77.550518 -74.600308)
					(mid 77.283818 -74.86448)
					(end 77.017118 -74.600308)
				)
				(arc
					(start 77.017118 -74.597768)
					(mid 77.283818 -74.331068)
					(end 77.550518 -74.597768)
				)
				(xy 77.667358 -74.597768) (xy 77.667358 -73.711308)
				(arc
					(start 77.550518 -73.711308)
					(mid 77.283818 -73.97548)
					(end 77.017118 -73.711308)
				)
				(arc
					(start 77.017118 -73.708768)
					(mid 77.283818 -73.442068)
					(end 77.550518 -73.708768)
				)
			)
		)
	)
	(zone
		(layers "In2.Cu" "In5.Cu")
		(hatch none 0.5)
		(connect_pads
			(clearance 0)
		)
		(min_thickness 0.25)
		(keepout
			(tracks not_allowed)
			(vias allowed)
			(pads allowed)
			(copperpour not_allowed)
			(footprints allowed)
		)
		(placement
			(enabled no)
			(sheetname "")
		)
		(fill yes
			(thermal_gap 0.5)
			(thermal_bridge_width 0.5)
			(island_removal_mode 0)
		)
		(polygon
			(pts
				(arc
					(start 194.757802 -73.899776)
					(mid 194.401313 -73.54164)
					(end 194.041522 -73.896474)
				)
				(arc
					(start 194.03441 -74.698606)
					(mid 194.389248 -75.060048)
					(end 194.75069 -74.70521)
				)
				(xy 194.75069 -74.704448)
				(arc
					(start 194.63385 -74.704448)
					(mid 194.39255 -74.943221)
					(end 194.15125 -74.704448)
				)
				(arc
					(start 194.15125 -74.701908)
					(mid 194.39255 -74.460608)
					(end 194.63385 -74.701908)
				)
				(xy 194.75069 -74.701908) (xy 194.757802 -73.903332) (xy 194.757802 -73.902316)
				(arc
					(start 194.640962 -73.902316)
					(mid 194.399662 -74.141089)
					(end 194.158362 -73.902316)
				)
				(arc
					(start 194.158362 -73.899776)
					(mid 194.399662 -73.658476)
					(end 194.640962 -73.899776)
				)
			)
		)
	)
	(zone
		(layers "In2.Cu" "In5.Cu")
		(hatch none 0.5)
		(connect_pads
			(clearance 0)
		)
		(min_thickness 0.25)
		(keepout
			(tracks not_allowed)
			(vias allowed)
			(pads allowed)
			(copperpour not_allowed)
			(footprints allowed)
		)
		(placement
			(enabled no)
			(sheetname "")
		)
		(fill yes
			(thermal_gap 0.5)
			(thermal_bridge_width 0.5)
			(island_removal_mode 0)
		)
		(polygon
			(pts
				(arc
					(start 192.35801 -73.899776)
					(mid 191.99987 -73.541636)
					(end 191.64173 -73.899776)
				)
				(arc
					(start 191.64173 -74.699622)
					(mid 191.9986 -75.05776)
					(end 192.35801 -74.702162)
				)
				(arc
					(start 192.24117 -74.702162)
					(mid 191.99987 -74.940935)
					(end 191.75857 -74.702162)
				)
				(arc
					(start 191.75857 -74.699622)
					(mid 191.99987 -74.458322)
					(end 192.24117 -74.699622)
				)
				(xy 192.35801 -74.699622) (xy 192.35801 -73.902316)
				(arc
					(start 192.24117 -73.902316)
					(mid 191.99987 -74.141089)
					(end 191.75857 -73.902316)
				)
				(arc
					(start 191.75857 -73.899776)
					(mid 191.99987 -73.658476)
					(end 192.24117 -73.899776)
				)
			)
		)
	)
	(zone
		(layers "In2.Cu" "In5.Cu")
		(hatch none 0.5)
		(connect_pads
			(clearance 0)
		)
		(min_thickness 0.25)
		(keepout
			(tracks not_allowed)
			(vias allowed)
			(pads allowed)
			(copperpour not_allowed)
			(footprints allowed)
		)
		(placement
			(enabled no)
			(sheetname "")
		)
		(fill yes
			(thermal_gap 0.5)
			(thermal_bridge_width 0.5)
			(island_removal_mode 0)
		)
		(polygon
			(pts
				(arc
					(start 195.557902 -73.899776)
					(mid 195.200016 -73.541636)
					(end 194.841622 -73.899268)
				)
				(arc
					(start 194.840352 -74.706988)
					(mid 195.196968 -75.065633)
					(end 195.556632 -74.710036)
				)
				(arc
					(start 195.439792 -74.710036)
					(mid 195.198492 -74.948809)
					(end 194.957192 -74.710036)
				)
				(arc
					(start 194.957192 -74.707496)
					(mid 195.198492 -74.466196)
					(end 195.439792 -74.707496)
				)
				(xy 195.556632 -74.707496) (xy 195.556632 -74.706988) (xy 195.557902 -73.902316)
				(arc
					(start 195.441062 -73.902316)
					(mid 195.199762 -74.141089)
					(end 194.958462 -73.902316)
				)
				(arc
					(start 194.958462 -73.899776)
					(mid 195.199762 -73.658476)
					(end 195.441062 -73.899776)
				)
			)
		)
	)
	(zone
		(layers "In2.Cu" "In5.Cu")
		(hatch none 0.5)
		(connect_pads
			(clearance 0)
		)
		(min_thickness 0.25)
		(keepout
			(tracks not_allowed)
			(vias allowed)
			(pads allowed)
			(copperpour not_allowed)
			(footprints allowed)
		)
		(placement
			(enabled no)
			(sheetname "")
		)
		(fill yes
			(thermal_gap 0.5)
			(thermal_bridge_width 0.5)
			(island_removal_mode 0)
		)
		(polygon
			(pts
				(arc
					(start 197.157848 -73.89622)
					(mid 196.796025 -73.541889)
					(end 196.441568 -73.903586)
				)
				(arc
					(start 196.44995 -74.702162)
					(mid 196.808725 -75.056512)
					(end 197.16623 -74.700892)
				)
				(arc
					(start 197.04939 -74.700892)
					(mid 196.80809 -74.939665)
					(end 196.56679 -74.700892)
				)
				(arc
					(start 196.56679 -74.698352)
					(mid 196.80809 -74.457052)
					(end 197.04939 -74.698352)
				)
				(xy 197.16623 -74.698352) (xy 197.16623 -74.694542) (xy 197.157848 -73.902316)
				(arc
					(start 197.041008 -73.902316)
					(mid 196.799708 -74.141089)
					(end 196.558408 -73.902316)
				)
				(arc
					(start 196.558408 -73.899776)
					(mid 196.799708 -73.658476)
					(end 197.041008 -73.899776)
				)
				(xy 197.157848 -73.899776)
			)
		)
	)
	(zone
		(layers "In2.Cu" "In5.Cu")
		(hatch none 0.5)
		(connect_pads
			(clearance 0)
		)
		(min_thickness 0.25)
		(keepout
			(tracks not_allowed)
			(vias allowed)
			(pads allowed)
			(copperpour not_allowed)
			(footprints allowed)
		)
		(placement
			(enabled no)
			(sheetname "")
		)
		(fill yes
			(thermal_gap 0.5)
			(thermal_bridge_width 0.5)
			(island_removal_mode 0)
		)
		(polygon
			(pts
				(arc
					(start 41.450006 -167.391842)
					(mid 41.450006 -172.607986)
					(end 41.450006 -167.391842)
				)
			)
		)
	)
	(zone
		(layers "In2.Cu" "In5.Cu")
		(hatch none 0.5)
		(connect_pads
			(clearance 0)
		)
		(min_thickness 0.25)
		(keepout
			(tracks not_allowed)
			(vias allowed)
			(pads allowed)
			(copperpour not_allowed)
			(footprints allowed)
		)
		(placement
			(enabled no)
			(sheetname "")
		)
		(fill yes
			(thermal_gap 0.5)
			(thermal_bridge_width 0.5)
			(island_removal_mode 0)
		)
		(polygon
			(pts
				(arc
					(start 78.505558 -83.335368)
					(mid 78.122018 -82.951828)
					(end 77.738478 -83.335368)
				)
				(arc
					(start 77.738478 -84.224114)
					(mid 78.120621 -84.607906)
					(end 78.505558 -84.226908)
				)
				(arc
					(start 78.388718 -84.226908)
					(mid 78.122018 -84.49108)
					(end 77.855318 -84.226908)
				)
				(arc
					(start 77.855318 -84.224368)
					(mid 78.122018 -83.957668)
					(end 78.388718 -84.224368)
				)
				(xy 78.505558 -84.224368) (xy 78.505558 -83.337908)
				(arc
					(start 78.388718 -83.337908)
					(mid 78.122018 -83.60208)
					(end 77.855318 -83.337908)
				)
				(arc
					(start 77.855318 -83.335368)
					(mid 78.122018 -83.068668)
					(end 78.388718 -83.335368)
				)
			)
		)
	)
	(zone
		(layers "In2.Cu" "In5.Cu")
		(hatch none 0.5)
		(connect_pads
			(clearance 0)
		)
		(min_thickness 0.25)
		(keepout
			(tracks not_allowed)
			(vias allowed)
			(pads allowed)
			(copperpour not_allowed)
			(footprints allowed)
		)
		(placement
			(enabled no)
			(sheetname "")
		)
		(fill yes
			(thermal_gap 0.5)
			(thermal_bridge_width 0.5)
			(island_removal_mode 0)
		)
		(polygon
			(pts
				(arc
					(start 197.957948 -73.895712)
					(mid 197.595617 -73.541888)
					(end 197.241668 -73.904094)
				)
				(arc
					(start 197.251066 -74.70394)
					(mid 197.610095 -75.057787)
					(end 197.967346 -74.702162)
				)
				(arc
					(start 197.850506 -74.702162)
					(mid 197.609206 -74.940935)
					(end 197.367906 -74.702162)
				)
				(arc
					(start 197.367906 -74.699622)
					(mid 197.609206 -74.458322)
					(end 197.850506 -74.699622)
				)
				(xy 197.967346 -74.699622) (xy 197.967346 -74.695304) (xy 197.957948 -73.902316)
				(arc
					(start 197.841108 -73.902316)
					(mid 197.599808 -74.141089)
					(end 197.358508 -73.902316)
				)
				(arc
					(start 197.358508 -73.899776)
					(mid 197.599808 -73.658476)
					(end 197.841108 -73.899776)
				)
				(xy 197.957948 -73.899776)
			)
		)
	)
	(zone
		(layers "In2.Cu" "In5.Cu")
		(hatch none 0.5)
		(connect_pads
			(clearance 0)
		)
		(min_thickness 0.25)
		(keepout
			(tracks not_allowed)
			(vias allowed)
			(pads allowed)
			(copperpour not_allowed)
			(footprints allowed)
		)
		(placement
			(enabled no)
			(sheetname "")
		)
		(fill yes
			(thermal_gap 0.5)
			(thermal_bridge_width 0.5)
			(island_removal_mode 0)
		)
		(polygon
			(pts
				(arc
					(start 199.557894 -73.899268)
					(mid 199.199119 -73.54189)
					(end 198.841614 -73.900538)
				)
				(arc
					(start 198.843392 -74.693018)
					(mid 199.200643 -75.050396)
					(end 199.559672 -74.694796)
				)
				(arc
					(start 199.442832 -74.694796)
					(mid 199.201532 -74.933569)
					(end 198.960232 -74.694796)
				)
				(arc
					(start 198.960232 -74.692256)
					(mid 199.201532 -74.450956)
					(end 199.442832 -74.692256)
				)
				(xy 199.559672 -74.692256) (xy 199.559672 -74.691494) (xy 199.557894 -73.902316)
				(arc
					(start 199.441054 -73.902316)
					(mid 199.199754 -74.141089)
					(end 198.958454 -73.902316)
				)
				(arc
					(start 198.958454 -73.899776)
					(mid 199.199754 -73.658476)
					(end 199.441054 -73.899776)
				)
				(xy 199.557894 -73.899776)
			)
		)
	)
	(zone
		(layers "In2.Cu" "In5.Cu")
		(hatch none 0.5)
		(connect_pads
			(clearance 0)
		)
		(min_thickness 0.25)
		(keepout
			(tracks not_allowed)
			(vias allowed)
			(pads allowed)
			(copperpour not_allowed)
			(footprints allowed)
		)
		(placement
			(enabled no)
			(sheetname "")
		)
		(fill yes
			(thermal_gap 0.5)
			(thermal_bridge_width 0.5)
			(island_removal_mode 0)
		)
		(polygon
			(pts
				(arc
					(start 77.658214 -67.322192)
					(mid 77.274674 -66.938652)
					(end 76.891134 -67.322192)
				)
				(arc
					(start 76.891134 -68.211192)
					(mid 77.273404 -68.59473)
					(end 77.658214 -68.213732)
				)
				(arc
					(start 77.541374 -68.213732)
					(mid 77.274674 -68.477904)
					(end 77.007974 -68.213732)
				)
				(arc
					(start 77.007974 -68.211192)
					(mid 77.274674 -67.944492)
					(end 77.541374 -68.211192)
				)
				(xy 77.658214 -68.211192) (xy 77.658214 -67.324732)
				(arc
					(start 77.541374 -67.324732)
					(mid 77.274674 -67.588904)
					(end 77.007974 -67.324732)
				)
				(arc
					(start 77.007974 -67.322192)
					(mid 77.274674 -67.055492)
					(end 77.541374 -67.322192)
				)
			)
		)
	)
	(zone
		(layers "In2.Cu" "In5.Cu")
		(hatch none 0.5)
		(connect_pads
			(clearance 0)
		)
		(min_thickness 0.25)
		(keepout
			(tracks not_allowed)
			(vias allowed)
			(pads allowed)
			(copperpour not_allowed)
			(footprints allowed)
		)
		(placement
			(enabled no)
			(sheetname "")
		)
		(fill yes
			(thermal_gap 0.5)
			(thermal_bridge_width 0.5)
			(island_removal_mode 0)
		)
		(polygon
			(pts
				(arc
					(start 77.667358 -80.109568)
					(mid 77.283818 -79.726028)
					(end 76.900278 -80.109568)
				)
				(arc
					(start 76.900278 -80.998314)
					(mid 77.282421 -81.382106)
					(end 77.667358 -81.001108)
				)
				(arc
					(start 77.550518 -81.001108)
					(mid 77.283818 -81.26528)
					(end 77.017118 -81.001108)
				)
				(arc
					(start 77.017118 -80.998568)
					(mid 77.283818 -80.731868)
					(end 77.550518 -80.998568)
				)
				(xy 77.667358 -80.998568) (xy 77.667358 -80.112108)
				(arc
					(start 77.550518 -80.112108)
					(mid 77.283818 -80.37628)
					(end 77.017118 -80.112108)
				)
				(arc
					(start 77.017118 -80.109568)
					(mid 77.283818 -79.842868)
					(end 77.550518 -80.109568)
				)
			)
		)
	)
	(zone
		(layers "In2.Cu" "In5.Cu")
		(hatch none 0.5)
		(connect_pads
			(clearance 0)
		)
		(min_thickness 0.25)
		(keepout
			(tracks not_allowed)
			(vias allowed)
			(pads allowed)
			(copperpour not_allowed)
			(footprints allowed)
		)
		(placement
			(enabled no)
			(sheetname "")
		)
		(fill yes
			(thermal_gap 0.5)
			(thermal_bridge_width 0.5)
			(island_removal_mode 0)
		)
		(polygon
			(pts
				(arc
					(start 201.594466 -70.319138)
					(mid 201.210164 -70.701789)
					(end 201.592688 -71.086218)
				)
				(arc
					(start 202.40371 -71.087996)
					(mid 202.675137 -70.976199)
					(end 202.788012 -70.705218)
				)
				(arc
					(start 202.671172 -70.705218)
					(mid 202.404472 -70.971157)
					(end 202.137772 -70.705218)
				)
				(arc
					(start 201.86015 -70.705218)
					(mid 201.59345 -70.96939)
					(end 201.32675 -70.705218)
				)
				(arc
					(start 201.32675 -70.702678)
					(mid 201.59345 -70.435978)
					(end 201.86015 -70.702678)
				)
				(arc
					(start 202.137772 -70.702678)
					(mid 202.404472 -70.43775)
					(end 202.671172 -70.702678)
				)
				(arc
					(start 202.788012 -70.702678)
					(mid 202.675319 -70.43289)
					(end 202.405234 -70.320916)
				)
			)
		)
	)
	(zone
		(net "P0V975")
		(layer "In3.Cu")
		(hatch none 0.5)
		(connect_pads
			(clearance 0.5)
		)
		(min_thickness 0.25)
		(fill yes
			(thermal_gap 0.5)
			(thermal_bridge_width 0.5)
			(island_removal_mode 0)
		)
		(polygon
			(pts
				(xy 197.055994 -57.0865) (xy 196.471794 -57.6707) (xy 191.183006 -57.6707) (xy 190.675006 -57.1627)
				(xy 185.752994 -57.1627) (xy 185.3311 -57.584594) (xy 185.3311 -71.955406) (xy 185.829194 -72.4535)
				(xy 190.578994 -72.4535) (xy 191.1731 -73.047606) (xy 191.1731 -76.202794) (xy 186.083194 -81.2927)
				(xy 182.349394 -81.2927) (xy 182.0545 -81.587594) (xy 182.0545 -82.509106) (xy 192.7225 -93.177106)
				(xy 192.7225 -100.537772) (xy 191.721994 -101.538278) (xy 190.196216 -101.538278) (xy 189.8015 -101.932994)
				(xy 189.8015 -111.300006) (xy 192.229994 -113.7285) (xy 207.185006 -113.7285) (xy 208.0895 -112.824006)
				(xy 208.0895 -105.458006) (xy 210.7565 -102.791006) (xy 210.7565 -68.907914) (xy 209.621628 -67.772788)
				(xy 209.2325 -67.389756) (xy 209.2325 -57.0865)
			)
		)
		(polygon
			(pts
				(arc
					(start 199.084692 -88.728296)
					(mid 199.084692 -88.189308)
					(end 198.545704 -88.189308)
				)
				(arc
					(start 197.922134 -88.813132)
					(mid 197.915055 -89.354246)
					(end 198.456296 -89.356692)
				)
			)
		)
		(polygon
			(pts
				(arc
					(start 194.720464 -88.652096)
					(mid 194.720464 -88.113108)
					(end 194.181476 -88.113108)
				)
				(arc
					(start 193.557906 -88.736932)
					(mid 193.550827 -89.278046)
					(end 194.092068 -89.280492)
				)
			)
		)
		(polygon
			(pts
				(arc
					(start 191.998092 -86.950296)
					(mid 191.998092 -86.411308)
					(end 191.459104 -86.411308)
				)
				(arc
					(start 190.835534 -87.035132)
					(mid 190.828455 -87.576246)
					(end 191.369696 -87.578692)
				)
			)
		)
		(polygon
			(pts
				(arc
					(start 202.107292 -85.731096)
					(mid 202.107292 -85.192108)
					(end 201.568304 -85.192108)
				)
				(arc
					(start 200.944734 -85.815932)
					(mid 200.937655 -86.357046)
					(end 201.478896 -86.359492)
				)
			)
		)
		(polygon
			(pts
				(arc
					(start 197.793864 -85.604096)
					(mid 197.793864 -85.065108)
					(end 197.254876 -85.065108)
				)
				(arc
					(start 196.631306 -85.688932)
					(mid 196.624227 -86.230046)
					(end 197.165468 -86.232492)
				)
			)
		)
		(polygon
			(pts
				(arc
					(start 204.698092 -85.146896)
					(mid 204.698092 -84.607908)
					(end 204.159104 -84.607908)
				)
				(arc
					(start 203.535534 -85.231732)
					(mid 203.528455 -85.772846)
					(end 204.069696 -85.775292)
				)
			)
		)
		(polygon
			(pts
				(arc
					(start 190.448692 -84.156296)
					(mid 190.448692 -83.617308)
					(end 189.909704 -83.617308)
				)
				(arc
					(start 189.286134 -84.241132)
					(mid 189.279055 -84.782246)
					(end 189.820296 -84.784692)
				)
			)
		)
		(polygon
			(pts
				(arc
					(start 194.944492 -83.927696)
					(mid 194.944492 -83.388708)
					(end 194.405504 -83.388708)
				)
				(arc
					(start 193.781934 -84.012532)
					(mid 193.774855 -84.553646)
					(end 194.316096 -84.556092)
				)
			)
		)
		(polygon
			(pts
				(arc
					(start 202.399646 -75.883262)
					(mid 202.783186 -75.499722)
					(end 202.399646 -75.116182)
				)
				(arc
					(start 201.599546 -75.116182)
					(mid 201.21626 -75.499849)
					(end 201.5998 -75.883262)
				)
			)
		)
		(polygon
			(pts
				(arc
					(start 200.357994 -73.899268)
					(mid 199.999219 -73.54189)
					(end 199.641714 -73.900538)
				)
				(xy 199.643492 -74.691494) (xy 199.643492 -74.692256)
				(arc
					(start 199.643492 -74.695558)
					(mid 200.002394 -75.052936)
					(end 200.359772 -74.694034)
				)
				(xy 200.357994 -73.900538)
			)
		)
		(polygon
			(pts
				(arc
					(start 199.557894 -73.899268)
					(mid 199.199119 -73.54189)
					(end 198.841614 -73.900538)
				)
				(arc
					(start 198.843392 -74.693018)
					(mid 199.202294 -75.050396)
					(end 199.559672 -74.691494)
				)
				(xy 199.557894 -73.900538) (xy 199.557894 -73.899776)
			)
		)
		(polygon
			(pts
				(arc
					(start 195.557902 -73.900538)
					(mid 195.200397 -73.54189)
					(end 194.841622 -73.899268)
				)
				(xy 194.841622 -73.899776) (xy 194.841622 -73.903332) (xy 194.840352 -74.70521)
				(arc
					(start 194.840352 -74.706988)
					(mid 195.197984 -75.065636)
					(end 195.556632 -74.708004)
				)
				(xy 195.556632 -74.706988)
			)
		)
		(polygon
			(pts
				(arc
					(start 194.757802 -73.903332)
					(mid 194.403091 -73.541891)
					(end 194.041522 -73.896474)
				)
				(arc
					(start 194.03441 -74.698606)
					(mid 194.389248 -75.060048)
					(end 194.75069 -74.70521)
				)
			)
		)
		(polygon
			(pts
				(arc
					(start 197.157848 -73.89622)
					(mid 196.796025 -73.541889)
					(end 196.441568 -73.903586)
				)
				(arc
					(start 196.44995 -74.702162)
					(mid 196.8119 -75.056492)
					(end 197.16623 -74.694542)
				)
			)
		)
		(polygon
			(pts
				(arc
					(start 197.957948 -73.895712)
					(mid 197.595617 -73.541888)
					(end 197.241668 -73.904094)
				)
				(arc
					(start 197.251066 -74.70394)
					(mid 197.613524 -75.057762)
					(end 197.967346 -74.695304)
				)
			)
		)
		(polygon
			(pts
				(arc
					(start 192.35801 -73.899522)
					(mid 191.999743 -73.541636)
					(end 191.64173 -73.899776)
				)
				(arc
					(start 191.64173 -74.699622)
					(mid 191.99987 -75.057762)
					(end 192.35801 -74.699622)
				)
			)
		)
		(polygon
			(pts
				(arc
					(start 193.157856 -73.90003)
					(mid 192.799716 -73.541636)
					(end 192.441576 -73.90003)
				)
				(xy 192.44183 -74.699622)
				(arc
					(start 192.44183 -74.699876)
					(mid 192.800097 -75.058016)
					(end 193.15811 -74.699622)
				)
			)
		)
		(polygon
			(pts
				(arc
					(start 201.598276 -74.287126)
					(mid 201.981816 -73.903586)
					(end 201.598276 -73.520046)
				)
				(arc
					(start 200.798176 -73.520046)
					(mid 200.41489 -73.903713)
					(end 200.79843 -74.287126)
				)
			)
		)
		(polygon
			(pts
				(arc
					(start 202.39863 -73.480676)
					(mid 202.780646 -73.095612)
					(end 202.395582 -72.713596)
				)
				(arc
					(start 201.599292 -72.716898)
					(mid 201.217276 -73.101835)
					(end 201.602086 -73.483978)
				)
			)
		)
		(polygon
			(pts
				(arc
					(start 201.978006 -71.50354)
					(mid 201.594974 -71.119492)
					(end 201.210926 -71.502524)
				)
				(arc
					(start 201.20991 -72.297036)
					(mid 201.592815 -72.681338)
					(end 201.97699 -72.298306)
				)
				(xy 201.97699 -72.297544) (xy 201.97699 -72.297036)
			)
		)
		(polygon
			(pts
				(arc
					(start 201.594466 -70.319138)
					(mid 201.210164 -70.701789)
					(end 201.592688 -71.086218)
				)
				(arc
					(start 202.40371 -71.087996)
					(mid 202.788012 -70.705218)
					(end 202.405234 -70.320916)
				)
			)
		)
		(polygon
			(pts
				(arc
					(start 201.978768 -69.097398)
					(mid 201.58837 -68.720716)
					(end 201.211688 -69.111114)
				)
				(arc
					(start 201.225658 -69.906388)
					(mid 201.615929 -70.283322)
					(end 201.992738 -69.892926)
				)
			)
		)
		(polygon
			(pts
				(arc
					(start 201.599546 -67.911726)
					(mid 201.212197 -68.291329)
					(end 201.591672 -68.678806)
				)
				(arc
					(start 202.39609 -68.68668)
					(mid 202.78344 -68.30695)
					(end 202.40371 -67.9196)
				)
			)
		)
		(polygon
			(pts
				(arc
					(start 201.983086 -66.712084)
					(mid 201.602594 -66.325496)
					(end 201.216006 -66.705988)
				)
				(arc
					(start 201.209656 -67.49923)
					(mid 201.590021 -67.886073)
					(end 201.976736 -67.50558)
				)
			)
		)
	)
	(zone
		(layer "In3.Cu")
		(hatch none 0.5)
		(connect_pads
			(clearance 0)
		)
		(min_thickness 0.25)
		(keepout
			(tracks not_allowed)
			(vias allowed)
			(pads allowed)
			(copperpour not_allowed)
			(footprints allowed)
		)
		(placement
			(enabled no)
			(sheetname "")
		)
		(fill
			(thermal_gap 0.5)
			(thermal_bridge_width 0.5)
			(island_removal_mode 0)
		)
		(polygon
			(pts
				(arc
					(start 41.450006 -166.249858)
					(mid 41.450006 -173.74997)
					(end 41.450006 -166.249858)
				)
			)
		)
	)
	(zone
		(net "P3V3_STBY")
		(layer "In3.Cu")
		(hatch none 0.5)
		(connect_pads
			(clearance 0.5)
		)
		(min_thickness 0.25)
		(fill yes
			(thermal_gap 0.5)
			(thermal_bridge_width 0.5)
			(island_removal_mode 0)
		)
		(polygon
			(pts
				(xy 94.820994 -47.1805) (xy 93.5355 -48.465994) (xy 93.5355 -51.640994) (xy 92.978986 -52.197508)
				(xy 84.508594 -52.197508) (xy 84.2391 -52.467002) (xy 84.2391 -96.944942) (xy 88.7349 -101.440742)
				(xy 88.7349 -106.606594) (xy 80.088994 -115.2525) (xy 16.080994 -115.2525) (xy 11.7475 -119.585994)
				(xy 11.7475 -126.260606) (xy 12.042394 -126.5555) (xy 32.888174 -126.5555) (xy 35.48888 -129.156206)
				(xy 35.48888 -131.051046) (xy 37.26434 -132.826506) (xy 37.26434 -137.061194) (xy 37.23132 -137.094214)
				(xy 40.538146 -140.40104) (xy 43.781726 -140.40104) (xy 44.3484 -140.967714) (xy 44.3484 -144.401794)
				(xy 45.04436 -145.097754) (xy 45.04436 -147.487386) (xy 43.51528 -149.016466) (xy 43.51528 -150.057866)
				(xy 43.174666 -150.39848) (xy 40.301926 -150.39848) (xy 39.8018 -150.898606) (xy 39.8018 -151.546306)
				(xy 39.8399 -151.584406) (xy 39.8399 -151.742394) (xy 36.604194 -154.9781) (xy 28.699206 -154.9781)
				(xy 28.369006 -154.6479) (xy 26.012394 -154.6479) (xy 25.7048 -154.955494) (xy 25.7048 -159.641794)
				(xy 24.386794 -160.9598) (xy 11.856974 -160.9598) (xy 11.844274 -160.9725) (xy 11.7475 -161.069274)
				(xy 11.7475 -169.720006) (xy 13.185394 -171.1579) (xy 13.611606 -171.1579) (xy 13.764006 -171.0055)
				(xy 22.938994 -171.0055) (xy 25.351994 -173.4185) (xy 31.701994 -173.4185) (xy 37.884354 -179.60086)
				(xy 38.882574 -179.60086) (xy 39.7383 -180.456586) (xy 39.7383 -181.454806) (xy 46.433994 -188.1505)
				(xy 73.936606 -188.1505) (xy 76.349606 -185.7375) (xy 79.804006 -185.7375) (xy 80.7085 -184.833006)
				(xy 80.7085 -178.485546) (xy 83.40598 -175.788066) (xy 83.40598 -171.432474) (xy 80.947006 -168.9735)
				(xy 78.026006 -168.9735) (xy 77.645006 -168.5925) (xy 76.121006 -168.5925) (xy 75.6285 -168.099994)
				(xy 75.6285 -165.021006) (xy 76.502006 -164.1475) (xy 93.083126 -164.1475) (xy 95.9866 -161.244026)
				(xy 95.9866 -157.139386) (xy 97.030286 -156.0957) (xy 97.947226 -156.0957) (xy 98.2345 -155.808426)
				(xy 98.2345 -146.255994) (xy 96.8375 -144.858994) (xy 96.8375 -135.684006) (xy 97.4725 -135.049006)
				(xy 97.4725 -47.627794) (xy 97.025206 -47.1805)
			)
		)
		(polygon
			(pts
				(arc
					(start 85.367368 -91.306396)
					(mid 84.983828 -90.922856)
					(end 84.600288 -91.306396)
				)
				(arc
					(start 84.600288 -92.19565)
					(mid 84.983955 -92.578936)
					(end 85.367368 -92.195396)
				)
			)
		)
		(polygon
			(pts
				(arc
					(start 85.367368 -84.904834)
					(mid 84.983828 -84.521294)
					(end 84.600288 -84.904834)
				)
				(arc
					(start 84.600288 -85.794088)
					(mid 84.983955 -86.177374)
					(end 85.367368 -85.793834)
				)
			)
		)
		(polygon
			(pts
				(arc
					(start 85.367368 -78.504796)
					(mid 84.983828 -78.121256)
					(end 84.600288 -78.504796)
				)
				(arc
					(start 84.600288 -79.39405)
					(mid 84.983955 -79.777336)
					(end 85.367368 -79.393796)
				)
			)
		)
		(polygon
			(pts
				(arc
					(start 85.367368 -72.080882)
					(mid 84.983701 -71.697596)
					(end 84.600288 -72.081136)
				)
				(arc
					(start 84.600288 -72.970136)
					(mid 84.983828 -73.353676)
					(end 85.367368 -72.970136)
				)
			)
		)
	)
	(zone
		(net "GND")
		(layer "In3.Cu")
		(hatch none 0.5)
		(connect_pads
			(clearance 0.5)
		)
		(min_thickness 0.25)
		(fill yes
			(thermal_gap 0.5)
			(thermal_bridge_width 0.5)
			(island_removal_mode 0)
		)
		(polygon
			(pts
				(xy 146.0373 -125.5395) (xy 146.0373 -125.605794) (xy 145.56994 -126.073154) (xy 145.56994 -183.700166)
				(xy 150.085044 -192.73012) (xy 229.214934 -192.73012) (xy 233.730038 -183.700166) (xy 233.730038 -158.358332)
				(xy 233.534712 -158.163006) (xy 175.549306 -158.163006) (xy 164.0967 -146.7104) (xy 164.0967 -125.986794)
				(xy 163.649406 -125.5395)
			)
		)
	)
	(zone
		(net "P1V2_STBY")
		(layer "In3.Cu")
		(hatch none 0.5)
		(connect_pads
			(clearance 0.5)
		)
		(min_thickness 0.25)
		(fill yes
			(thermal_gap 0.5)
			(thermal_bridge_width 0.5)
			(island_removal_mode 0)
		)
		(polygon
			(pts
				(xy 12.042394 -126.9365) (xy 11.7475 -127.231394) (xy 11.7475 -160.431226) (xy 11.895074 -160.5788)
				(xy 24.228806 -160.5788) (xy 25.3238 -159.483806) (xy 25.3238 -154.797506) (xy 25.854406 -154.2669)
				(xy 28.526994 -154.2669) (xy 28.857194 -154.5971) (xy 36.446206 -154.5971) (xy 39.497 -151.546306)
				(xy 39.497 -150.772114) (xy 40.175434 -150.09368) (xy 43.048174 -150.09368) (xy 43.21048 -149.931374)
				(xy 43.21048 -148.889974) (xy 44.73956 -147.360894) (xy 44.73956 -145.224246) (xy 44.0436 -144.528286)
				(xy 44.0436 -141.094206) (xy 43.655234 -140.70584) (xy 40.411654 -140.70584) (xy 36.92144 -137.215626)
				(xy 36.92144 -137.099294) (xy 36.88334 -137.061194) (xy 36.88334 -132.984494) (xy 35.10788 -131.209034)
				(xy 35.10788 -129.314194) (xy 32.730186 -126.9365)
			)
		)
	)
	(zone
		(net "GND")
		(layer "In3.Cu")
		(hatch none 0.5)
		(connect_pads
			(clearance 0.5)
		)
		(min_thickness 0.25)
		(fill yes
			(thermal_gap 0.5)
			(thermal_bridge_width 0.5)
			(island_removal_mode 0)
		)
		(polygon
			(pts
				(xy 113.540794 -17.1577) (xy 104.9655 -25.732994) (xy 104.9655 -45.544994) (xy 104.5337 -45.976794)
				(arc
					(start 104.5337 -46.261782)
					(mid 105.017523 -46.430077)
					(end 105.43286 -46.729904)
				)
				(xy 121.116852 -46.729904) (xy 121.116852 -17.368774) (xy 120.905778 -17.1577)
			)
		)
		(polygon
			(pts
				(arc
					(start 118.385082 -36.799774)
					(mid 117.899815 -36.314888)
					(end 117.414802 -36.800028)
				)
				(arc
					(start 117.414802 -38.200076)
					(mid 117.899942 -38.685216)
					(end 118.385082 -38.200076)
				)
			)
		)
		(polygon
			(pts
				(arc
					(start 114.78514 -36.799774)
					(mid 114.299873 -36.314888)
					(end 113.81486 -36.800028)
				)
				(arc
					(start 113.81486 -38.200076)
					(mid 114.3 -38.685216)
					(end 114.78514 -38.200076)
				)
			)
		)
		(polygon
			(pts
				(arc
					(start 111.185198 -36.799774)
					(mid 110.699931 -36.314888)
					(end 110.214918 -36.800028)
				)
				(arc
					(start 110.214918 -38.200076)
					(mid 110.700058 -38.685216)
					(end 111.185198 -38.200076)
				)
			)
		)
		(polygon
			(pts
				(arc
					(start 107.585002 -36.799774)
					(mid 107.099735 -36.314888)
					(end 106.614722 -36.800028)
				)
				(arc
					(start 106.614722 -38.200076)
					(mid 107.099862 -38.685216)
					(end 107.585002 -38.200076)
				)
			)
		)
		(polygon
			(pts
				(arc
					(start 120.18518 -35.599878)
					(mid 119.699913 -35.114992)
					(end 119.2149 -35.600132)
				)
				(arc
					(start 119.2149 -37.00018)
					(mid 119.70004 -37.48532)
					(end 120.18518 -37.00018)
				)
			)
		)
		(polygon
			(pts
				(arc
					(start 116.584984 -35.599878)
					(mid 116.099717 -35.114992)
					(end 115.614704 -35.600132)
				)
				(arc
					(start 115.614704 -37.00018)
					(mid 116.099844 -37.48532)
					(end 116.584984 -37.00018)
				)
			)
		)
		(polygon
			(pts
				(arc
					(start 112.985042 -35.599878)
					(mid 112.499775 -35.114992)
					(end 112.014762 -35.600132)
				)
				(arc
					(start 112.014762 -37.00018)
					(mid 112.499902 -37.48532)
					(end 112.985042 -37.00018)
				)
			)
		)
		(polygon
			(pts
				(arc
					(start 109.3851 -35.599878)
					(mid 108.899833 -35.114992)
					(end 108.41482 -35.600132)
				)
				(arc
					(start 108.41482 -37.00018)
					(mid 108.89996 -37.48532)
					(end 109.3851 -37.00018)
				)
			)
		)
		(polygon
			(pts
				(arc
					(start 118.385082 -33.199832)
					(mid 117.899815 -32.714946)
					(end 117.414802 -33.200086)
				)
				(arc
					(start 117.414802 -34.600134)
					(mid 117.899942 -35.085274)
					(end 118.385082 -34.600134)
				)
			)
		)
		(polygon
			(pts
				(arc
					(start 114.78514 -33.199832)
					(mid 114.299873 -32.714946)
					(end 113.81486 -33.200086)
				)
				(arc
					(start 113.81486 -34.600134)
					(mid 114.3 -35.085274)
					(end 114.78514 -34.600134)
				)
			)
		)
		(polygon
			(pts
				(arc
					(start 111.185198 -33.199832)
					(mid 110.699931 -32.714946)
					(end 110.214918 -33.200086)
				)
				(arc
					(start 110.214918 -34.600134)
					(mid 110.700058 -35.085274)
					(end 111.185198 -34.600134)
				)
			)
		)
		(polygon
			(pts
				(arc
					(start 107.585002 -33.199832)
					(mid 107.099735 -32.714946)
					(end 106.614722 -33.200086)
				)
				(arc
					(start 106.614722 -34.600134)
					(mid 107.099862 -35.085274)
					(end 107.585002 -34.600134)
				)
			)
		)
		(polygon
			(pts
				(arc
					(start 120.18518 -31.999936)
					(mid 119.699913 -31.51505)
					(end 119.2149 -32.00019)
				)
				(arc
					(start 119.2149 -33.399984)
					(mid 119.70004 -33.885124)
					(end 120.18518 -33.399984)
				)
			)
		)
		(polygon
			(pts
				(arc
					(start 116.584984 -31.999936)
					(mid 116.099717 -31.51505)
					(end 115.614704 -32.00019)
				)
				(arc
					(start 115.614704 -33.399984)
					(mid 116.099844 -33.885124)
					(end 116.584984 -33.399984)
				)
			)
		)
		(polygon
			(pts
				(arc
					(start 112.985042 -31.999936)
					(mid 112.499775 -31.51505)
					(end 112.014762 -32.00019)
				)
				(arc
					(start 112.014762 -33.399984)
					(mid 112.499902 -33.885124)
					(end 112.985042 -33.399984)
				)
			)
		)
		(polygon
			(pts
				(arc
					(start 109.3851 -31.999936)
					(mid 108.899833 -31.51505)
					(end 108.41482 -32.00019)
				)
				(arc
					(start 108.41482 -33.399984)
					(mid 108.89996 -33.885124)
					(end 109.3851 -33.399984)
				)
			)
		)
	)
	(zone
		(net "GND")
		(layer "In3.Cu")
		(hatch none 0.5)
		(connect_pads
			(clearance 0.5)
		)
		(min_thickness 0.25)
		(fill yes
			(thermal_gap 0.5)
			(thermal_bridge_width 0.5)
			(island_removal_mode 0)
		)
		(polygon
			(pts
				(xy 151.208994 -11.2395) (xy 150.8125 -11.635994) (xy 150.8125 -39.443406) (xy 151.310594 -39.9415)
				(xy 210.321906 -39.9415) (xy 210.7565 -39.506906) (xy 210.7565 -29.923994) (xy 197.456806 -16.6243)
				(xy 193.418206 -16.6243) (xy 188.033406 -11.2395)
			)
		)
		(polygon
			(pts
				(arc
					(start 182.663592 -29.328618)
					(mid 182.47589 -28.684976)
					(end 181.83352 -28.877006)
				)
				(arc
					(start 181.083458 -30.277054)
					(mid 181.277006 -30.916626)
					(end 181.916578 -30.723078)
				)
			)
		)
		(polygon
			(pts
				(arc
					(start 180.413406 -29.328618)
					(mid 180.225704 -28.684976)
					(end 179.583334 -28.877006)
				)
				(arc
					(start 178.833526 -30.277054)
					(mid 179.027074 -30.916626)
					(end 179.666646 -30.723078)
				)
			)
		)
		(polygon
			(pts
				(arc
					(start 162.663632 -29.328618)
					(mid 162.47593 -28.684976)
					(end 161.83356 -28.877006)
				)
				(arc
					(start 161.083498 -30.277054)
					(mid 161.277046 -30.916626)
					(end 161.916618 -30.723078)
				)
			)
		)
		(polygon
			(pts
				(arc
					(start 160.413446 -29.328618)
					(mid 160.225744 -28.684976)
					(end 159.583374 -28.877006)
				)
				(arc
					(start 158.833566 -30.277054)
					(mid 159.027114 -30.916626)
					(end 159.666686 -30.723078)
				)
			)
		)
		(polygon
			(pts
				(arc
					(start 162.663632 -25.528524)
					(mid 162.47593 -24.884882)
					(end 161.83356 -25.076912)
				)
				(arc
					(start 161.083498 -26.47696)
					(mid 161.277046 -27.116532)
					(end 161.916618 -26.922984)
				)
			)
		)
		(polygon
			(pts
				(arc
					(start 160.413446 -25.528524)
					(mid 160.225744 -24.884882)
					(end 159.583374 -25.076912)
				)
				(arc
					(start 158.833566 -26.47696)
					(mid 159.027114 -27.116532)
					(end 159.666686 -26.922984)
				)
			)
		)
		(polygon
			(pts
				(arc
					(start 180.43398 -25.543764)
					(mid 180.239312 -24.863383)
					(end 179.560982 -25.064974)
				)
				(arc
					(start 178.811174 -26.465022)
					(mid 179.015136 -27.138884)
					(end 179.688998 -26.934922)
				)
			)
		)
		(polygon
			(pts
				(arc
					(start 182.684166 -25.543764)
					(mid 182.489596 -24.863437)
					(end 181.811168 -25.06472)
				)
				(arc
					(start 181.061106 -26.464768)
					(mid 181.264814 -27.138884)
					(end 181.93893 -26.935176)
				)
			)
		)
		(polygon
			(pts
				(arc
					(start 182.666386 -21.72335)
					(mid 182.473247 -21.083725)
					(end 181.833774 -21.277072)
				)
				(xy 181.831488 -21.275802) (xy 181.081426 -22.675596)
				(arc
					(start 181.083712 -22.676866)
					(mid 181.277006 -23.316184)
					(end 181.916324 -23.12289)
				)
				(xy 181.91861 -23.12416) (xy 182.668672 -21.72462) (xy 182.668418 -21.724366)
			)
		)
		(polygon
			(pts
				(arc
					(start 162.666426 -21.72335)
					(mid 162.473287 -21.083725)
					(end 161.833814 -21.277072)
				)
				(xy 161.831528 -21.275802) (xy 161.081466 -22.675596)
				(arc
					(start 161.083752 -22.676866)
					(mid 161.277046 -23.316184)
					(end 161.916364 -23.12289)
				)
				(xy 161.91865 -23.12416) (xy 162.668712 -21.72462) (xy 162.668458 -21.724366)
			)
		)
		(polygon
			(pts
				(arc
					(start 180.416454 -21.723096)
					(mid 180.222906 -21.083524)
					(end 179.583334 -21.277072)
				)
				(arc
					(start 178.836574 -22.671278)
					(mid 179.024276 -23.31492)
					(end 179.666646 -23.12289)
				)
			)
		)
		(polygon
			(pts
				(arc
					(start 160.416494 -21.723096)
					(mid 160.222946 -21.083524)
					(end 159.583374 -21.277072)
				)
				(arc
					(start 158.836614 -22.671278)
					(mid 159.024316 -23.31492)
					(end 159.666686 -23.12289)
				)
			)
		)
		(polygon
			(pts
				(arc
					(start 182.663592 -17.92859)
					(mid 182.47589 -17.284948)
					(end 181.83352 -17.476978)
				)
				(arc
					(start 181.083458 -18.877026)
					(mid 181.277006 -19.516598)
					(end 181.916578 -19.32305)
				)
			)
		)
		(polygon
			(pts
				(arc
					(start 180.413406 -17.92859)
					(mid 180.225704 -17.284948)
					(end 179.583334 -17.476978)
				)
				(arc
					(start 178.833526 -18.877026)
					(mid 179.027074 -19.516598)
					(end 179.666646 -19.32305)
				)
			)
		)
		(polygon
			(pts
				(arc
					(start 162.663632 -17.92859)
					(mid 162.47593 -17.284948)
					(end 161.83356 -17.476978)
				)
				(arc
					(start 161.083498 -18.877026)
					(mid 161.277046 -19.516598)
					(end 161.916618 -19.32305)
				)
			)
		)
		(polygon
			(pts
				(arc
					(start 160.413446 -17.92859)
					(mid 160.225744 -17.284948)
					(end 159.583374 -17.476978)
				)
				(arc
					(start 158.833566 -18.877026)
					(mid 159.027114 -19.516598)
					(end 159.666686 -19.32305)
				)
			)
		)
	)
	(zone
		(net "GND")
		(layer "In3.Cu")
		(hatch none 0.5)
		(connect_pads
			(clearance 0.5)
		)
		(min_thickness 0.25)
		(fill yes
			(thermal_gap 0.5)
			(thermal_bridge_width 0.5)
			(island_removal_mode 0)
		)
		(polygon
			(pts
				(xy 135.88365 -30.014672) (xy 135.248142 -30.65018) (xy 135.248142 -46.729904)
				(arc
					(start 142.567152 -46.729904)
					(mid 143.528345 -46.251001)
					(end 144.5895 -46.41596)
				)
				(xy 144.5895 -30.151578) (xy 144.452594 -30.014672)
			)
		)
		(polygon
			(pts
				(arc
					(start 139.984988 -36.799774)
					(mid 139.499721 -36.314888)
					(end 139.014708 -36.800028)
				)
				(arc
					(start 139.014708 -38.200076)
					(mid 139.499848 -38.685216)
					(end 139.984988 -38.200076)
				)
			)
		)
		(polygon
			(pts
				(arc
					(start 136.385046 -36.799774)
					(mid 135.899779 -36.314888)
					(end 135.414766 -36.800028)
				)
				(arc
					(start 135.414766 -38.200076)
					(mid 135.899906 -38.685216)
					(end 136.385046 -38.200076)
				)
			)
		)
		(polygon
			(pts
				(arc
					(start 141.785086 -35.599878)
					(mid 141.299819 -35.114992)
					(end 140.814806 -35.600132)
				)
				(arc
					(start 140.814806 -37.00018)
					(mid 141.299946 -37.48532)
					(end 141.785086 -37.00018)
				)
			)
		)
		(polygon
			(pts
				(arc
					(start 138.185144 -35.599878)
					(mid 137.699877 -35.114992)
					(end 137.214864 -35.600132)
				)
				(arc
					(start 137.214864 -37.00018)
					(mid 137.700004 -37.48532)
					(end 138.185144 -37.00018)
				)
			)
		)
		(polygon
			(pts
				(arc
					(start 139.984988 -33.199832)
					(mid 139.499721 -32.714946)
					(end 139.014708 -33.200086)
				)
				(arc
					(start 139.014708 -34.600134)
					(mid 139.499848 -35.085274)
					(end 139.984988 -34.600134)
				)
			)
		)
		(polygon
			(pts
				(arc
					(start 136.385046 -33.199832)
					(mid 135.899779 -32.714946)
					(end 135.414766 -33.200086)
				)
				(arc
					(start 135.414766 -34.600134)
					(mid 135.899906 -35.085274)
					(end 136.385046 -34.600134)
				)
			)
		)
		(polygon
			(pts
				(arc
					(start 141.785086 -31.999936)
					(mid 141.299819 -31.51505)
					(end 140.814806 -32.00019)
				)
				(arc
					(start 140.814806 -33.399984)
					(mid 141.299946 -33.885124)
					(end 141.785086 -33.399984)
				)
			)
		)
		(polygon
			(pts
				(arc
					(start 138.185144 -31.999936)
					(mid 137.699877 -31.51505)
					(end 137.214864 -32.00019)
				)
				(arc
					(start 137.214864 -33.399984)
					(mid 137.700004 -33.885124)
					(end 138.185144 -33.399984)
				)
			)
		)
	)
	(zone
		(net "P1V8")
		(layer "In3.Cu")
		(hatch none 0.5)
		(connect_pads
			(clearance 0.5)
		)
		(min_thickness 0.25)
		(fill yes
			(thermal_gap 0.5)
			(thermal_bridge_width 0.5)
			(island_removal_mode 0)
		)
		(polygon
			(pts
				(xy 151.310594 -40.3225) (xy 150.827994 -40.8051) (xy 150.8125 -40.8051) (xy 150.8125 -75.105006)
				(xy 165.7985 -90.091006) (xy 165.7985 -113.456466) (xy 166.248334 -113.9063) (xy 175.892206 -113.9063)
				(xy 176.4665 -113.332006) (xy 176.4665 -105.585006) (xy 180.894228 -101.157278) (xy 189.022228 -101.157278)
				(xy 189.024006 -101.1555) (xy 189.181994 -101.1555) (xy 189.183772 -101.157278) (xy 190.038228 -101.157278)
				(xy 190.040006 -101.1555) (xy 190.197994 -101.1555) (xy 190.199772 -101.157278) (xy 191.564006 -101.157278)
				(xy 192.3415 -100.379784) (xy 192.3415 -93.335094) (xy 181.6735 -82.667094) (xy 181.6735 -81.429606)
				(xy 182.191406 -80.9117) (xy 185.925206 -80.9117) (xy 190.7921 -76.044806) (xy 190.7921 -73.205594)
				(xy 190.421006 -72.8345) (xy 185.671206 -72.8345) (xy 184.9501 -72.113394) (xy 184.9501 -57.426606)
				(xy 185.595006 -56.7817) (xy 190.832994 -56.7817) (xy 191.340994 -57.2897) (xy 196.313806 -57.2897)
				(xy 196.898006 -56.7055) (xy 209.420206 -56.7055) (xy 210.7565 -55.369206) (xy 210.7565 -40.833294)
				(xy 210.245706 -40.3225)
			)
		)
	)
	(zone
		(net "GND")
		(layer "In3.Cu")
		(hatch none 0.5)
		(connect_pads
			(clearance 0.5)
		)
		(min_thickness 0.25)
		(fill yes
			(thermal_gap 0.5)
			(thermal_bridge_width 0.5)
			(island_removal_mode 0)
		)
		(polygon
			(pts
				(xy 1.507744 -182.93715) (xy 1.27 -183.174894) (xy 1.27 -183.700166) (xy 5.785104 -192.73012) (xy 28.351226 -192.73012)
				(xy 24.0665 -188.445394) (xy 24.0665 -185.6105) (xy 15.91691 -185.6105) (xy 13.24356 -182.93715)
			)
		)
	)
	(zone
		(layer "In3.Cu")
		(hatch none 0.5)
		(connect_pads
			(clearance 0)
		)
		(min_thickness 0.25)
		(keepout
			(tracks not_allowed)
			(vias allowed)
			(pads allowed)
			(copperpour not_allowed)
			(footprints allowed)
		)
		(placement
			(enabled no)
			(sheetname "")
		)
		(fill
			(thermal_gap 0.5)
			(thermal_bridge_width 0.5)
			(island_removal_mode 0)
		)
		(polygon
			(pts
				(arc
					(start 12.499848 -183.250078)
					(mid 12.500356 -192.749678)
					(end 12.499848 -183.250078)
				)
			)
		)
	)
	(zone
		(net "GND")
		(layer "In3.Cu")
		(hatch none 0.5)
		(connect_pads
			(clearance 0.5)
		)
		(min_thickness 0.25)
		(fill yes
			(thermal_gap 0.5)
			(thermal_bridge_width 0.5)
			(island_removal_mode 0)
		)
		(polygon
			(pts
				(xy 1.27 -1.27) (xy 1.27 -108.163106) (xy 1.504442 -108.397548) (xy 29.260038 -108.397548) (xy 29.260038 -1.27)
			)
		)
	)
	(zone
		(net "P12V_IOM")
		(layer "In3.Cu")
		(hatch none 0.5)
		(connect_pads
			(clearance 0.5)
		)
		(min_thickness 0.25)
		(fill yes
			(thermal_gap 0.5)
			(thermal_bridge_width 0.5)
			(island_removal_mode 0)
		)
		(polygon
			(pts
				(xy 133.670294 -14.8844) (xy 132.387594 -16.1671) (xy 130.330194 -16.1671) (xy 129.339594 -17.1577)
				(xy 121.719086 -17.1577) (xy 121.497852 -17.378934) (xy 121.497852 -46.729904) (xy 134.867142 -46.729904)
				(xy 134.867142 -30.492192) (xy 135.725662 -29.633672) (xy 144.459198 -29.633672) (xy 144.5895 -29.50337)
				(xy 144.5895 -18.620994) (xy 140.852906 -14.8844)
			)
		)
		(polygon
			(pts
				(arc
					(start 132.785104 -36.799774)
					(mid 132.299837 -36.314888)
					(end 131.814824 -36.800028)
				)
				(arc
					(start 131.814824 -38.200076)
					(mid 132.299964 -38.685216)
					(end 132.785104 -38.200076)
				)
			)
		)
		(polygon
			(pts
				(arc
					(start 129.185162 -36.799774)
					(mid 128.699895 -36.314888)
					(end 128.214882 -36.800028)
				)
				(arc
					(start 128.214882 -38.200076)
					(mid 128.700022 -38.685216)
					(end 129.185162 -38.200076)
				)
			)
		)
		(polygon
			(pts
				(arc
					(start 134.585202 -35.599878)
					(mid 134.099935 -35.114992)
					(end 133.614922 -35.600132)
				)
				(arc
					(start 133.614922 -37.00018)
					(mid 134.100062 -37.48532)
					(end 134.585202 -37.00018)
				)
			)
		)
		(polygon
			(pts
				(arc
					(start 130.985006 -35.599878)
					(mid 130.499739 -35.114992)
					(end 130.014726 -35.600132)
				)
				(arc
					(start 130.014726 -37.00018)
					(mid 130.499866 -37.48532)
					(end 130.985006 -37.00018)
				)
			)
		)
		(polygon
			(pts
				(arc
					(start 132.785104 -33.199832)
					(mid 132.299837 -32.714946)
					(end 131.814824 -33.200086)
				)
				(arc
					(start 131.814824 -34.600134)
					(mid 132.299964 -35.085274)
					(end 132.785104 -34.600134)
				)
			)
		)
		(polygon
			(pts
				(arc
					(start 129.185162 -33.199832)
					(mid 128.699895 -32.714946)
					(end 128.214882 -33.200086)
				)
				(arc
					(start 128.214882 -34.600134)
					(mid 128.700022 -35.085274)
					(end 129.185162 -34.600134)
				)
			)
		)
		(polygon
			(pts
				(arc
					(start 134.585202 -31.999936)
					(mid 134.099935 -31.51505)
					(end 133.614922 -32.00019)
				)
				(arc
					(start 133.614922 -33.399984)
					(mid 134.100062 -33.885124)
					(end 134.585202 -33.399984)
				)
			)
		)
		(polygon
			(pts
				(arc
					(start 130.985006 -31.999936)
					(mid 130.499739 -31.51505)
					(end 130.014726 -32.00019)
				)
				(arc
					(start 130.014726 -33.399984)
					(mid 130.499866 -33.885124)
					(end 130.985006 -33.399984)
				)
			)
		)
	)
	(zone
		(net "P1V8_STBY")
		(layer "In3.Cu")
		(hatch none 0.5)
		(connect_pads
			(clearance 0.5)
		)
		(min_thickness 0.25)
		(fill yes
			(thermal_gap 0.5)
			(thermal_bridge_width 0.5)
			(island_removal_mode 0)
		)
		(polygon
			(pts
				(xy 134.45109 -9.5885) (xy 132.250942 -11.788648) (xy 129.567178 -11.788648) (xy 128.25603 -10.4775)
				(xy 120.088914 -10.4775) (xy 119.365014 -11.2014) (xy 118.480586 -11.2014) (xy 117.756686 -10.4775)
				(xy 109.578394 -10.4775) (xy 99.5045 -20.551394) (xy 99.5045 -45.43044) (xy 97.8535 -47.08144) (xy 97.8535 -135.206994)
				(xy 97.2185 -135.841994) (xy 97.2185 -144.701006) (xy 98.6155 -146.098006) (xy 98.6155 -155.966414)
				(xy 98.105214 -156.4767) (xy 97.188274 -156.4767) (xy 96.3676 -157.297374) (xy 96.3676 -161.402014)
				(xy 93.241114 -164.5285) (xy 76.659994 -164.5285) (xy 76.0095 -165.178994) (xy 76.0095 -167.942006)
				(xy 76.278994 -168.2115) (xy 77.802994 -168.2115) (xy 78.183994 -168.5925) (xy 81.104994 -168.5925)
				(xy 83.78698 -171.274486) (xy 83.78698 -175.946054) (xy 81.0895 -178.643534) (xy 81.0895 -184.990994)
				(xy 79.961994 -186.1185) (xy 76.507594 -186.1185) (xy 74.094594 -188.5315) (xy 46.276006 -188.5315)
				(xy 39.3573 -181.612794) (xy 39.3573 -180.614574) (xy 38.724586 -179.98186) (xy 37.726366 -179.98186)
				(xy 31.544006 -173.7995) (xy 25.194006 -173.7995) (xy 22.781006 -171.3865) (xy 13.921994 -171.3865)
				(xy 13.8811 -171.427394) (xy 13.8811 -171.853606) (xy 18.620994 -176.5935) (xy 23.700994 -176.5935)
				(xy 25.0825 -177.975006) (xy 25.0825 -184.863994) (xy 24.4475 -185.498994) (xy 24.4475 -188.287406)
				(xy 28.890214 -192.73012) (xy 85.054186 -192.73012) (xy 85.2297 -192.554606) (xy 85.2297 -187.373006)
				(xy 89.786206 -182.8165) (xy 96.720406 -182.8165) (xy 101.190806 -178.3461) (xy 102.181406 -178.3461)
				(xy 102.430072 -178.097434)
				(arc
					(start 102.430072 -47.999904)
					(mid 102.931847 -46.765144)
					(end 104.1527 -46.23054)
				)
				(xy 104.1527 -45.818806) (xy 104.5845 -45.387006) (xy 104.5845 -25.575006) (xy 113.382806 -16.7767)
				(xy 120.904254 -16.7767) (xy 120.905016 -16.775938) (xy 121.063004 -16.775938) (xy 121.063766 -16.7767)
				(xy 129.181606 -16.7767) (xy 130.172206 -15.7861) (xy 132.229606 -15.7861) (xy 133.512306 -14.5034)
				(xy 141.010894 -14.5034) (xy 144.9705 -18.463006) (xy 144.9705 -29.99359) (xy 144.977866 -30.000956)
				(xy 144.977866 -30.158944) (xy 144.9705 -30.16631)
				(arc
					(start 144.9705 -46.672246)
					(mid 145.413049 -47.271443)
					(end 145.56994 -47.99965)
				)
				(xy 145.56994 -47.999904) (xy 145.56994 -124.828046) (xy 145.900394 -125.1585) (xy 164.271198 -125.1585)
				(xy 164.2872 -125.174502) (xy 165.4175 -124.044202) (xy 165.4175 -90.248994) (xy 150.4315 -75.262994)
				(xy 150.4315 -11.127994) (xy 148.892006 -9.5885)
			)
		)
	)
	(zone
		(net "GND")
		(layer "In3.Cu")
		(hatch none 0.5)
		(connect_pads
			(clearance 0.5)
		)
		(min_thickness 0.25)
		(fill yes
			(thermal_gap 0.5)
			(thermal_bridge_width 0.5)
			(island_removal_mode 0)
		)
		(polygon
			(pts
				(xy 101.348794 -178.7271) (xy 96.878394 -183.1975) (xy 89.944194 -183.1975) (xy 85.6107 -187.530994)
				(xy 85.6107 -192.453006) (xy 85.887814 -192.73012) (xy 97.914968 -192.73012) (xy 102.430072 -183.700166)
				(xy 102.430072 -178.975766) (xy 102.181406 -178.7271)
			)
		)
	)
	(zone
		(net "P12V_STBY")
		(layer "In3.Cu")
		(hatch none 0.5)
		(connect_pads
			(clearance 0.5)
		)
		(min_thickness 0.25)
		(fill yes
			(thermal_gap 0.5)
			(thermal_bridge_width 0.5)
			(island_removal_mode 0)
		)
		(polygon
			(pts
				(xy 74.30008 -1.27)
				(arc
					(start 74.30008 -109.050074)
					(mid 73.635213 -110.655205)
					(end 72.030082 -111.320072)
				)
				(arc
					(start 31.530036 -111.320072)
					(mid 29.924905 -110.655205)
					(end 29.260038 -109.050074)
				)
				(xy 29.260038 -108.778548) (xy 1.447546 -108.778548) (xy 1.27 -108.956094) (xy 1.27 -182.381906)
				(xy 1.444244 -182.55615) (xy 13.401548 -182.55615) (xy 16.074898 -185.2295) (xy 24.178006 -185.2295)
				(xy 24.7015 -184.706006) (xy 24.7015 -178.132994) (xy 23.543006 -176.9745) (xy 18.463006 -176.9745)
				(xy 11.3665 -169.877994) (xy 11.3665 -160.624774) (xy 11.3665 -160.456626) (xy 11.3665 -119.428006)
				(xy 15.923006 -114.8715) (xy 79.931006 -114.8715) (xy 88.3539 -106.448606) (xy 88.3539 -101.59873)
				(xy 83.8581 -97.10293) (xy 83.8581 -52.309014) (xy 84.350606 -51.816508) (xy 92.820998 -51.816508)
				(xy 93.1545 -51.483006) (xy 93.1545 -48.308006) (xy 94.663006 -46.7995) (xy 97.596452 -46.7995)
				(xy 99.1235 -45.272452) (xy 99.1235 -20.393406) (xy 109.420406 -10.0965) (xy 117.914674 -10.0965)
				(xy 118.638574 -10.8204) (xy 119.207026 -10.8204) (xy 119.930926 -10.0965) (xy 128.414018 -10.0965)
				(xy 129.725166 -11.407648) (xy 132.092954 -11.407648) (xy 134.293102 -9.2075) (xy 149.049994 -9.2075)
				(xy 150.700994 -10.8585) (xy 188.191394 -10.8585) (xy 193.576194 -16.2433) (xy 197.614794 -16.2433)
				(xy 211.1375 -29.766006) (xy 211.1375 -55.527194) (xy 209.6135 -57.051194) (xy 209.6135 -67.230244)
				(xy 209.889852 -67.502532) (xy 211.1375 -68.749926) (xy 211.1375 -102.948994) (xy 208.4705 -105.615994)
				(xy 208.4705 -112.981994) (xy 207.342994 -114.1095) (xy 192.072006 -114.1095) (xy 189.4205 -111.457994)
				(xy 189.4205 -101.932994) (xy 189.025784 -101.538278) (xy 181.052216 -101.538278) (xy 176.8475 -105.742994)
				(xy 176.8475 -113.489994) (xy 176.050194 -114.2873) (xy 166.288974 -114.2873) (xy 165.7985 -114.777774)
				(xy 165.7985 -124.20219) (xy 164.4777 -125.52299) (xy 164.4777 -146.552412) (xy 175.707294 -157.782006)
				(xy 233.5149 -157.782006) (xy 233.730038 -157.566868) (xy 233.730038 -1.27)
			)
		)
		(polygon
			(pts
				(arc
					(start 83.741768 -94.492572)
					(mid 83.358228 -94.109032)
					(end 82.974688 -94.492572)
				)
				(arc
					(start 82.974688 -95.381826)
					(mid 83.358355 -95.765112)
					(end 83.741768 -95.381572)
				)
			)
		)
		(polygon
			(pts
				(arc
					(start 77.667358 -92.911168)
					(mid 77.283818 -92.527628)
					(end 76.900278 -92.911168)
				)
				(arc
					(start 76.900278 -93.800422)
					(mid 77.283945 -94.183708)
					(end 77.667358 -93.800168)
				)
			)
		)
		(polygon
			(pts
				(arc
					(start 78.505558 -89.710768)
					(mid 78.122018 -89.327228)
					(end 77.738478 -89.710768)
				)
				(arc
					(start 77.738478 -90.600022)
					(mid 78.122145 -90.983308)
					(end 78.505558 -90.599768)
				)
			)
		)
		(polygon
			(pts
				(arc
					(start 83.741768 -88.10498)
					(mid 83.358101 -87.721694)
					(end 82.974688 -88.105234)
				)
				(arc
					(start 82.974688 -88.994234)
					(mid 83.358228 -89.377774)
					(end 83.741768 -88.994234)
				)
			)
		)
		(polygon
			(pts
				(arc
					(start 77.667358 -86.510368)
					(mid 77.283818 -86.126828)
					(end 76.900278 -86.510368)
				)
				(arc
					(start 76.900278 -87.399622)
					(mid 77.283945 -87.782908)
					(end 77.667358 -87.399368)
				)
			)
		)
		(polygon
			(pts
				(arc
					(start 78.505558 -83.335368)
					(mid 78.122018 -82.951828)
					(end 77.738478 -83.335368)
				)
				(arc
					(start 77.738478 -84.224622)
					(mid 78.122145 -84.607908)
					(end 78.505558 -84.224368)
				)
			)
		)
		(polygon
			(pts
				(arc
					(start 83.741768 -81.705196)
					(mid 83.358228 -81.321656)
					(end 82.974688 -81.705196)
				)
				(arc
					(start 82.974688 -82.59445)
					(mid 83.358355 -82.977736)
					(end 83.741768 -82.594196)
				)
			)
		)
		(polygon
			(pts
				(arc
					(start 216.573354 -79.113126)
					(mid 216.573354 -78.574646)
					(end 216.034874 -78.574646)
				)
				(xy 216.03462 -78.574392) (xy 215.226392 -79.38262)
				(arc
					(start 215.226646 -79.382874)
					(mid 215.226646 -79.921354)
					(end 215.765126 -79.921354)
				)
				(xy 215.76538 -79.921608) (xy 216.573354 -79.11338)
			)
		)
		(polygon
			(pts
				(arc
					(start 78.505558 -76.909168)
					(mid 78.122018 -76.525628)
					(end 77.738478 -76.909168)
				)
				(arc
					(start 77.738478 -77.798422)
					(mid 78.122145 -78.181708)
					(end 78.505558 -77.798168)
				)
			)
		)
		(polygon
			(pts
				(arc
					(start 83.741768 -75.305158)
					(mid 83.358228 -74.921618)
					(end 82.974688 -75.305158)
				)
				(arc
					(start 82.974688 -76.194412)
					(mid 83.358355 -76.577698)
					(end 83.741768 -76.194158)
				)
			)
		)
		(polygon
			(pts
				(arc
					(start 217.716354 -75.176126)
					(mid 217.716354 -74.637646)
					(end 217.177874 -74.637646)
				)
				(xy 217.17762 -74.637392) (xy 216.369392 -75.44562)
				(arc
					(start 216.369646 -75.445874)
					(mid 216.369646 -75.984354)
					(end 216.908126 -75.984354)
				)
				(xy 216.90838 -75.984608) (xy 217.716354 -75.17638)
			)
		)
		(polygon
			(pts
				(arc
					(start 77.667358 -73.708768)
					(mid 77.283818 -73.325228)
					(end 76.900278 -73.708768)
				)
				(arc
					(start 76.900278 -74.598022)
					(mid 77.283945 -74.981308)
					(end 77.667358 -74.597768)
				)
			)
		)
		(polygon
			(pts
				(arc
					(start 216.192354 -73.652126)
					(mid 216.192354 -73.113646)
					(end 215.653874 -73.113646)
				)
				(xy 215.65362 -73.113392) (xy 214.845392 -73.92162)
				(arc
					(start 214.845646 -73.921874)
					(mid 214.845646 -74.460354)
					(end 215.384126 -74.460354)
				)
				(xy 215.38438 -74.460608) (xy 216.192354 -73.65238)
			)
		)
		(polygon
			(pts
				(arc
					(start 214.795354 -72.255126)
					(mid 214.795354 -71.716646)
					(end 214.256874 -71.716646)
				)
				(xy 214.25662 -71.716392) (xy 213.448392 -72.52462)
				(arc
					(start 213.448646 -72.524874)
					(mid 213.448646 -73.063354)
					(end 213.987126 -73.063354)
				)
				(xy 213.98738 -73.063608) (xy 214.795354 -72.25538)
			)
		)
		(polygon
			(pts
				(arc
					(start 78.505558 -70.508368)
					(mid 78.122018 -70.124828)
					(end 77.738478 -70.508368)
				)
				(arc
					(start 77.738478 -71.397622)
					(mid 78.122145 -71.780908)
					(end 78.505558 -71.397368)
				)
			)
		)
		(polygon
			(pts
				(arc
					(start 215.303354 -68.953126)
					(mid 215.303354 -68.414646)
					(end 214.764874 -68.414646)
				)
				(xy 214.76462 -68.414392) (xy 213.956392 -69.22262)
				(arc
					(start 213.956646 -69.222874)
					(mid 213.956646 -69.761354)
					(end 214.495126 -69.761354)
				)
				(xy 214.49538 -69.761608) (xy 215.303354 -68.95338)
			)
		)
		(polygon
			(pts
				(arc
					(start 213.779354 -67.479926)
					(mid 213.779354 -66.941446)
					(end 213.240874 -66.941446)
				)
				(xy 213.24062 -66.941192) (xy 212.432392 -67.74942)
				(arc
					(start 212.432646 -67.749674)
					(mid 212.432646 -68.288154)
					(end 212.971126 -68.288154)
				)
				(xy 212.97138 -68.288408) (xy 213.779354 -67.48018)
			)
		)
		(polygon
			(pts
				(arc
					(start 212.306154 -65.828926)
					(mid 212.306154 -65.290446)
					(end 211.767674 -65.290446)
				)
				(xy 211.76742 -65.290192) (xy 210.959192 -66.09842)
				(arc
					(start 210.959446 -66.098674)
					(mid 210.959446 -66.637154)
					(end 211.497926 -66.637154)
				)
				(xy 211.49818 -66.637408) (xy 212.306154 -65.82918)
			)
		)
		(polygon
			(pts
				(arc
					(start 212.137498 -63.3857)
					(mid 212.137498 -62.84722)
					(end 211.599018 -62.84722)
				)
				(xy 211.598764 -62.846966) (xy 210.790536 -63.655194)
				(arc
					(start 210.79079 -63.655448)
					(mid 210.79079 -64.193928)
					(end 211.32927 -64.193928)
				)
				(xy 211.329524 -64.194182) (xy 212.137498 -63.385954)
			)
		)
	)
	(zone
		(layer "In3.Cu")
		(hatch none 0.5)
		(connect_pads
			(clearance 0)
		)
		(min_thickness 0.25)
		(keepout
			(tracks not_allowed)
			(vias allowed)
			(pads allowed)
			(copperpour not_allowed)
			(footprints allowed)
		)
		(placement
			(enabled no)
			(sheetname "")
		)
		(fill
			(thermal_gap 0.5)
			(thermal_bridge_width 0.5)
			(island_removal_mode 0)
		)
		(polygon
			(pts
				(arc
					(start 222.499936 -10.249916)
					(mid 222.499936 -19.750024)
					(end 222.499936 -10.249916)
				)
			)
		)
	)
	(zone
		(layers "In3.Cu" "In4.Cu")
		(hatch none 0.5)
		(connect_pads
			(clearance 0)
		)
		(min_thickness 0.25)
		(keepout
			(tracks not_allowed)
			(vias allowed)
			(pads allowed)
			(copperpour not_allowed)
			(footprints allowed)
		)
		(placement
			(enabled no)
			(sheetname "")
		)
		(fill yes
			(thermal_gap 0.5)
			(thermal_bridge_width 0.5)
			(island_removal_mode 0)
		)
		(polygon
			(pts
				(arc
					(start 150.82774 -145.8976)
					(mid 149.04466 -145.8976)
					(end 150.82774 -145.8976)
				)
			)
		)
	)
	(zone
		(layers "In3.Cu" "In4.Cu")
		(hatch none 0.5)
		(connect_pads
			(clearance 0)
		)
		(min_thickness 0.25)
		(keepout
			(tracks not_allowed)
			(vias allowed)
			(pads allowed)
			(copperpour not_allowed)
			(footprints allowed)
		)
		(placement
			(enabled no)
			(sheetname "")
		)
		(fill yes
			(thermal_gap 0.5)
			(thermal_bridge_width 0.5)
			(island_removal_mode 0)
		)
		(polygon
			(pts
				(arc
					(start 27.141424 -8.750046)
					(mid 25.358344 -8.750046)
					(end 27.141424 -8.750046)
				)
			)
		)
	)
	(zone
		(layers "In3.Cu" "In4.Cu")
		(hatch none 0.5)
		(connect_pads
			(clearance 0)
		)
		(min_thickness 0.25)
		(keepout
			(tracks not_allowed)
			(vias allowed)
			(pads allowed)
			(copperpour not_allowed)
			(footprints allowed)
		)
		(placement
			(enabled no)
			(sheetname "")
		)
		(fill yes
			(thermal_gap 0.5)
			(thermal_bridge_width 0.5)
			(island_removal_mode 0)
		)
		(polygon
			(pts
				(arc
					(start 15.141448 -6.249924)
					(mid 13.358368 -6.249924)
					(end 15.141448 -6.249924)
				)
			)
		)
	)
	(zone
		(net "P3V3_STBY")
		(layer "In4.Cu")
		(hatch none 0.5)
		(connect_pads
			(clearance 0.5)
		)
		(min_thickness 0.25)
		(fill yes
			(thermal_gap 0.5)
			(thermal_bridge_width 0.5)
			(island_removal_mode 0)
		)
		(polygon
			(pts
				(xy 93.804994 -150.4315) (xy 89.5223 -154.714194) (xy 89.5223 -156.034994) (xy 86.616794 -158.9405)
				(xy 81.358994 -158.9405) (xy 80.9625 -159.336994) (xy 80.9625 -164.102796) (xy 81.388204 -164.5285)
				(xy 83.594194 -164.5285) (xy 84.7217 -165.656006) (xy 84.7217 -180.937916) (xy 85.127084 -181.3433)
				(xy 87.327994 -181.3433) (xy 88.166194 -182.1815) (xy 88.871806 -182.1815) (xy 89.710006 -181.3433)
				(xy 100.047806 -181.3433) (xy 100.4189 -180.972206) (xy 100.4189 -151.335994) (xy 99.514406 -150.4315)
			)
		)
	)
	(zone
		(net "GND")
		(layer "In4.Cu")
		(hatch none 0.5)
		(connect_pads
			(clearance 0.5)
		)
		(min_thickness 0.25)
		(fill yes
			(thermal_gap 0.5)
			(thermal_bridge_width 0.5)
			(island_removal_mode 0)
		)
		(polygon
			(pts
				(xy 212.156294 -1.27) (xy 211.728304 -1.69799) (xy 211.728304 -15.145766) (xy 207.475328 -19.398742)
				(xy 201.5998 -19.398742) (xy 195.027042 -12.825984) (xy 158.388304 -12.825984) (xy 155.961588 -15.2527)
				(xy 142.059406 -15.2527) (xy 141.043406 -14.2367) (xy 136.893046 -14.2367) (xy 134.735824 -12.079478)
				(xy 129.416302 -12.079478) (xy 128.779524 -11.4427) (xy 111.172498 -11.4427) (xy 105.313988 -5.58419)
				(xy 88.222836 -5.58419) (xy 84.281518 -9.525508) (xy 84.281518 -96.884236) (xy 88.9635 -101.566218)
				(xy 88.9635 -109.170978) (xy 83.669378 -114.4651) (xy 78.103476 -114.4651) (xy 72.135492 -120.433084)
				(xy 26.517854 -120.433084) (xy 14.356334 -132.594604) (xy 14.356334 -165.45306) (xy 14.799564 -165.89629)
				(xy 27.648916 -165.89629) (xy 28.062936 -165.48227) (xy 28.062936 -153.822908) (xy 31.949136 -149.936708)
				(xy 43.534838 -149.936708) (xy 44.47032 -149.001226) (xy 44.47032 -148.000466) (xy 44.297854 -147.828)
				(xy 43.624754 -147.828) (xy 42.862754 -147.066) (xy 39.046658 -147.066) (xy 38.306502 -146.325844)
				(xy 38.252654 -146.325844) (xy 26.580592 -134.653782) (xy 18.014188 -134.653782) (xy 17.0688 -135.59917)
				(xy 17.0688 -139.956794) (xy 16.622522 -140.403072) (xy 15.460726 -140.403072) (xy 15.02156 -139.963906)
				(xy 15.02156 -135.998458) (xy 17.530572 -133.489446) (xy 27.081988 -133.489446) (xy 38.237668 -144.645126)
				(xy 38.578028 -144.645126) (xy 38.798754 -144.4244) (xy 44.386754 -144.4244) (xy 44.47032 -144.340834)
				(xy 44.47032 -142.2654) (xy 43.791124 -141.586204) (xy 37.483796 -141.586204) (xy 36.645596 -140.748004)
				(xy 36.645596 -135.75411)
				(arc
					(start 40.392604 -132.007102)
					(mid 40.453998 -131.965696)
					(end 40.526462 -131.95046)
				)
				(xy 40.529256 -131.95046)
				(arc
					(start 72.145398 -131.95046)
					(mid 72.219218 -131.965237)
					(end 72.281796 -132.007102)
				)
				(xy 79.0067 -138.732006) (xy 79.0067 -153.520394) (xy 77.802994 -154.7241) (xy 76.510642 -154.7241)
				(xy 65.306194 -165.928548) (xy 34.434526 -165.928548) (xy 34.276284 -166.08679) (xy 34.647124 -166.45763)
				(xy 34.647124 -169.65803) (xy 53.698394 -188.7093) (xy 68.424806 -188.7093) (xy 72.2757 -184.858406)
				(xy 72.2757 -168.831006) (xy 76.578206 -164.5285) (xy 80.155796 -164.5285) (xy 80.5815 -164.102796)
				(xy 80.5815 -159.179006) (xy 81.201006 -158.5595) (xy 86.458806 -158.5595) (xy 89.1413 -155.877006)
				(xy 89.1413 -154.556206) (xy 93.647006 -150.0505) (xy 99.672394 -150.0505) (xy 100.7999 -151.178006)
				(xy 100.7999 -181.130194) (xy 100.205794 -181.7243) (xy 89.867994 -181.7243) (xy 89.029794 -182.5625)
				(xy 88.008206 -182.5625) (xy 87.170006 -181.7243) (xy 85.127084 -181.7243) (xy 84.7217 -182.129684)
				(xy 84.7217 -192.326006) (xy 85.125814 -192.73012) (xy 97.914968 -192.73012) (xy 102.430072 -183.700166)
				(arc
					(start 102.430072 -47.999904)
					(mid 103.510621 -46.369619)
					(end 105.43286 -46.729904)
				)
				(arc
					(start 142.567152 -46.729904)
					(mid 144.489165 -46.369827)
					(end 145.56994 -47.99965)
				)
				(xy 145.56994 -47.999904) (xy 145.56994 -90.021156) (xy 145.756884 -90.2081) (xy 150.294594 -90.2081)
				(xy 150.904194 -90.8177) (xy 165.202616 -90.8177) (xy 169.656252 -95.271336) (xy 172.73143 -95.271336)
				(xy 183.6547 -106.194606) (xy 183.6547 -119.631206) (xy 184.813194 -120.7897) (xy 199.341994 -120.7897)
				(xy 201.1807 -122.628406) (xy 201.1807 -128.876806) (xy 208.206594 -135.9027) (xy 208.231994 -135.9027)
				(xy 209.6643 -137.335006) (xy 209.6643 -150.599394) (xy 208.892394 -151.3713) (xy 207.495394 -151.3713)
				(xy 206.961994 -151.9047) (xy 196.186806 -151.9047) (xy 182.547006 -138.2649) (xy 174.952406 -138.2649)
				(xy 170.1927 -133.505194) (xy 170.1927 -117.960394) (xy 157.655006 -105.4227) (xy 145.807684 -105.4227)
				(xy 145.56994 -105.660444) (xy 145.56994 -183.700166) (xy 150.085044 -192.73012) (xy 229.214934 -192.73012)
				(xy 233.730038 -183.700166) (xy 233.730038 -1.27)
			)
		)
		(polygon
			(pts
				(arc
					(start 149.9362 -145.00606)
					(mid 149.9362 -146.78914)
					(end 149.9362 -145.00606)
				)
			)
		)
		(polygon
			(pts
				(arc
					(start 85.367368 -91.306396)
					(mid 84.983828 -90.922856)
					(end 84.600288 -91.306396)
				)
				(arc
					(start 84.600288 -92.19565)
					(mid 84.983955 -92.578936)
					(end 85.367368 -92.195396)
				)
			)
		)
		(polygon
			(pts
				(arc
					(start 199.084692 -88.728296)
					(mid 199.084692 -88.189308)
					(end 198.545704 -88.189308)
				)
				(arc
					(start 197.922134 -88.813132)
					(mid 197.915055 -89.354246)
					(end 198.456296 -89.356692)
				)
			)
		)
		(polygon
			(pts
				(arc
					(start 194.720464 -88.652096)
					(mid 194.720464 -88.113108)
					(end 194.181476 -88.113108)
				)
				(arc
					(start 193.557906 -88.736932)
					(mid 193.550827 -89.278046)
					(end 194.092068 -89.280492)
				)
			)
		)
		(polygon
			(pts
				(arc
					(start 191.998092 -86.950296)
					(mid 191.998092 -86.411308)
					(end 191.459104 -86.411308)
				)
				(arc
					(start 190.835534 -87.035132)
					(mid 190.828455 -87.576246)
					(end 191.369696 -87.578692)
				)
			)
		)
		(polygon
			(pts
				(arc
					(start 202.107292 -85.731096)
					(mid 202.107292 -85.192108)
					(end 201.568304 -85.192108)
				)
				(arc
					(start 200.944734 -85.815932)
					(mid 200.937655 -86.357046)
					(end 201.478896 -86.359492)
				)
			)
		)
		(polygon
			(pts
				(arc
					(start 197.793864 -85.604096)
					(mid 197.793864 -85.065108)
					(end 197.254876 -85.065108)
				)
				(arc
					(start 196.631306 -85.688932)
					(mid 196.624227 -86.230046)
					(end 197.165468 -86.232492)
				)
			)
		)
		(polygon
			(pts
				(arc
					(start 85.367368 -84.904834)
					(mid 84.983828 -84.521294)
					(end 84.600288 -84.904834)
				)
				(arc
					(start 84.600288 -85.794088)
					(mid 84.983955 -86.177374)
					(end 85.367368 -85.793834)
				)
			)
		)
		(polygon
			(pts
				(arc
					(start 204.698092 -85.146896)
					(mid 204.698092 -84.607908)
					(end 204.159104 -84.607908)
				)
				(arc
					(start 203.535534 -85.231732)
					(mid 203.528455 -85.772846)
					(end 204.069696 -85.775292)
				)
			)
		)
		(polygon
			(pts
				(arc
					(start 190.448692 -84.156296)
					(mid 190.448692 -83.617308)
					(end 189.909704 -83.617308)
				)
				(arc
					(start 189.286134 -84.241132)
					(mid 189.279055 -84.782246)
					(end 189.820296 -84.784692)
				)
			)
		)
		(polygon
			(pts
				(arc
					(start 194.944492 -83.927696)
					(mid 194.944492 -83.388708)
					(end 194.405504 -83.388708)
				)
				(arc
					(start 193.781934 -84.012532)
					(mid 193.774855 -84.553646)
					(end 194.316096 -84.556092)
				)
			)
		)
		(polygon
			(pts
				(arc
					(start 85.367368 -78.504796)
					(mid 84.983828 -78.121256)
					(end 84.600288 -78.504796)
				)
				(arc
					(start 84.600288 -79.39405)
					(mid 84.983955 -79.777336)
					(end 85.367368 -79.393796)
				)
			)
		)
		(polygon
			(pts
				(arc
					(start 85.367368 -72.080882)
					(mid 84.983701 -71.697596)
					(end 84.600288 -72.081136)
				)
				(arc
					(start 84.600288 -72.970136)
					(mid 84.983828 -73.353676)
					(end 85.367368 -72.970136)
				)
			)
		)
		(polygon
			(pts
				(xy 212.969094 -60.3123) (xy 209.991706 -60.3123) (xy 209.953606 -60.3504) (xy 188.506354 -60.3504)
				(xy 188.1886 -60.668154) (xy 188.1886 -69.774054) (xy 187.93587 -70.026784) (xy 181.07533 -70.026784)
				(xy 178.68392 -72.418194) (xy 178.68392 -74.694034) (xy 177.8889 -75.489054) (xy 177.8889 -80.330548)
				(xy 180.260752 -82.7024) (xy 198.023734 -82.7024) (xy 201.795634 -78.9305) (xy 202.309222 -78.9305)
				(xy 203.1238 -79.745078) (xy 203.1238 -79.796894) (xy 206.1337 -82.806794) (xy 206.1337 -104.429306)
				(xy 204.518006 -106.045) (xy 189.735206 -106.045) (xy 189.2173 -106.562906) (xy 189.2173 -112.905794)
				(xy 189.646306 -113.3348) (xy 211.330794 -113.3348) (xy 220.055694 -104.6099) (xy 224.322894 -104.6099)
				(xy 225.1202 -103.812594) (xy 225.1202 -72.463406)
			)
		)
		(polygon
			(pts
				(arc
					(start 139.984988 -36.799774)
					(mid 139.499721 -36.314888)
					(end 139.014708 -36.800028)
				)
				(arc
					(start 139.014708 -38.200076)
					(mid 139.499848 -38.685216)
					(end 139.984988 -38.200076)
				)
			)
		)
		(polygon
			(pts
				(arc
					(start 136.385046 -36.799774)
					(mid 135.899779 -36.314888)
					(end 135.414766 -36.800028)
				)
				(arc
					(start 135.414766 -38.200076)
					(mid 135.899906 -38.685216)
					(end 136.385046 -38.200076)
				)
			)
		)
		(polygon
			(pts
				(arc
					(start 132.785104 -36.799774)
					(mid 132.299837 -36.314888)
					(end 131.814824 -36.800028)
				)
				(arc
					(start 131.814824 -38.200076)
					(mid 132.299964 -38.685216)
					(end 132.785104 -38.200076)
				)
			)
		)
		(polygon
			(pts
				(arc
					(start 129.185162 -36.799774)
					(mid 128.699895 -36.314888)
					(end 128.214882 -36.800028)
				)
				(arc
					(start 128.214882 -38.200076)
					(mid 128.700022 -38.685216)
					(end 129.185162 -38.200076)
				)
			)
		)
		(polygon
			(pts
				(arc
					(start 118.385082 -36.799774)
					(mid 117.899815 -36.314888)
					(end 117.414802 -36.800028)
				)
				(arc
					(start 117.414802 -38.200076)
					(mid 117.899942 -38.685216)
					(end 118.385082 -38.200076)
				)
			)
		)
		(polygon
			(pts
				(arc
					(start 114.78514 -36.799774)
					(mid 114.299873 -36.314888)
					(end 113.81486 -36.800028)
				)
				(arc
					(start 113.81486 -38.200076)
					(mid 114.3 -38.685216)
					(end 114.78514 -38.200076)
				)
			)
		)
		(polygon
			(pts
				(arc
					(start 111.185198 -36.799774)
					(mid 110.699931 -36.314888)
					(end 110.214918 -36.800028)
				)
				(arc
					(start 110.214918 -38.200076)
					(mid 110.700058 -38.685216)
					(end 111.185198 -38.200076)
				)
			)
		)
		(polygon
			(pts
				(arc
					(start 107.585002 -36.799774)
					(mid 107.099735 -36.314888)
					(end 106.614722 -36.800028)
				)
				(arc
					(start 106.614722 -38.200076)
					(mid 107.099862 -38.685216)
					(end 107.585002 -38.200076)
				)
			)
		)
		(polygon
			(pts
				(arc
					(start 141.785086 -35.599878)
					(mid 141.299819 -35.114992)
					(end 140.814806 -35.600132)
				)
				(arc
					(start 140.814806 -37.00018)
					(mid 141.299946 -37.48532)
					(end 141.785086 -37.00018)
				)
			)
		)
		(polygon
			(pts
				(arc
					(start 138.185144 -35.599878)
					(mid 137.699877 -35.114992)
					(end 137.214864 -35.600132)
				)
				(arc
					(start 137.214864 -37.00018)
					(mid 137.700004 -37.48532)
					(end 138.185144 -37.00018)
				)
			)
		)
		(polygon
			(pts
				(arc
					(start 134.585202 -35.599878)
					(mid 134.099935 -35.114992)
					(end 133.614922 -35.600132)
				)
				(arc
					(start 133.614922 -37.00018)
					(mid 134.100062 -37.48532)
					(end 134.585202 -37.00018)
				)
			)
		)
		(polygon
			(pts
				(arc
					(start 130.985006 -35.599878)
					(mid 130.499739 -35.114992)
					(end 130.014726 -35.600132)
				)
				(arc
					(start 130.014726 -37.00018)
					(mid 130.499866 -37.48532)
					(end 130.985006 -37.00018)
				)
			)
		)
		(polygon
			(pts
				(arc
					(start 120.18518 -35.599878)
					(mid 119.699913 -35.114992)
					(end 119.2149 -35.600132)
				)
				(arc
					(start 119.2149 -37.00018)
					(mid 119.70004 -37.48532)
					(end 120.18518 -37.00018)
				)
			)
		)
		(polygon
			(pts
				(arc
					(start 116.584984 -35.599878)
					(mid 116.099717 -35.114992)
					(end 115.614704 -35.600132)
				)
				(arc
					(start 115.614704 -37.00018)
					(mid 116.099844 -37.48532)
					(end 116.584984 -37.00018)
				)
			)
		)
		(polygon
			(pts
				(arc
					(start 112.985042 -35.599878)
					(mid 112.499775 -35.114992)
					(end 112.014762 -35.600132)
				)
				(arc
					(start 112.014762 -37.00018)
					(mid 112.499902 -37.48532)
					(end 112.985042 -37.00018)
				)
			)
		)
		(polygon
			(pts
				(arc
					(start 109.3851 -35.599878)
					(mid 108.899833 -35.114992)
					(end 108.41482 -35.600132)
				)
				(arc
					(start 108.41482 -37.00018)
					(mid 108.89996 -37.48532)
					(end 109.3851 -37.00018)
				)
			)
		)
		(polygon
			(pts
				(arc
					(start 139.984988 -33.199832)
					(mid 139.499721 -32.714946)
					(end 139.014708 -33.200086)
				)
				(arc
					(start 139.014708 -34.600134)
					(mid 139.499848 -35.085274)
					(end 139.984988 -34.600134)
				)
			)
		)
		(polygon
			(pts
				(arc
					(start 136.385046 -33.199832)
					(mid 135.899779 -32.714946)
					(end 135.414766 -33.200086)
				)
				(arc
					(start 135.414766 -34.600134)
					(mid 135.899906 -35.085274)
					(end 136.385046 -34.600134)
				)
			)
		)
		(polygon
			(pts
				(arc
					(start 132.785104 -33.199832)
					(mid 132.299837 -32.714946)
					(end 131.814824 -33.200086)
				)
				(arc
					(start 131.814824 -34.600134)
					(mid 132.299964 -35.085274)
					(end 132.785104 -34.600134)
				)
			)
		)
		(polygon
			(pts
				(arc
					(start 129.185162 -33.199832)
					(mid 128.699895 -32.714946)
					(end 128.214882 -33.200086)
				)
				(arc
					(start 128.214882 -34.600134)
					(mid 128.700022 -35.085274)
					(end 129.185162 -34.600134)
				)
			)
		)
		(polygon
			(pts
				(arc
					(start 118.385082 -33.199832)
					(mid 117.899815 -32.714946)
					(end 117.414802 -33.200086)
				)
				(arc
					(start 117.414802 -34.600134)
					(mid 117.899942 -35.085274)
					(end 118.385082 -34.600134)
				)
			)
		)
		(polygon
			(pts
				(arc
					(start 114.78514 -33.199832)
					(mid 114.299873 -32.714946)
					(end 113.81486 -33.200086)
				)
				(arc
					(start 113.81486 -34.600134)
					(mid 114.3 -35.085274)
					(end 114.78514 -34.600134)
				)
			)
		)
		(polygon
			(pts
				(arc
					(start 111.185198 -33.199832)
					(mid 110.699931 -32.714946)
					(end 110.214918 -33.200086)
				)
				(arc
					(start 110.214918 -34.600134)
					(mid 110.700058 -35.085274)
					(end 111.185198 -34.600134)
				)
			)
		)
		(polygon
			(pts
				(arc
					(start 107.585002 -33.199832)
					(mid 107.099735 -32.714946)
					(end 106.614722 -33.200086)
				)
				(arc
					(start 106.614722 -34.600134)
					(mid 107.099862 -35.085274)
					(end 107.585002 -34.600134)
				)
			)
		)
		(polygon
			(pts
				(arc
					(start 141.785086 -31.999936)
					(mid 141.299819 -31.51505)
					(end 140.814806 -32.00019)
				)
				(arc
					(start 140.814806 -33.399984)
					(mid 141.299946 -33.885124)
					(end 141.785086 -33.399984)
				)
			)
		)
		(polygon
			(pts
				(arc
					(start 138.185144 -31.999936)
					(mid 137.699877 -31.51505)
					(end 137.214864 -32.00019)
				)
				(arc
					(start 137.214864 -33.399984)
					(mid 137.700004 -33.885124)
					(end 138.185144 -33.399984)
				)
			)
		)
		(polygon
			(pts
				(arc
					(start 134.585202 -31.999936)
					(mid 134.099935 -31.51505)
					(end 133.614922 -32.00019)
				)
				(arc
					(start 133.614922 -33.399984)
					(mid 134.100062 -33.885124)
					(end 134.585202 -33.399984)
				)
			)
		)
		(polygon
			(pts
				(arc
					(start 130.985006 -31.999936)
					(mid 130.499739 -31.51505)
					(end 130.014726 -32.00019)
				)
				(arc
					(start 130.014726 -33.399984)
					(mid 130.499866 -33.885124)
					(end 130.985006 -33.399984)
				)
			)
		)
		(polygon
			(pts
				(arc
					(start 120.18518 -31.999936)
					(mid 119.699913 -31.51505)
					(end 119.2149 -32.00019)
				)
				(arc
					(start 119.2149 -33.399984)
					(mid 119.70004 -33.885124)
					(end 120.18518 -33.399984)
				)
			)
		)
		(polygon
			(pts
				(arc
					(start 116.584984 -31.999936)
					(mid 116.099717 -31.51505)
					(end 115.614704 -32.00019)
				)
				(arc
					(start 115.614704 -33.399984)
					(mid 116.099844 -33.885124)
					(end 116.584984 -33.399984)
				)
			)
		)
		(polygon
			(pts
				(arc
					(start 112.985042 -31.999936)
					(mid 112.499775 -31.51505)
					(end 112.014762 -32.00019)
				)
				(arc
					(start 112.014762 -33.399984)
					(mid 112.499902 -33.885124)
					(end 112.985042 -33.399984)
				)
			)
		)
		(polygon
			(pts
				(arc
					(start 109.3851 -31.999936)
					(mid 108.899833 -31.51505)
					(end 108.41482 -32.00019)
				)
				(arc
					(start 108.41482 -33.399984)
					(mid 108.89996 -33.885124)
					(end 109.3851 -33.399984)
				)
			)
		)
		(polygon
			(pts
				(arc
					(start 182.663592 -29.328618)
					(mid 182.47589 -28.684976)
					(end 181.83352 -28.877006)
				)
				(arc
					(start 181.083458 -30.277054)
					(mid 181.277006 -30.916626)
					(end 181.916578 -30.723078)
				)
			)
		)
		(polygon
			(pts
				(arc
					(start 180.413406 -29.328618)
					(mid 180.225704 -28.684976)
					(end 179.583334 -28.877006)
				)
				(arc
					(start 178.833526 -30.277054)
					(mid 179.027074 -30.916626)
					(end 179.666646 -30.723078)
				)
			)
		)
		(polygon
			(pts
				(arc
					(start 162.663632 -29.328618)
					(mid 162.47593 -28.684976)
					(end 161.83356 -28.877006)
				)
				(arc
					(start 161.083498 -30.277054)
					(mid 161.277046 -30.916626)
					(end 161.916618 -30.723078)
				)
			)
		)
		(polygon
			(pts
				(arc
					(start 160.413446 -29.328618)
					(mid 160.225744 -28.684976)
					(end 159.583374 -28.877006)
				)
				(arc
					(start 158.833566 -30.277054)
					(mid 159.027114 -30.916626)
					(end 159.666686 -30.723078)
				)
			)
		)
		(polygon
			(pts
				(arc
					(start 162.663632 -25.528524)
					(mid 162.47593 -24.884882)
					(end 161.83356 -25.076912)
				)
				(arc
					(start 161.083498 -26.47696)
					(mid 161.277046 -27.116532)
					(end 161.916618 -26.922984)
				)
			)
		)
		(polygon
			(pts
				(arc
					(start 160.413446 -25.528524)
					(mid 160.225744 -24.884882)
					(end 159.583374 -25.076912)
				)
				(arc
					(start 158.833566 -26.47696)
					(mid 159.027114 -27.116532)
					(end 159.666686 -26.922984)
				)
			)
		)
		(polygon
			(pts
				(arc
					(start 180.43398 -25.543764)
					(mid 180.239312 -24.863383)
					(end 179.560982 -25.064974)
				)
				(arc
					(start 178.811174 -26.465022)
					(mid 179.015136 -27.138884)
					(end 179.688998 -26.934922)
				)
			)
		)
		(polygon
			(pts
				(arc
					(start 182.684166 -25.543764)
					(mid 182.489596 -24.863437)
					(end 181.811168 -25.06472)
				)
				(arc
					(start 181.061106 -26.464768)
					(mid 181.264814 -27.138884)
					(end 181.93893 -26.935176)
				)
			)
		)
		(polygon
			(pts
				(arc
					(start 182.666386 -21.72335)
					(mid 182.473247 -21.083725)
					(end 181.833774 -21.277072)
				)
				(xy 181.831488 -21.275802) (xy 181.081426 -22.675596)
				(arc
					(start 181.083712 -22.676866)
					(mid 181.277006 -23.316184)
					(end 181.916324 -23.12289)
				)
				(xy 181.91861 -23.12416) (xy 182.668672 -21.72462) (xy 182.668418 -21.724366)
			)
		)
		(polygon
			(pts
				(arc
					(start 162.666426 -21.72335)
					(mid 162.473287 -21.083725)
					(end 161.833814 -21.277072)
				)
				(xy 161.831528 -21.275802) (xy 161.081466 -22.675596)
				(arc
					(start 161.083752 -22.676866)
					(mid 161.277046 -23.316184)
					(end 161.916364 -23.12289)
				)
				(xy 161.91865 -23.12416) (xy 162.668712 -21.72462) (xy 162.668458 -21.724366)
			)
		)
		(polygon
			(pts
				(arc
					(start 180.416454 -21.723096)
					(mid 180.222906 -21.083524)
					(end 179.583334 -21.277072)
				)
				(arc
					(start 178.836574 -22.671278)
					(mid 179.024276 -23.31492)
					(end 179.666646 -23.12289)
				)
			)
		)
		(polygon
			(pts
				(arc
					(start 160.416494 -21.723096)
					(mid 160.222946 -21.083524)
					(end 159.583374 -21.277072)
				)
				(arc
					(start 158.836614 -22.671278)
					(mid 159.024316 -23.31492)
					(end 159.666686 -23.12289)
				)
			)
		)
		(polygon
			(pts
				(arc
					(start 182.663592 -17.92859)
					(mid 182.47589 -17.284948)
					(end 181.83352 -17.476978)
				)
				(arc
					(start 181.083458 -18.877026)
					(mid 181.277006 -19.516598)
					(end 181.916578 -19.32305)
				)
			)
		)
		(polygon
			(pts
				(arc
					(start 180.413406 -17.92859)
					(mid 180.225704 -17.284948)
					(end 179.583334 -17.476978)
				)
				(arc
					(start 178.833526 -18.877026)
					(mid 179.027074 -19.516598)
					(end 179.666646 -19.32305)
				)
			)
		)
		(polygon
			(pts
				(arc
					(start 162.663632 -17.92859)
					(mid 162.47593 -17.284948)
					(end 161.83356 -17.476978)
				)
				(arc
					(start 161.083498 -18.877026)
					(mid 161.277046 -19.516598)
					(end 161.916618 -19.32305)
				)
			)
		)
		(polygon
			(pts
				(arc
					(start 160.413446 -17.92859)
					(mid 160.225744 -17.284948)
					(end 159.583374 -17.476978)
				)
				(arc
					(start 158.833566 -18.877026)
					(mid 159.027114 -19.516598)
					(end 159.666686 -19.32305)
				)
			)
		)
	)
	(zone
		(net "P1V8_STBY")
		(layer "In4.Cu")
		(hatch none 0.5)
		(connect_pads
			(clearance 0.5)
		)
		(min_thickness 0.25)
		(fill yes
			(thermal_gap 0.5)
			(thermal_bridge_width 0.5)
			(island_removal_mode 0)
		)
		(polygon
			(pts
				(xy 76.736194 -164.9095) (xy 72.6567 -168.988994) (xy 72.6567 -185.016394) (xy 68.582794 -189.0903)
				(xy 53.540406 -189.0903) (xy 34.266124 -169.816018) (xy 34.266124 -166.615618) (xy 33.927796 -166.27729)
				(xy 27.806904 -166.27729) (xy 27.803094 -166.2811) (xy 27.645106 -166.2811) (xy 27.641296 -166.27729)
				(xy 14.840204 -166.27729) (xy 14.356334 -166.76116) (xy 14.356334 -172.953172) (xy 17.90446 -176.501298)
				(xy 23.527766 -176.501298) (xy 25.086818 -178.06035) (xy 25.086818 -184.888124) (xy 25.406096 -185.207402)
				(xy 28.898088 -185.207402)
				(arc
					(start 28.89885 -185.207402)
					(mid 28.980896 -185.223912)
					(end 29.050488 -185.270394)
				)
				(xy 36.510214 -192.73012) (xy 83.936586 -192.73012) (xy 84.3407 -192.326006) (xy 84.3407 -165.813994)
				(xy 83.436206 -164.9095)
			)
		)
	)
	(zone
		(net "P12V_STBY")
		(layer "In4.Cu")
		(hatch none 0.5)
		(connect_pads
			(clearance 0.5)
		)
		(min_thickness 0.25)
		(fill yes
			(thermal_gap 0.5)
			(thermal_bridge_width 0.5)
			(island_removal_mode 0)
		)
		(polygon
			(pts
				(xy 74.30008 -1.27)
				(arc
					(start 74.30008 -109.050074)
					(mid 73.635213 -110.655205)
					(end 72.030082 -111.320072)
				)
				(arc
					(start 31.530036 -111.320072)
					(mid 29.924905 -110.655205)
					(end 29.260038 -109.050074)
				)
				(xy 29.260038 -108.932218) (xy 1.725168 -108.932218) (xy 1.27 -109.387386) (xy 1.27 -182.095394)
				(xy 1.693164 -182.518558) (xy 5.091938 -182.518558) (xy 5.092192 -182.518304) (xy 13.542772 -182.518304)
				(xy 16.23187 -185.207402) (xy 24.327104 -185.207402) (xy 24.705818 -184.828688) (xy 24.705818 -178.218338)
				(xy 23.369778 -176.882298) (xy 17.746472 -176.882298) (xy 13.975334 -173.11116) (xy 13.975334 -132.436616)
				(xy 26.359866 -120.052084) (xy 71.977504 -120.052084) (xy 77.945488 -114.0841) (xy 83.51139 -114.0841)
				(xy 88.5825 -109.01299) (xy 88.5825 -101.724206) (xy 83.900518 -97.042224) (xy 83.900518 -9.36752)
				(xy 88.064848 -5.20319) (xy 105.471976 -5.20319) (xy 111.330486 -11.0617) (xy 128.937512 -11.0617)
				(xy 129.57429 -11.698478) (xy 134.893812 -11.698478) (xy 137.051034 -13.8557) (xy 141.201394 -13.8557)
				(xy 142.217394 -14.8717) (xy 155.8036 -14.8717) (xy 158.230316 -12.444984) (xy 195.18503 -12.444984)
				(xy 201.757788 -19.017742) (xy 207.31734 -19.017742) (xy 211.347304 -14.987778) (xy 211.347304 -1.736598)
				(xy 210.880706 -1.27)
			)
		)
		(polygon
			(pts
				(arc
					(start 83.741768 -94.492572)
					(mid 83.358228 -94.109032)
					(end 82.974688 -94.492572)
				)
				(arc
					(start 82.974688 -95.381826)
					(mid 83.358355 -95.765112)
					(end 83.741768 -95.381572)
				)
			)
		)
		(polygon
			(pts
				(arc
					(start 77.667358 -92.911168)
					(mid 77.283818 -92.527628)
					(end 76.900278 -92.911168)
				)
				(arc
					(start 76.900278 -93.800422)
					(mid 77.283945 -94.183708)
					(end 77.667358 -93.800168)
				)
			)
		)
		(polygon
			(pts
				(arc
					(start 78.505558 -89.710768)
					(mid 78.122018 -89.327228)
					(end 77.738478 -89.710768)
				)
				(arc
					(start 77.738478 -90.600022)
					(mid 78.122145 -90.983308)
					(end 78.505558 -90.599768)
				)
			)
		)
		(polygon
			(pts
				(arc
					(start 83.741768 -88.10498)
					(mid 83.358101 -87.721694)
					(end 82.974688 -88.105234)
				)
				(arc
					(start 82.974688 -88.994234)
					(mid 83.358228 -89.377774)
					(end 83.741768 -88.994234)
				)
			)
		)
		(polygon
			(pts
				(arc
					(start 77.667358 -86.510368)
					(mid 77.283818 -86.126828)
					(end 76.900278 -86.510368)
				)
				(arc
					(start 76.900278 -87.399622)
					(mid 77.283945 -87.782908)
					(end 77.667358 -87.399368)
				)
			)
		)
		(polygon
			(pts
				(arc
					(start 78.505558 -83.335368)
					(mid 78.122018 -82.951828)
					(end 77.738478 -83.335368)
				)
				(arc
					(start 77.738478 -84.224622)
					(mid 78.122145 -84.607908)
					(end 78.505558 -84.224368)
				)
			)
		)
		(polygon
			(pts
				(arc
					(start 83.741768 -81.705196)
					(mid 83.358228 -81.321656)
					(end 82.974688 -81.705196)
				)
				(arc
					(start 82.974688 -82.59445)
					(mid 83.358355 -82.977736)
					(end 83.741768 -82.594196)
				)
			)
		)
		(polygon
			(pts
				(arc
					(start 77.667358 -80.109568)
					(mid 77.283818 -79.726028)
					(end 76.900278 -80.109568)
				)
				(arc
					(start 76.900278 -80.998822)
					(mid 77.283945 -81.382108)
					(end 77.667358 -80.998568)
				)
			)
		)
		(polygon
			(pts
				(arc
					(start 78.505558 -76.909168)
					(mid 78.122018 -76.525628)
					(end 77.738478 -76.909168)
				)
				(arc
					(start 77.738478 -77.798422)
					(mid 78.122145 -78.181708)
					(end 78.505558 -77.798168)
				)
			)
		)
		(polygon
			(pts
				(arc
					(start 83.741768 -75.305158)
					(mid 83.358228 -74.921618)
					(end 82.974688 -75.305158)
				)
				(arc
					(start 82.974688 -76.194412)
					(mid 83.358355 -76.577698)
					(end 83.741768 -76.194158)
				)
			)
		)
		(polygon
			(pts
				(arc
					(start 77.667358 -73.708768)
					(mid 77.283818 -73.325228)
					(end 76.900278 -73.708768)
				)
				(arc
					(start 76.900278 -74.598022)
					(mid 77.283945 -74.981308)
					(end 77.667358 -74.597768)
				)
			)
		)
		(polygon
			(pts
				(arc
					(start 78.505558 -70.508368)
					(mid 78.122018 -70.124828)
					(end 77.738478 -70.508368)
				)
				(arc
					(start 77.738478 -71.397622)
					(mid 78.122145 -71.780908)
					(end 78.505558 -71.397368)
				)
			)
		)
		(polygon
			(pts
				(arc
					(start 77.658214 -67.321938)
					(mid 77.274547 -66.938652)
					(end 76.891134 -67.322192)
				)
				(arc
					(start 76.891134 -68.211192)
					(mid 77.274674 -68.594732)
					(end 77.658214 -68.211192)
				)
			)
		)
	)
	(zone
		(net "DDR_VREF")
		(layer "In4.Cu")
		(hatch none 0.5)
		(connect_pads
			(clearance 0.5)
		)
		(min_thickness 0.25)
		(fill yes
			(thermal_gap 0.5)
			(thermal_bridge_width 0.5)
			(island_removal_mode 0)
		)
		(polygon
			(pts
				(xy 17.68856 -133.870446) (xy 15.40256 -136.156446) (xy 15.40256 -139.805918) (xy 15.618714 -140.022072)
				(xy 16.464534 -140.022072) (xy 16.6878 -139.798806) (xy 16.6878 -135.441182) (xy 17.8562 -134.272782)
				(xy 26.73858 -134.272782) (xy 38.522148 -146.05635) (xy 38.522148 -146.110198) (xy 39.17315 -146.7612)
				(xy 42.989246 -146.7612) (xy 43.751246 -147.5232) (xy 44.310554 -147.5232) (xy 44.47032 -147.363434)
				(xy 44.47032 -144.812766) (xy 44.386754 -144.7292) (xy 38.925246 -144.7292) (xy 38.70452 -144.949926)
				(xy 38.237668 -144.949926) (xy 38.199568 -144.988026) (xy 38.04158 -144.988026) (xy 26.924 -133.870446)
			)
		)
	)
	(zone
		(net "GND")
		(layer "In4.Cu")
		(hatch none 0.5)
		(connect_pads
			(clearance 0.5)
		)
		(min_thickness 0.25)
		(fill yes
			(thermal_gap 0.5)
			(thermal_bridge_width 0.5)
			(island_removal_mode 0)
		)
		(polygon
			(pts
				(xy 1.27 -1.27) (xy 1.27 -108.133134) (xy 1.688084 -108.551218) (xy 29.260038 -108.551218) (xy 29.260038 -1.27)
			)
		)
		(polygon
			(pts
				(arc
					(start 26.249884 -7.858506)
					(mid 26.249884 -9.641586)
					(end 26.249884 -7.858506)
				)
			)
		)
		(polygon
			(pts
				(arc
					(start 14.249908 -5.358384)
					(mid 14.249908 -7.141464)
					(end 14.249908 -5.358384)
				)
			)
		)
	)
	(zone
		(net "PCE_AVDD")
		(layer "In4.Cu")
		(hatch none 0.5)
		(connect_pads
			(clearance 0.5)
		)
		(min_thickness 0.25)
		(fill yes
			(thermal_gap 0.5)
			(thermal_bridge_width 0.5)
			(island_removal_mode 0)
		)
		(polygon
			(pts
				(xy 181.201822 -70.331584) (xy 178.98872 -72.544686) (xy 178.98872 -74.820526) (xy 178.1937 -75.615546)
				(xy 178.1937 -80.204056) (xy 180.387244 -82.3976) (xy 197.897242 -82.3976) (xy 201.900028 -78.394814)
				(xy 201.900028 -75.883262)
				(arc
					(start 201.5998 -75.883262)
					(mid 201.21626 -75.499849)
					(end 201.599546 -75.116182)
				)
				(xy 201.900028 -75.116182)
				(arc
					(start 201.900028 -74.140314)
					(mid 201.766059 -74.248467)
					(end 201.598276 -74.287126)
				)
				(arc
					(start 200.79843 -74.287126)
					(mid 200.41489 -73.903713)
					(end 200.798176 -73.520046)
				)
				(arc
					(start 201.598276 -73.520046)
					(mid 201.766064 -73.558695)
					(end 201.900028 -73.666858)
				)
				(xy 201.900028 -73.482708)
				(arc
					(start 201.602086 -73.483978)
					(mid 201.217276 -73.101835)
					(end 201.599292 -72.716898)
				)
				(xy 201.900028 -72.715628)
				(arc
					(start 201.900028 -72.528176)
					(mid 201.47165 -72.661431)
					(end 201.20991 -72.297036)
				)
				(arc
					(start 201.210926 -71.502524)
					(mid 201.241646 -71.352629)
					(end 201.328528 -71.22668)
				)
				(xy 200.433432 -70.331584) (xy 188.824362 -70.331584) (xy 188.823346 -70.3326) (xy 188.696854 -70.3326)
				(xy 188.695838 -70.331584) (xy 188.062362 -70.331584) (xy 188.061346 -70.3326) (xy 187.934854 -70.3326)
				(xy 187.933838 -70.331584)
			)
		)
		(polygon
			(pts
				(arc
					(start 200.357994 -73.899268)
					(mid 199.999219 -73.54189)
					(end 199.641714 -73.900538)
				)
				(xy 199.643492 -74.691494) (xy 199.643492 -74.692256)
				(arc
					(start 199.643492 -74.695558)
					(mid 200.002394 -75.052936)
					(end 200.359772 -74.694034)
				)
				(xy 200.357994 -73.900538)
			)
		)
		(polygon
			(pts
				(arc
					(start 199.557894 -73.899268)
					(mid 199.199119 -73.54189)
					(end 198.841614 -73.900538)
				)
				(arc
					(start 198.843392 -74.693018)
					(mid 199.202294 -75.050396)
					(end 199.559672 -74.691494)
				)
				(xy 199.557894 -73.900538) (xy 199.557894 -73.899776)
			)
		)
		(polygon
			(pts
				(arc
					(start 195.557902 -73.900538)
					(mid 195.200397 -73.54189)
					(end 194.841622 -73.899268)
				)
				(xy 194.841622 -73.899776) (xy 194.841622 -73.903332) (xy 194.840352 -74.70521)
				(arc
					(start 194.840352 -74.706988)
					(mid 195.197984 -75.065636)
					(end 195.556632 -74.708004)
				)
				(xy 195.556632 -74.706988)
			)
		)
		(polygon
			(pts
				(arc
					(start 194.757802 -73.903332)
					(mid 194.403091 -73.541891)
					(end 194.041522 -73.896474)
				)
				(arc
					(start 194.03441 -74.698606)
					(mid 194.389248 -75.060048)
					(end 194.75069 -74.70521)
				)
			)
		)
		(polygon
			(pts
				(arc
					(start 197.157848 -73.89622)
					(mid 196.796025 -73.541889)
					(end 196.441568 -73.903586)
				)
				(arc
					(start 196.44995 -74.702162)
					(mid 196.8119 -75.056492)
					(end 197.16623 -74.694542)
				)
			)
		)
		(polygon
			(pts
				(arc
					(start 197.957948 -73.895712)
					(mid 197.595617 -73.541888)
					(end 197.241668 -73.904094)
				)
				(arc
					(start 197.251066 -74.70394)
					(mid 197.613524 -75.057762)
					(end 197.967346 -74.695304)
				)
			)
		)
		(polygon
			(pts
				(arc
					(start 192.35801 -73.899522)
					(mid 191.999743 -73.541636)
					(end 191.64173 -73.899776)
				)
				(arc
					(start 191.64173 -74.699622)
					(mid 191.99987 -75.057762)
					(end 192.35801 -74.699622)
				)
			)
		)
		(polygon
			(pts
				(arc
					(start 193.157856 -73.90003)
					(mid 192.799716 -73.541636)
					(end 192.441576 -73.90003)
				)
				(xy 192.44183 -74.699622)
				(arc
					(start 192.44183 -74.699876)
					(mid 192.800097 -75.058016)
					(end 193.15811 -74.699622)
				)
			)
		)
	)
	(zone
		(net "P3V3_STBY")
		(layer "In4.Cu")
		(hatch none 0.5)
		(connect_pads
			(clearance 0.5)
		)
		(min_thickness 0.25)
		(fill yes
			(thermal_gap 0.5)
			(thermal_bridge_width 0.5)
			(island_removal_mode 0)
		)
		(polygon
			(pts
				(xy 145.909284 -90.5891) (xy 145.56994 -90.928444) (xy 145.56994 -104.753156) (xy 145.858484 -105.0417)
				(xy 157.812994 -105.0417) (xy 170.5737 -117.802406) (xy 170.5737 -133.347206) (xy 175.110394 -137.8839)
				(xy 182.704994 -137.8839) (xy 196.344794 -151.5237) (xy 206.804006 -151.5237) (xy 207.337406 -150.9903)
				(xy 208.734406 -150.9903) (xy 209.2833 -150.441406) (xy 209.2833 -137.492994) (xy 208.074006 -136.2837)
				(xy 208.048606 -136.2837) (xy 200.7997 -129.034794) (xy 200.7997 -122.786394) (xy 199.184006 -121.1707)
				(xy 184.655206 -121.1707) (xy 183.2737 -119.789194) (xy 183.2737 -106.352594) (xy 172.573442 -95.652336)
				(xy 169.498264 -95.652336) (xy 165.044628 -91.1987) (xy 150.746206 -91.1987) (xy 150.136606 -90.5891)
			)
		)
	)
	(zone
		(net "P1V15_STBY")
		(layer "In4.Cu")
		(hatch none 0.5)
		(connect_pads
			(clearance 0.5)
		)
		(min_thickness 0.25)
		(fill yes
			(thermal_gap 0.5)
			(thermal_bridge_width 0.5)
			(island_removal_mode 0)
		)
		(polygon
			(pts
				(xy 40.607234 -132.33146) (xy 37.026596 -135.912098) (xy 37.026596 -140.590016) (xy 37.641784 -141.205204)
				(xy 43.949112 -141.205204) (xy 44.85132 -142.107412) (xy 44.85132 -149.159214) (xy 43.748452 -150.261828)
				(xy 43.748452 -150.262082) (xy 43.692826 -150.317708) (xy 32.107124 -150.317708) (xy 28.443936 -153.980896)
				(xy 28.443936 -165.486842) (xy 28.853384 -165.89629) (xy 33.927796 -165.89629) (xy 34.276538 -165.547548)
				(xy 65.148206 -165.547548) (xy 76.352654 -154.3431) (xy 77.645006 -154.3431) (xy 78.6257 -153.362406)
				(xy 78.6257 -138.889994) (xy 72.067166 -132.33146)
			)
		)
	)
	(zone
		(net "GND")
		(layer "In4.Cu")
		(hatch none 0.5)
		(connect_pads
			(clearance 0.5)
		)
		(min_thickness 0.25)
		(fill yes
			(thermal_gap 0.5)
			(thermal_bridge_width 0.5)
			(island_removal_mode 0)
		)
		(polygon
			(pts
				(xy 5.25018 -182.899304) (xy 5.249926 -182.899558) (xy 1.715008 -182.899558) (xy 1.27 -183.344566)
				(xy 1.27 -183.700166) (xy 5.785104 -192.73012) (xy 35.971226 -192.73012) (xy 28.829508 -185.588402)
				(xy 16.073882 -185.588402) (xy 13.384784 -182.899304)
			)
		)
	)
	(zone
		(net "P0V975")
		(layer "In4.Cu")
		(hatch none 0.5)
		(connect_pads
			(clearance 0.5)
		)
		(min_thickness 0.25)
		(fill yes
			(thermal_gap 0.5)
			(thermal_bridge_width 0.5)
			(island_removal_mode 0)
		)
		(polygon
			(pts
				(xy 188.632846 -60.6552) (xy 188.4934 -60.794646) (xy 188.4934 -69.697854) (xy 188.82233 -70.026784)
				(xy 200.559924 -70.026784)
				(arc
					(start 201.210926 -70.677786)
					(mid 201.331694 -70.422519)
					(end 201.594466 -70.319138)
				)
				(arc
					(start 202.405234 -70.320916)
					(mid 202.788012 -70.705218)
					(end 202.40371 -71.087996)
				)
				(xy 201.619358 -71.086218)
				(arc
					(start 201.657712 -71.124826)
					(mid 201.865612 -71.231886)
					(end 201.972672 -71.439786)
				)
				(xy 202.204828 -71.671688) (xy 202.204828 -72.714358)
				(arc
					(start 202.395582 -72.713596)
					(mid 202.780646 -73.095612)
					(end 202.39863 -73.480676)
				)
				(xy 202.204828 -73.481438) (xy 202.204828 -75.116182)
				(arc
					(start 202.399646 -75.116182)
					(mid 202.783186 -75.499722)
					(end 202.399646 -75.883262)
				)
				(xy 202.204828 -75.883262) (xy 202.204828 -78.394814) (xy 203.337414 -79.5274) (xy 203.393294 -79.5274)
				(xy 206.5147 -82.648806) (xy 206.5147 -104.587294) (xy 204.675994 -106.426) (xy 189.893194 -106.426)
				(xy 189.5983 -106.720894) (xy 189.5983 -112.747806) (xy 189.804294 -112.9538) (xy 211.172806 -112.9538)
				(xy 219.897706 -104.2289) (xy 224.164906 -104.2289) (xy 224.7392 -103.654606) (xy 224.7392 -72.621394)
				(xy 212.811106 -60.6933) (xy 209.991706 -60.6933) (xy 209.953606 -60.6552)
			)
		)
		(polygon
			(pts
				(arc
					(start 216.573354 -79.113126)
					(mid 216.573354 -78.574646)
					(end 216.034874 -78.574646)
				)
				(xy 216.03462 -78.574392) (xy 215.226392 -79.38262)
				(arc
					(start 215.226646 -79.382874)
					(mid 215.226646 -79.921354)
					(end 215.765126 -79.921354)
				)
				(xy 215.76538 -79.921608) (xy 216.573354 -79.11338)
			)
		)
		(polygon
			(pts
				(arc
					(start 217.716354 -75.176126)
					(mid 217.716354 -74.637646)
					(end 217.177874 -74.637646)
				)
				(xy 217.17762 -74.637392) (xy 216.369392 -75.44562)
				(arc
					(start 216.369646 -75.445874)
					(mid 216.369646 -75.984354)
					(end 216.908126 -75.984354)
				)
				(xy 216.90838 -75.984608) (xy 217.716354 -75.17638)
			)
		)
		(polygon
			(pts
				(arc
					(start 216.192354 -73.652126)
					(mid 216.192354 -73.113646)
					(end 215.653874 -73.113646)
				)
				(xy 215.65362 -73.113392) (xy 214.845392 -73.92162)
				(arc
					(start 214.845646 -73.921874)
					(mid 214.845646 -74.460354)
					(end 215.384126 -74.460354)
				)
				(xy 215.38438 -74.460608) (xy 216.192354 -73.65238)
			)
		)
		(polygon
			(pts
				(arc
					(start 214.795354 -72.255126)
					(mid 214.795354 -71.716646)
					(end 214.256874 -71.716646)
				)
				(xy 214.25662 -71.716392) (xy 213.448392 -72.52462)
				(arc
					(start 213.448646 -72.524874)
					(mid 213.448646 -73.063354)
					(end 213.987126 -73.063354)
				)
				(xy 213.98738 -73.063608) (xy 214.795354 -72.25538)
			)
		)
		(polygon
			(pts
				(arc
					(start 201.978768 -69.097398)
					(mid 201.58837 -68.720716)
					(end 201.211688 -69.111114)
				)
				(arc
					(start 201.225658 -69.906388)
					(mid 201.615929 -70.283322)
					(end 201.992738 -69.892926)
				)
			)
		)
		(polygon
			(pts
				(arc
					(start 215.303354 -68.953126)
					(mid 215.303354 -68.414646)
					(end 214.764874 -68.414646)
				)
				(xy 214.76462 -68.414392) (xy 213.956392 -69.22262)
				(arc
					(start 213.956646 -69.222874)
					(mid 213.956646 -69.761354)
					(end 214.495126 -69.761354)
				)
				(xy 214.49538 -69.761608) (xy 215.303354 -68.95338)
			)
		)
		(polygon
			(pts
				(arc
					(start 201.599546 -67.911726)
					(mid 201.212197 -68.291329)
					(end 201.591672 -68.678806)
				)
				(arc
					(start 202.39609 -68.68668)
					(mid 202.78344 -68.30695)
					(end 202.40371 -67.9196)
				)
			)
		)
		(polygon
			(pts
				(arc
					(start 213.779354 -67.479926)
					(mid 213.779354 -66.941446)
					(end 213.240874 -66.941446)
				)
				(xy 213.24062 -66.941192) (xy 212.432392 -67.74942)
				(arc
					(start 212.432646 -67.749674)
					(mid 212.432646 -68.288154)
					(end 212.971126 -68.288154)
				)
				(xy 212.97138 -68.288408) (xy 213.779354 -67.48018)
			)
		)
		(polygon
			(pts
				(arc
					(start 201.983086 -66.712084)
					(mid 201.602594 -66.325496)
					(end 201.216006 -66.705988)
				)
				(arc
					(start 201.209656 -67.49923)
					(mid 201.590021 -67.886073)
					(end 201.976736 -67.50558)
				)
			)
		)
		(polygon
			(pts
				(arc
					(start 212.306154 -65.828926)
					(mid 212.306154 -65.290446)
					(end 211.767674 -65.290446)
				)
				(xy 211.76742 -65.290192) (xy 210.959192 -66.09842)
				(arc
					(start 210.959446 -66.098674)
					(mid 210.959446 -66.637154)
					(end 211.497926 -66.637154)
				)
				(xy 211.49818 -66.637408) (xy 212.306154 -65.82918)
			)
		)
		(polygon
			(pts
				(arc
					(start 212.137498 -63.3857)
					(mid 212.137498 -62.84722)
					(end 211.599018 -62.84722)
				)
				(xy 211.598764 -62.846966) (xy 210.790536 -63.655194)
				(arc
					(start 210.79079 -63.655448)
					(mid 210.79079 -64.193928)
					(end 211.32927 -64.193928)
				)
				(xy 211.329524 -64.194182) (xy 212.137498 -63.385954)
			)
		)
	)
	(zone
		(layer "In5.Cu")
		(hatch none 0.5)
		(connect_pads
			(clearance 0)
		)
		(min_thickness 0.25)
		(keepout
			(tracks not_allowed)
			(vias allowed)
			(pads allowed)
			(copperpour not_allowed)
			(footprints allowed)
		)
		(placement
			(enabled no)
			(sheetname "")
		)
		(fill
			(thermal_gap 0.5)
			(thermal_bridge_width 0.5)
			(island_removal_mode 0)
		)
		(polygon
			(pts
				(xy 191.74206 -87.206328) (xy 191.646048 -87.110316)
				(arc
					(start 191.646048 -87.107776)
					(mid 191.587444 -87.006021)
					(end 191.564514 -86.89086)
				)
				(arc
					(start 191.564514 -86.89086)
					(mid 191.809616 -86.42662)
					(end 191.741806 -86.947248)
				)
				(arc
					(start 191.741806 -86.947248)
					(mid 191.760638 -86.984851)
					(end 191.787018 -87.017606)
				)
				(xy 191.8589 -87.089488)
				(arc
					(start 191.998092 -86.950296)
					(mid 191.998092 -86.411308)
					(end 191.459104 -86.411308)
				)
				(arc
					(start 190.835534 -87.035132)
					(mid 190.828455 -87.576246)
					(end 191.369696 -87.578692)
				)
				(xy 191.50838 -87.440008)
				(arc
					(start 191.43599 -87.367364)
					(mid 191.403697 -87.341323)
					(end 191.366648 -87.32266)
				)
				(arc
					(start 191.366648 -87.32266)
					(mid 190.845812 -87.389575)
					(end 191.310514 -87.145114)
				)
				(arc
					(start 191.310514 -87.145114)
					(mid 191.425021 -87.168207)
					(end 191.52616 -87.226648)
				)
				(xy 191.5287 -87.226648) (xy 191.552576 -87.250778) (xy 191.55283 -87.250778) (xy 191.62522 -87.323168)
			)
		)
	)
	(zone
		(layer "In5.Cu")
		(hatch none 0.5)
		(connect_pads
			(clearance 0)
		)
		(min_thickness 0.25)
		(keepout
			(tracks not_allowed)
			(vias allowed)
			(pads allowed)
			(copperpour not_allowed)
			(footprints allowed)
		)
		(placement
			(enabled no)
			(sheetname "")
		)
		(fill
			(thermal_gap 0.5)
			(thermal_bridge_width 0.5)
			(island_removal_mode 0)
		)
		(polygon
			(pts
				(arc
					(start 114.78514 -36.800282)
					(mid 114.300127 -36.314888)
					(end 113.81486 -36.800028)
				)
				(arc
					(start 113.81486 -37.22624)
					(mid 113.873138 -37.245765)
					(end 113.93424 -37.252402)
				)
				(arc
					(start 114.11204 -37.252402)
					(mid 114.172264 -37.233504)
					(end 114.210846 -37.183568)
				)
				(arc
					(start 114.210846 -37.183568)
					(mid 114.304808 -36.406292)
					(end 114.379756 -37.1856)
				)
				(arc
					(start 114.379756 -37.1856)
					(mid 114.302577 -37.338977)
					(end 114.148616 -37.414962)
				)
				(xy 114.14633 -37.417502) (xy 113.89995 -37.417502)
				(arc
					(start 113.89868 -37.415978)
					(mid 113.856427 -37.410724)
					(end 113.81486 -37.4015)
				)
				(arc
					(start 113.81486 -37.570918)
					(mid 113.874266 -37.57966)
					(end 113.93424 -37.582602)
				)
				(xy 114.14633 -37.582602)
				(arc
					(start 114.148616 -37.585142)
					(mid 114.302555 -37.661149)
					(end 114.379756 -37.814504)
				)
				(arc
					(start 114.379756 -37.814504)
					(mid 114.304807 -38.593781)
					(end 114.210846 -37.816536)
				)
				(arc
					(start 114.210846 -37.816536)
					(mid 114.172235 -37.766642)
					(end 114.11204 -37.747702)
				)
				(xy 113.89995 -37.747702)
				(arc
					(start 113.899188 -37.74694)
					(mid 113.85691 -37.743892)
					(end 113.81486 -37.738558)
				)
				(arc
					(start 113.81486 -38.200076)
					(mid 114.3 -38.685216)
					(end 114.78514 -38.200076)
				)
			)
		)
	)
	(zone
		(net "GND")
		(layer "In5.Cu")
		(hatch none 0.5)
		(connect_pads
			(clearance 0.5)
		)
		(min_thickness 0.25)
		(fill yes
			(thermal_gap 0.5)
			(thermal_bridge_width 0.5)
			(island_removal_mode 0)
		)
		(polygon
			(pts
				(xy 188.443362 -0.763016) (xy 188.443362 -2.715514) (xy 85.138514 -2.715514) (xy 85.138514 -2.794)
				(xy 232.206038 -2.794) (xy 232.206038 -183.340248) (xy 228.273356 -191.20612) (xy 151.026622 -191.20612)
				(xy 147.09394 -183.340248) (xy 147.09394 -97.61093) (xy 145.183098 -97.61093) (xy 145.183098 -94.285816)
				(xy 147.09394 -94.285816) (xy 147.09394 -93.971872) (xy 145.062956 -93.971872)
				(arc
					(start 145.062956 -183.76392)
					(mid 145.069351 -183.818347)
					(end 145.088102 -183.869838)
				)
				(arc
					(start 149.706076 -193.10604)
					(mid 149.793376 -193.201687)
					(end 149.917912 -193.237104)
				)
				(arc
					(start 229.382066 -193.237104)
					(mid 229.506557 -193.201614)
					(end 229.593902 -193.10604)
				)
				(arc
					(start 234.211876 -183.869838)
					(mid 234.230599 -183.818341)
					(end 234.237022 -183.76392)
				)
				(arc
					(start 234.237022 -0.999998)
					(mid 234.167612 -0.832426)
					(end 234.00004 -0.763016)
				)
			)
		)
	)
	(zone
		(layer "In5.Cu")
		(hatch none 0.5)
		(connect_pads
			(clearance 0)
		)
		(min_thickness 0.25)
		(keepout
			(tracks not_allowed)
			(vias allowed)
			(pads allowed)
			(copperpour not_allowed)
			(footprints allowed)
		)
		(placement
			(enabled no)
			(sheetname "")
		)
		(fill
			(thermal_gap 0.5)
			(thermal_bridge_width 0.5)
			(island_removal_mode 0)
		)
		(polygon
			(pts
				(arc
					(start 216.573354 -79.113126)
					(mid 216.573354 -78.574646)
					(end 216.034874 -78.574646)
				)
				(xy 216.03462 -78.574392) (xy 215.78316 -78.825852)
				(arc
					(start 215.919558 -78.96225)
					(mid 215.993979 -78.998001)
					(end 216.074498 -78.979522)
				)
				(arc
					(start 216.074498 -78.979522)
					(mid 216.494344 -78.656544)
					(end 216.164414 -79.070962)
				)
				(arc
					(start 216.164414 -79.070962)
					(mid 216.007418 -79.125728)
					(end 215.85047 -79.070708)
				)
				(xy 215.848184 -79.070708) (xy 215.829642 -79.052166) (xy 215.693244 -78.915768) (xy 215.567514 -79.041498)
				(xy 215.722454 -79.196438)
				(arc
					(start 215.722454 -79.198724)
					(mid 215.777592 -79.355494)
					(end 215.722962 -79.512414)
				)
				(arc
					(start 215.722962 -79.512414)
					(mid 215.308536 -79.842351)
					(end 215.631522 -79.422498)
				)
				(arc
					(start 215.631522 -79.422498)
					(mid 215.649798 -79.342107)
					(end 215.613996 -79.267812)
				)
				(xy 215.477598 -79.131414) (xy 215.226392 -79.38262)
				(arc
					(start 215.226646 -79.382874)
					(mid 215.226646 -79.921354)
					(end 215.765126 -79.921354)
				)
				(xy 215.76538 -79.921608) (xy 216.573354 -79.11338)
			)
		)
	)
	(zone
		(layer "In5.Cu")
		(hatch none 0.5)
		(connect_pads
			(clearance 0)
		)
		(min_thickness 0.25)
		(keepout
			(tracks not_allowed)
			(vias allowed)
			(pads allowed)
			(copperpour not_allowed)
			(footprints allowed)
		)
		(placement
			(enabled no)
			(sheetname "")
		)
		(fill
			(thermal_gap 0.5)
			(thermal_bridge_width 0.5)
			(island_removal_mode 0)
		)
		(polygon
			(pts
				(arc
					(start 107.585002 -36.800282)
					(mid 107.099989 -36.314888)
					(end 106.614722 -36.800028)
				)
				(xy 106.614722 -37.252402)
				(arc
					(start 106.8959 -37.252402)
					(mid 106.961126 -37.233393)
					(end 107.005882 -37.182298)
				)
				(arc
					(start 107.005882 -37.182298)
					(mid 107.10896 -36.406414)
					(end 107.177078 -37.186108)
				)
				(arc
					(start 107.177078 -37.186108)
					(mid 107.091755 -37.340131)
					(end 106.932476 -37.415216)
				)
				(xy 106.93019 -37.417502) (xy 106.614722 -37.417502) (xy 106.614722 -37.582602) (xy 106.93019 -37.582602)
				(arc
					(start 106.932476 -37.584888)
					(mid 107.091782 -37.659944)
					(end 107.177078 -37.813996)
				)
				(arc
					(start 107.177078 -37.813996)
					(mid 107.108959 -38.593653)
					(end 107.005882 -37.817806)
				)
				(arc
					(start 107.005882 -37.817806)
					(mid 106.961099 -37.766753)
					(end 106.8959 -37.747702)
				)
				(xy 106.614722 -37.747702)
				(arc
					(start 106.614722 -38.200076)
					(mid 107.099862 -38.685216)
					(end 107.585002 -38.200076)
				)
			)
		)
	)
	(zone
		(layer "In5.Cu")
		(hatch none 0.5)
		(connect_pads
			(clearance 0)
		)
		(min_thickness 0.25)
		(keepout
			(tracks not_allowed)
			(vias allowed)
			(pads allowed)
			(copperpour not_allowed)
			(footprints allowed)
		)
		(placement
			(enabled no)
			(sheetname "")
		)
		(fill
			(thermal_gap 0.5)
			(thermal_bridge_width 0.5)
			(island_removal_mode 0)
		)
		(polygon
			(pts
				(arc
					(start 118.385082 -36.800282)
					(mid 117.900069 -36.314888)
					(end 117.414802 -36.800028)
				)
				(arc
					(start 117.414802 -37.22624)
					(mid 117.47308 -37.245765)
					(end 117.534182 -37.252402)
				)
				(arc
					(start 117.711982 -37.252402)
					(mid 117.772206 -37.233504)
					(end 117.810788 -37.183568)
				)
				(arc
					(start 117.810788 -37.183568)
					(mid 117.90475 -36.406292)
					(end 117.979698 -37.1856)
				)
				(arc
					(start 117.979698 -37.1856)
					(mid 117.902519 -37.338977)
					(end 117.748558 -37.414962)
				)
				(xy 117.746272 -37.417502) (xy 117.499892 -37.417502)
				(arc
					(start 117.498622 -37.415978)
					(mid 117.456369 -37.410724)
					(end 117.414802 -37.4015)
				)
				(arc
					(start 117.414802 -37.570918)
					(mid 117.474208 -37.57966)
					(end 117.534182 -37.582602)
				)
				(xy 117.746272 -37.582602)
				(arc
					(start 117.748558 -37.585142)
					(mid 117.902497 -37.661149)
					(end 117.979698 -37.814504)
				)
				(arc
					(start 117.979698 -37.814504)
					(mid 117.904749 -38.593781)
					(end 117.810788 -37.816536)
				)
				(arc
					(start 117.810788 -37.816536)
					(mid 117.772177 -37.766642)
					(end 117.711982 -37.747702)
				)
				(xy 117.499892 -37.747702)
				(arc
					(start 117.49913 -37.74694)
					(mid 117.456852 -37.743892)
					(end 117.414802 -37.738558)
				)
				(arc
					(start 117.414802 -38.200076)
					(mid 117.899942 -38.685216)
					(end 118.385082 -38.200076)
				)
			)
		)
	)
	(zone
		(layer "In5.Cu")
		(hatch none 0.5)
		(connect_pads
			(clearance 0)
		)
		(min_thickness 0.25)
		(keepout
			(tracks not_allowed)
			(vias allowed)
			(pads allowed)
			(copperpour not_allowed)
			(footprints allowed)
		)
		(placement
			(enabled no)
			(sheetname "")
		)
		(fill
			(thermal_gap 0.5)
			(thermal_bridge_width 0.5)
			(island_removal_mode 0)
		)
		(polygon
			(pts
				(arc
					(start 214.795354 -72.255126)
					(mid 214.795354 -71.716646)
					(end 214.256874 -71.716646)
				)
				(xy 214.25662 -71.716392) (xy 214.00516 -71.967852)
				(arc
					(start 214.141558 -72.10425)
					(mid 214.215979 -72.140001)
					(end 214.296498 -72.121522)
				)
				(arc
					(start 214.296498 -72.121522)
					(mid 214.716344 -71.798544)
					(end 214.386414 -72.212962)
				)
				(arc
					(start 214.386414 -72.212962)
					(mid 214.229418 -72.267728)
					(end 214.07247 -72.212708)
				)
				(xy 214.070184 -72.212708) (xy 214.051642 -72.194166) (xy 213.915244 -72.057768) (xy 213.789514 -72.183498)
				(xy 213.944454 -72.338438)
				(arc
					(start 213.944454 -72.340724)
					(mid 213.999592 -72.497494)
					(end 213.944962 -72.654414)
				)
				(arc
					(start 213.944962 -72.654414)
					(mid 213.530536 -72.984351)
					(end 213.853522 -72.564498)
				)
				(arc
					(start 213.853522 -72.564498)
					(mid 213.871798 -72.484107)
					(end 213.835996 -72.409812)
				)
				(xy 213.699598 -72.273414) (xy 213.448392 -72.52462)
				(arc
					(start 213.448646 -72.524874)
					(mid 213.448646 -73.063354)
					(end 213.987126 -73.063354)
				)
				(xy 213.98738 -73.063608) (xy 214.795354 -72.25538)
			)
		)
	)
	(zone
		(layer "In5.Cu")
		(hatch none 0.5)
		(connect_pads
			(clearance 0)
		)
		(min_thickness 0.25)
		(keepout
			(tracks not_allowed)
			(vias allowed)
			(pads allowed)
			(copperpour not_allowed)
			(footprints allowed)
		)
		(placement
			(enabled no)
			(sheetname "")
		)
		(fill
			(thermal_gap 0.5)
			(thermal_bridge_width 0.5)
			(island_removal_mode 0)
		)
		(polygon
			(pts
				(arc
					(start 83.741768 -75.305158)
					(mid 83.358228 -74.921618)
					(end 82.974688 -75.305158)
				)
				(arc
					(start 82.974688 -76.193904)
					(mid 83.358101 -76.577698)
					(end 83.741768 -76.194158)
				)
				(xy 83.741768 -75.997308)
				(arc
					(start 83.637628 -75.997308)
					(mid 83.595778 -76.001802)
					(end 83.55584 -76.015088)
				)
				(arc
					(start 83.55584 -76.015088)
					(mid 83.235459 -76.430895)
					(end 83.39074 -75.92949)
				)
				(arc
					(start 83.39074 -75.92949)
					(mid 83.488315 -75.864448)
					(end 83.60156 -75.833986)
				)
				(xy 83.603338 -75.832208) (xy 83.741768 -75.832208) (xy 83.741768 -75.667108) (xy 83.603338 -75.667108)
				(arc
					(start 83.60156 -75.66533)
					(mid 83.488302 -75.634895)
					(end 83.39074 -75.569826)
				)
				(arc
					(start 83.39074 -75.569826)
					(mid 83.235468 -75.068438)
					(end 83.55584 -75.484228)
				)
				(arc
					(start 83.55584 -75.484228)
					(mid 83.59578 -75.497505)
					(end 83.637628 -75.502008)
				)
				(xy 83.741768 -75.502008)
			)
		)
	)
	(zone
		(layer "In5.Cu")
		(hatch none 0.5)
		(connect_pads
			(clearance 0)
		)
		(min_thickness 0.25)
		(keepout
			(tracks not_allowed)
			(vias allowed)
			(pads allowed)
			(copperpour not_allowed)
			(footprints allowed)
		)
		(placement
			(enabled no)
			(sheetname "")
		)
		(fill
			(thermal_gap 0.5)
			(thermal_bridge_width 0.5)
			(island_removal_mode 0)
		)
		(polygon
			(pts
				(arc
					(start 215.303354 -68.953126)
					(mid 215.303354 -68.414646)
					(end 214.764874 -68.414646)
				)
				(xy 214.76462 -68.414392) (xy 214.51316 -68.665852)
				(arc
					(start 214.649558 -68.80225)
					(mid 214.723979 -68.838001)
					(end 214.804498 -68.819522)
				)
				(arc
					(start 214.804498 -68.819522)
					(mid 215.224344 -68.496544)
					(end 214.894414 -68.910962)
				)
				(arc
					(start 214.894414 -68.910962)
					(mid 214.737418 -68.965728)
					(end 214.58047 -68.910708)
				)
				(xy 214.578184 -68.910708) (xy 214.559642 -68.892166) (xy 214.423244 -68.755768) (xy 214.297514 -68.881498)
				(xy 214.452454 -69.036438)
				(arc
					(start 214.452454 -69.038724)
					(mid 214.507592 -69.195494)
					(end 214.452962 -69.352414)
				)
				(arc
					(start 214.452962 -69.352414)
					(mid 214.038536 -69.682351)
					(end 214.361522 -69.262498)
				)
				(arc
					(start 214.361522 -69.262498)
					(mid 214.379798 -69.182107)
					(end 214.343996 -69.107812)
				)
				(xy 214.207598 -68.971414) (xy 213.956392 -69.22262)
				(arc
					(start 213.956646 -69.222874)
					(mid 213.956646 -69.761354)
					(end 214.495126 -69.761354)
				)
				(xy 214.49538 -69.761608) (xy 215.303354 -68.95338)
			)
		)
	)
	(zone
		(layer "In5.Cu")
		(hatch none 0.5)
		(connect_pads
			(clearance 0)
		)
		(min_thickness 0.25)
		(keepout
			(tracks not_allowed)
			(vias allowed)
			(pads allowed)
			(copperpour not_allowed)
			(footprints allowed)
		)
		(placement
			(enabled no)
			(sheetname "")
		)
		(fill
			(thermal_gap 0.5)
			(thermal_bridge_width 0.5)
			(island_removal_mode 0)
		)
		(polygon
			(pts
				(arc
					(start 141.785086 -32.000444)
					(mid 141.300073 -31.51505)
					(end 140.814806 -32.00019)
				)
				(arc
					(start 140.814806 -32.449008)
					(mid 140.833519 -32.451664)
					(end 140.852398 -32.452564)
				)
				(arc
					(start 141.068298 -32.452564)
					(mid 141.141891 -32.433136)
					(end 141.196314 -32.37992)
				)
				(arc
					(start 141.196314 -32.37992)
					(mid 141.316615 -31.606926)
					(end 141.371066 -32.387286)
				)
				(arc
					(start 141.371066 -32.387286)
					(mid 141.272664 -32.542063)
					(end 141.10462 -32.615632)
				)
				(xy 141.102588 -32.617664) (xy 140.818108 -32.617664) (xy 140.81633 -32.615886) (xy 140.814806 -32.615632)
				(xy 140.814806 -32.781494) (xy 140.852398 -32.782764) (xy 141.102588 -32.782764)
				(arc
					(start 141.10462 -32.784796)
					(mid 141.272554 -32.858118)
					(end 141.371066 -33.012634)
				)
				(arc
					(start 141.371066 -33.012634)
					(mid 141.317268 -33.793393)
					(end 141.19606 -33.020254)
				)
				(arc
					(start 141.19606 -33.020254)
					(mid 141.141732 -32.967187)
					(end 141.068298 -32.947864)
				)
				(xy 140.818108 -32.947864) (xy 140.817346 -32.947102) (xy 140.814806 -32.946848)
				(arc
					(start 140.814806 -33.399984)
					(mid 141.299946 -33.885124)
					(end 141.785086 -33.399984)
				)
			)
		)
	)
	(zone
		(layer "In5.Cu")
		(hatch none 0.5)
		(connect_pads
			(clearance 0)
		)
		(min_thickness 0.25)
		(keepout
			(tracks not_allowed)
			(vias allowed)
			(pads allowed)
			(copperpour not_allowed)
			(footprints allowed)
		)
		(placement
			(enabled no)
			(sheetname "")
		)
		(fill
			(thermal_gap 0.5)
			(thermal_bridge_width 0.5)
			(island_removal_mode 0)
		)
		(polygon
			(pts
				(xy 179.981098 -26.38933) (xy 180.068982 -26.225246) (xy 179.878228 -26.034238) (xy 179.75707 -25.969722)
				(xy 179.733702 -25.957276) (xy 179.726082 -25.93213) (xy 179.691792 -25.819862) (xy 179.684172 -25.794716)
				(xy 179.676552 -25.76957) (xy 179.676552 -25.769316) (xy 179.688744 -25.746202) (xy 179.70119 -25.723088)
				(arc
					(start 179.766468 -25.601168)
					(mid 180.179317 -24.964017)
					(end 179.878482 -25.661112)
				)
				(xy 179.813204 -25.782778) (xy 179.839874 -25.8699) (xy 179.93233 -25.919176) (xy 179.942744 -25.919176)
				(xy 179.954428 -25.931114) (xy 179.969414 -25.938988) (xy 179.972462 -25.948894) (xy 180.13172 -26.108152)
				(arc
					(start 180.43398 -25.543764)
					(mid 180.239312 -24.863383)
					(end 179.560982 -25.064974)
				)
				(arc
					(start 178.811174 -26.465022)
					(mid 179.015136 -27.138884)
					(end 179.688998 -26.934922)
				)
				(xy 179.918614 -26.50617) (xy 179.694078 -26.281888) (xy 179.635912 -26.250646) (xy 179.54879 -26.276808)
				(arc
					(start 179.483512 -26.398982)
					(mid 179.069114 -27.035277)
					(end 179.371498 -26.338784)
				)
				(xy 179.43703 -26.216864) (xy 179.449476 -26.19375) (xy 179.461922 -26.170636) (xy 179.487068 -26.163016)
				(xy 179.512214 -26.155396) (xy 179.624482 -26.121614) (xy 179.649628 -26.113994) (xy 179.672742 -26.12644)
				(xy 179.748434 -26.166826) (xy 179.758848 -26.166826) (xy 179.770786 -26.178764) (xy 179.785518 -26.186638)
				(xy 179.788566 -26.196798)
			)
		)
	)
	(zone
		(layer "In5.Cu")
		(hatch none 0.5)
		(connect_pads
			(clearance 0)
		)
		(min_thickness 0.25)
		(keepout
			(tracks not_allowed)
			(vias allowed)
			(pads allowed)
			(copperpour not_allowed)
			(footprints allowed)
		)
		(placement
			(enabled no)
			(sheetname "")
		)
		(fill
			(thermal_gap 0.5)
			(thermal_bridge_width 0.5)
			(island_removal_mode 0)
		)
		(polygon
			(pts
				(arc
					(start 190.448692 -84.156296)
					(mid 190.448692 -83.617308)
					(end 189.909704 -83.617308)
				)
				(arc
					(start 189.286134 -84.241132)
					(mid 189.279055 -84.782246)
					(end 189.820296 -84.784692)
				)
				(xy 189.959234 -84.645754)
				(arc
					(start 189.886844 -84.573618)
					(mid 189.854447 -84.54742)
					(end 189.817248 -84.52866)
				)
				(arc
					(start 189.817248 -84.52866)
					(mid 189.296412 -84.595575)
					(end 189.761114 -84.351114)
				)
				(arc
					(start 189.761114 -84.351114)
					(mid 189.875763 -84.374157)
					(end 189.977014 -84.432648)
				)
				(xy 189.979554 -84.432648) (xy 190.003684 -84.456778) (xy 190.07582 -84.529168) (xy 190.19266 -84.412328)
				(xy 190.096648 -84.316316)
				(arc
					(start 190.096648 -84.313776)
					(mid 190.038044 -84.212021)
					(end 190.015114 -84.09686)
				)
				(arc
					(start 190.015114 -84.09686)
					(mid 190.260216 -83.63262)
					(end 190.192406 -84.153248)
				)
				(arc
					(start 190.192406 -84.153248)
					(mid 190.211238 -84.190851)
					(end 190.237618 -84.223606)
				)
				(xy 190.3095 -84.295488)
			)
		)
	)
	(zone
		(layer "In5.Cu")
		(hatch none 0.5)
		(connect_pads
			(clearance 0)
		)
		(min_thickness 0.25)
		(keepout
			(tracks not_allowed)
			(vias allowed)
			(pads allowed)
			(copperpour not_allowed)
			(footprints allowed)
		)
		(placement
			(enabled no)
			(sheetname "")
		)
		(fill
			(thermal_gap 0.5)
			(thermal_bridge_width 0.5)
			(island_removal_mode 0)
		)
		(polygon
			(pts
				(xy 162.212782 -30.170374) (xy 162.300412 -30.006544) (xy 162.127946 -29.834078) (xy 162.007042 -29.769562)
				(xy 161.983928 -29.757116) (xy 161.976308 -29.73197) (xy 161.942018 -29.619702) (xy 161.942018 -29.619448)
				(xy 161.934398 -29.594556) (xy 161.926778 -29.56941) (xy 161.926778 -29.569156) (xy 161.93897 -29.546042)
				(xy 161.951416 -29.522928)
				(arc
					(start 162.016694 -29.401262)
					(mid 162.429543 -28.764111)
					(end 162.128708 -29.461206)
				)
				(xy 162.06343 -29.582618) (xy 162.0901 -29.66974) (xy 162.182302 -29.719016) (xy 162.192716 -29.719016)
				(xy 162.204654 -29.730954) (xy 162.219386 -29.738828) (xy 162.222434 -29.748734) (xy 162.36315 -29.88945)
				(arc
					(start 162.663632 -29.328618)
					(mid 162.47593 -28.684976)
					(end 161.83356 -28.877006)
				)
				(arc
					(start 161.083498 -30.277054)
					(mid 161.277046 -30.916626)
					(end 161.916618 -30.723078)
				)
				(xy 162.150044 -30.287214) (xy 161.944304 -30.081728) (xy 161.885884 -30.050486) (xy 161.798762 -30.076648)
				(arc
					(start 161.733484 -30.198822)
					(mid 161.320635 -30.835973)
					(end 161.62147 -30.138878)
				)
				(xy 161.687002 -30.016704) (xy 161.699448 -29.99359) (xy 161.711894 -29.970476) (xy 161.73704 -29.962856)
				(xy 161.762186 -29.955236) (xy 161.874454 -29.921454) (xy 161.899346 -29.913834) (xy 161.8996 -29.913834)
				(xy 161.922714 -29.92628) (xy 161.99866 -29.966666) (xy 162.009074 -29.966666) (xy 162.021012 -29.978604)
				(xy 162.035744 -29.986478) (xy 162.038792 -29.996384)
			)
		)
	)
	(zone
		(layer "In5.Cu")
		(hatch none 0.5)
		(connect_pads
			(clearance 0)
		)
		(min_thickness 0.25)
		(keepout
			(tracks not_allowed)
			(vias allowed)
			(pads allowed)
			(copperpour not_allowed)
			(footprints allowed)
		)
		(placement
			(enabled no)
			(sheetname "")
		)
		(fill
			(thermal_gap 0.5)
			(thermal_bridge_width 0.5)
			(island_removal_mode 0)
		)
		(polygon
			(pts
				(arc
					(start 109.3851 -35.600386)
					(mid 108.900087 -35.114992)
					(end 108.41482 -35.600132)
				)
				(arc
					(start 108.41482 -36.026344)
					(mid 108.473098 -36.045869)
					(end 108.5342 -36.052506)
				)
				(arc
					(start 108.712 -36.052506)
					(mid 108.772224 -36.033608)
					(end 108.810806 -35.983672)
				)
				(arc
					(start 108.810806 -35.983672)
					(mid 108.904768 -35.206396)
					(end 108.979716 -35.985704)
				)
				(arc
					(start 108.979716 -35.985704)
					(mid 108.902537 -36.139081)
					(end 108.748576 -36.215066)
				)
				(xy 108.74629 -36.217606) (xy 108.49991 -36.217606)
				(arc
					(start 108.49864 -36.216082)
					(mid 108.456387 -36.210828)
					(end 108.41482 -36.201604)
				)
				(arc
					(start 108.41482 -36.371022)
					(mid 108.474226 -36.379764)
					(end 108.5342 -36.382706)
				)
				(xy 108.74629 -36.382706)
				(arc
					(start 108.748576 -36.385246)
					(mid 108.902515 -36.461253)
					(end 108.979716 -36.614608)
				)
				(arc
					(start 108.979716 -36.614608)
					(mid 108.904767 -37.393885)
					(end 108.810806 -36.61664)
				)
				(arc
					(start 108.810806 -36.61664)
					(mid 108.772195 -36.566746)
					(end 108.712 -36.547806)
				)
				(xy 108.49991 -36.547806)
				(arc
					(start 108.499148 -36.547044)
					(mid 108.45687 -36.543996)
					(end 108.41482 -36.538662)
				)
				(arc
					(start 108.41482 -37.00018)
					(mid 108.89996 -37.48532)
					(end 109.3851 -37.00018)
				)
			)
		)
	)
	(zone
		(layer "In5.Cu")
		(hatch none 0.5)
		(connect_pads
			(clearance 0)
		)
		(min_thickness 0.25)
		(keepout
			(tracks not_allowed)
			(vias allowed)
			(pads allowed)
			(copperpour not_allowed)
			(footprints allowed)
		)
		(placement
			(enabled no)
			(sheetname "")
		)
		(fill
			(thermal_gap 0.5)
			(thermal_bridge_width 0.5)
			(island_removal_mode 0)
		)
		(polygon
			(pts
				(arc
					(start 213.779354 -67.479926)
					(mid 213.779354 -66.941446)
					(end 213.240874 -66.941446)
				)
				(xy 213.24062 -66.941192) (xy 212.98916 -67.192652)
				(arc
					(start 213.125558 -67.32905)
					(mid 213.199979 -67.364801)
					(end 213.280498 -67.346322)
				)
				(arc
					(start 213.280498 -67.346322)
					(mid 213.700344 -67.023344)
					(end 213.370414 -67.437762)
				)
				(arc
					(start 213.370414 -67.437762)
					(mid 213.213418 -67.492528)
					(end 213.05647 -67.437508)
				)
				(xy 213.054184 -67.437508) (xy 213.035642 -67.418966) (xy 212.899244 -67.282568) (xy 212.773514 -67.408298)
				(xy 212.928454 -67.563238)
				(arc
					(start 212.928454 -67.565524)
					(mid 212.983592 -67.722294)
					(end 212.928962 -67.879214)
				)
				(arc
					(start 212.928962 -67.879214)
					(mid 212.514536 -68.209151)
					(end 212.837522 -67.789298)
				)
				(arc
					(start 212.837522 -67.789298)
					(mid 212.855798 -67.708907)
					(end 212.819996 -67.634612)
				)
				(xy 212.683598 -67.498214) (xy 212.432392 -67.74942)
				(arc
					(start 212.432646 -67.749674)
					(mid 212.432646 -68.288154)
					(end 212.971126 -68.288154)
				)
				(xy 212.97138 -68.288408) (xy 213.779354 -67.48018)
			)
		)
	)
	(zone
		(layer "In5.Cu")
		(hatch none 0.5)
		(connect_pads
			(clearance 0)
		)
		(min_thickness 0.25)
		(keepout
			(tracks allowed)
			(vias allowed)
			(pads allowed)
			(copperpour allowed)
			(footprints allowed)
		)
		(placement
			(enabled no)
			(sheetname "")
		)
		(fill
			(thermal_gap 0.5)
			(thermal_bridge_width 0.5)
			(island_removal_mode 0)
		)
		(polygon
			(pts
				(xy 127.428752 -34.539936) (xy 127.428752 -30.25775) (xy 142.25397 -30.25775) (xy 142.25397 -34.539936)
			)
		)
	)
	(zone
		(layer "In5.Cu")
		(hatch none 0.5)
		(connect_pads
			(clearance 0)
		)
		(min_thickness 0.25)
		(keepout
			(tracks not_allowed)
			(vias allowed)
			(pads allowed)
			(copperpour not_allowed)
			(footprints allowed)
		)
		(placement
			(enabled no)
			(sheetname "")
		)
		(fill
			(thermal_gap 0.5)
			(thermal_bridge_width 0.5)
			(island_removal_mode 0)
		)
		(polygon
			(pts
				(arc
					(start 182.684166 -25.543764)
					(mid 182.489596 -24.863437)
					(end 181.811168 -25.06472)
				)
				(arc
					(start 181.061106 -26.464768)
					(mid 181.264814 -27.138884)
					(end 181.93893 -26.935176)
				)
				(xy 182.1561 -26.529792) (xy 182.1561 -26.49347) (xy 181.94401 -26.28138) (xy 181.921658 -26.270204)
				(xy 181.92115 -26.269442) (xy 181.885844 -26.250392) (xy 181.798722 -26.276554)
				(arc
					(start 181.733444 -26.398728)
					(mid 181.320595 -27.035879)
					(end 181.62143 -26.338784)
				)
				(xy 181.686962 -26.21661) (xy 181.699408 -26.193496) (xy 181.711854 -26.170382) (xy 181.737 -26.162762)
				(xy 181.762146 -26.155142) (xy 181.85257 -26.127964) (xy 181.854348 -26.124916) (xy 181.877208 -26.120344)
				(xy 181.89956 -26.11374) (xy 181.902608 -26.115264) (xy 181.906164 -26.114756) (xy 181.925468 -26.127456)
				(xy 181.945788 -26.138632) (xy 181.946042 -26.138632) (xy 181.98338 -26.158444) (xy 181.984142 -26.15819)
				(xy 181.998874 -26.166572) (xy 182.008526 -26.166572) (xy 182.019194 -26.17724) (xy 182.02783 -26.181558)
				(xy 182.028592 -26.183082) (xy 182.036466 -26.1874) (xy 182.039006 -26.196798) (xy 182.231284 -26.389076)
				(xy 182.319168 -26.225246) (xy 182.127906 -26.033984) (xy 182.112158 -26.025602) (xy 182.111396 -26.025602)
				(xy 182.110126 -26.02484) (xy 182.107332 -26.025348) (xy 182.088028 -26.012648) (xy 182.067708 -26.001472)
				(xy 182.067454 -26.001472) (xy 182.03037 -25.98166) (xy 182.007256 -25.969468) (xy 181.983888 -25.957022)
				(xy 181.976268 -25.931876) (xy 181.968648 -25.90673) (xy 181.941978 -25.819608) (xy 181.941978 -25.819354)
				(xy 181.934358 -25.794462) (xy 181.926738 -25.769316) (xy 181.926738 -25.769062) (xy 181.93893 -25.745948)
				(xy 181.951376 -25.722834)
				(arc
					(start 182.016654 -25.601168)
					(mid 182.429503 -24.964017)
					(end 182.128668 -25.661112)
				)
				(xy 182.06339 -25.782524) (xy 182.09006 -25.869646) (xy 182.125112 -25.888188) (xy 182.127144 -25.88768)
				(xy 182.131462 -25.890474) (xy 182.133494 -25.89022) (xy 182.151528 -25.902158) (xy 182.17007 -25.912064)
				(xy 182.17007 -25.912318) (xy 182.182262 -25.918922) (xy 182.192676 -25.918922) (xy 182.204614 -25.93086)
				(xy 182.219346 -25.938988) (xy 182.222394 -25.948894) (xy 182.381906 -26.108152)
			)
		)
	)
	(zone
		(layer "In5.Cu")
		(hatch none 0.5)
		(connect_pads
			(clearance 0)
		)
		(min_thickness 0.25)
		(keepout
			(tracks not_allowed)
			(vias allowed)
			(pads allowed)
			(copperpour not_allowed)
			(footprints allowed)
		)
		(placement
			(enabled no)
			(sheetname "")
		)
		(fill
			(thermal_gap 0.5)
			(thermal_bridge_width 0.5)
			(island_removal_mode 0)
		)
		(polygon
			(pts
				(arc
					(start 85.367368 -84.904834)
					(mid 84.983828 -84.521294)
					(end 84.600288 -84.904834)
				)
				(arc
					(start 84.600288 -85.79358)
					(mid 84.983701 -86.177374)
					(end 85.367368 -85.793834)
				)
				(xy 85.367368 -85.596984)
				(arc
					(start 85.263228 -85.596984)
					(mid 85.221378 -85.601478)
					(end 85.18144 -85.614764)
				)
				(arc
					(start 85.18144 -85.614764)
					(mid 84.861059 -86.030571)
					(end 85.01634 -85.529166)
				)
				(arc
					(start 85.01634 -85.529166)
					(mid 85.113915 -85.464124)
					(end 85.22716 -85.433662)
				)
				(xy 85.228938 -85.431884) (xy 85.367368 -85.431884) (xy 85.367368 -85.266784) (xy 85.228938 -85.266784)
				(arc
					(start 85.22716 -85.265006)
					(mid 85.113902 -85.234571)
					(end 85.01634 -85.169502)
				)
				(arc
					(start 85.01634 -85.169502)
					(mid 84.861068 -84.668114)
					(end 85.18144 -85.083904)
				)
				(arc
					(start 85.18144 -85.083904)
					(mid 85.22138 -85.097181)
					(end 85.263228 -85.101684)
				)
				(xy 85.367368 -85.101684)
			)
		)
	)
	(zone
		(layer "In5.Cu")
		(hatch none 0.5)
		(connect_pads
			(clearance 0)
		)
		(min_thickness 0.25)
		(keepout
			(tracks not_allowed)
			(vias allowed)
			(pads allowed)
			(copperpour not_allowed)
			(footprints allowed)
		)
		(placement
			(enabled no)
			(sheetname "")
		)
		(fill
			(thermal_gap 0.5)
			(thermal_bridge_width 0.5)
			(island_removal_mode 0)
		)
		(polygon
			(pts
				(arc
					(start 83.741768 -94.492572)
					(mid 83.358228 -94.109032)
					(end 82.974688 -94.492572)
				)
				(arc
					(start 82.974688 -95.381318)
					(mid 83.358101 -95.765112)
					(end 83.741768 -95.381572)
				)
				(xy 83.741768 -95.189548)
				(arc
					(start 83.599528 -95.189548)
					(mid 83.574972 -95.191459)
					(end 83.551014 -95.197168)
				)
				(arc
					(start 83.551014 -95.197168)
					(mid 83.245973 -95.623584)
					(end 83.374484 -95.11538)
				)
				(arc
					(start 83.374484 -95.11538)
					(mid 83.461489 -95.055312)
					(end 83.563206 -95.02648)
				)
				(xy 83.565238 -95.024448) (xy 83.741768 -95.024448) (xy 83.741768 -94.859348) (xy 83.565238 -94.859348)
				(arc
					(start 83.563206 -94.857316)
					(mid 83.455674 -94.825657)
					(end 83.36534 -94.759272)
				)
				(arc
					(start 83.36534 -94.759272)
					(mid 83.254755 -94.24666)
					(end 83.543902 -94.684088)
				)
				(arc
					(start 83.543902 -94.684088)
					(mid 83.571259 -94.691665)
					(end 83.599528 -94.694248)
				)
				(xy 83.741768 -94.694248)
			)
		)
	)
	(zone
		(layer "In5.Cu")
		(hatch none 0.5)
		(connect_pads
			(clearance 0)
		)
		(min_thickness 0.25)
		(keepout
			(tracks not_allowed)
			(vias allowed)
			(pads allowed)
			(copperpour not_allowed)
			(footprints allowed)
		)
		(placement
			(enabled no)
			(sheetname "")
		)
		(fill
			(thermal_gap 0.5)
			(thermal_bridge_width 0.5)
			(island_removal_mode 0)
		)
		(polygon
			(pts
				(arc
					(start 112.985042 -35.600386)
					(mid 112.500029 -35.114992)
					(end 112.014762 -35.600132)
				)
				(arc
					(start 112.014762 -36.026344)
					(mid 112.07304 -36.045869)
					(end 112.134142 -36.052506)
				)
				(arc
					(start 112.311942 -36.052506)
					(mid 112.372166 -36.033608)
					(end 112.410748 -35.983672)
				)
				(arc
					(start 112.410748 -35.983672)
					(mid 112.50471 -35.206396)
					(end 112.579658 -35.985704)
				)
				(arc
					(start 112.579658 -35.985704)
					(mid 112.502479 -36.139081)
					(end 112.348518 -36.215066)
				)
				(xy 112.346232 -36.217606) (xy 112.099852 -36.217606)
				(arc
					(start 112.098582 -36.216082)
					(mid 112.056329 -36.210828)
					(end 112.014762 -36.201604)
				)
				(arc
					(start 112.014762 -36.371022)
					(mid 112.074168 -36.379764)
					(end 112.134142 -36.382706)
				)
				(xy 112.346232 -36.382706)
				(arc
					(start 112.348518 -36.385246)
					(mid 112.502457 -36.461253)
					(end 112.579658 -36.614608)
				)
				(arc
					(start 112.579658 -36.614608)
					(mid 112.504709 -37.393885)
					(end 112.410748 -36.61664)
				)
				(arc
					(start 112.410748 -36.61664)
					(mid 112.372137 -36.566746)
					(end 112.311942 -36.547806)
				)
				(xy 112.099852 -36.547806)
				(arc
					(start 112.09909 -36.547044)
					(mid 112.056812 -36.543996)
					(end 112.014762 -36.538662)
				)
				(arc
					(start 112.014762 -37.00018)
					(mid 112.499902 -37.48532)
					(end 112.985042 -37.00018)
				)
			)
		)
	)
	(zone
		(layer "In5.Cu")
		(hatch none 0.5)
		(connect_pads
			(clearance 0)
		)
		(min_thickness 0.25)
		(keepout
			(tracks not_allowed)
			(vias allowed)
			(pads allowed)
			(copperpour not_allowed)
			(footprints allowed)
		)
		(placement
			(enabled no)
			(sheetname "")
		)
		(fill
			(thermal_gap 0.5)
			(thermal_bridge_width 0.5)
			(island_removal_mode 0)
		)
		(polygon
			(pts
				(xy 162.326828 -26.157174) (xy 162.309302 -26.130758) (xy 162.007042 -25.969468) (xy 161.983928 -25.957022)
				(xy 161.976308 -25.931876) (xy 161.942018 -25.819608) (xy 161.942018 -25.819354) (xy 161.934398 -25.794462)
				(xy 161.926778 -25.769316) (xy 161.926778 -25.769062) (xy 161.93897 -25.745948) (xy 161.951416 -25.722834)
				(arc
					(start 162.016694 -25.601168)
					(mid 162.429543 -24.964017)
					(end 162.128708 -25.661112)
				)
				(xy 162.06343 -25.782524) (xy 162.0901 -25.869646) (xy 162.374834 -26.021792) (xy 162.391598 -26.025094)
				(xy 162.3949 -26.030174)
				(arc
					(start 162.663632 -25.528524)
					(mid 162.47593 -24.884882)
					(end 161.83356 -25.076912)
				)
				(arc
					(start 161.083498 -26.47696)
					(mid 161.277046 -27.116532)
					(end 161.916618 -26.922984)
				)
				(xy 162.163506 -26.461974) (xy 162.097974 -26.363676) (xy 161.885884 -26.250392) (xy 161.798762 -26.276554)
				(arc
					(start 161.733484 -26.398728)
					(mid 161.320635 -27.035879)
					(end 161.62147 -26.338784)
				)
				(xy 161.687002 -26.21661) (xy 161.699448 -26.193496) (xy 161.711894 -26.170382) (xy 161.73704 -26.162762)
				(xy 161.762186 -26.155142) (xy 161.874454 -26.12136) (xy 161.899346 -26.11374) (xy 161.8996 -26.11374)
				(xy 161.922714 -26.126186) (xy 162.163506 -26.25471) (xy 162.18027 -26.258012) (xy 162.185858 -26.266648)
				(xy 162.195002 -26.271474) (xy 162.199828 -26.28773) (xy 162.231578 -26.334974)
			)
		)
	)
	(zone
		(layer "In5.Cu")
		(hatch none 0.5)
		(connect_pads
			(clearance 0)
		)
		(min_thickness 0.25)
		(keepout
			(tracks not_allowed)
			(vias allowed)
			(pads allowed)
			(copperpour not_allowed)
			(footprints allowed)
		)
		(placement
			(enabled no)
			(sheetname "")
		)
		(fill
			(thermal_gap 0.5)
			(thermal_bridge_width 0.5)
			(island_removal_mode 0)
		)
		(polygon
			(pts
				(arc
					(start 139.984988 -33.20034)
					(mid 139.499975 -32.714946)
					(end 139.014708 -33.200086)
				)
				(arc
					(start 139.014708 -33.648904)
					(mid 139.033421 -33.65156)
					(end 139.0523 -33.65246)
				)
				(arc
					(start 139.2682 -33.65246)
					(mid 139.341793 -33.633032)
					(end 139.396216 -33.579816)
				)
				(arc
					(start 139.396216 -33.579816)
					(mid 139.516517 -32.806822)
					(end 139.570968 -33.587182)
				)
				(arc
					(start 139.570968 -33.587182)
					(mid 139.472566 -33.741959)
					(end 139.304522 -33.815528)
				)
				(xy 139.30249 -33.81756) (xy 139.01801 -33.81756) (xy 139.016232 -33.815782) (xy 139.014708 -33.815528)
				(xy 139.014708 -33.98139) (xy 139.0523 -33.98266) (xy 139.30249 -33.98266)
				(arc
					(start 139.304522 -33.984692)
					(mid 139.472642 -34.058173)
					(end 139.570968 -34.213038)
				)
				(arc
					(start 139.570968 -34.213038)
					(mid 139.516515 -34.993356)
					(end 139.396216 -34.220404)
				)
				(arc
					(start 139.396216 -34.220404)
					(mid 139.341798 -34.167179)
					(end 139.2682 -34.14776)
				)
				(xy 139.01801 -34.14776) (xy 139.017248 -34.146998) (xy 139.014708 -34.146744)
				(arc
					(start 139.014708 -34.600134)
					(mid 139.499848 -35.085274)
					(end 139.984988 -34.600134)
				)
			)
		)
	)
	(zone
		(layer "In5.Cu")
		(hatch none 0.5)
		(connect_pads
			(clearance 0)
		)
		(min_thickness 0.25)
		(keepout
			(tracks not_allowed)
			(vias allowed)
			(pads allowed)
			(copperpour not_allowed)
			(footprints allowed)
		)
		(placement
			(enabled no)
			(sheetname "")
		)
		(fill
			(thermal_gap 0.5)
			(thermal_bridge_width 0.5)
			(island_removal_mode 0)
		)
		(polygon
			(pts
				(arc
					(start 212.306154 -65.828926)
					(mid 212.306154 -65.290446)
					(end 211.767674 -65.290446)
				)
				(xy 211.76742 -65.290192) (xy 211.537296 -65.520316) (xy 211.537296 -65.562988)
				(arc
					(start 211.652358 -65.67805)
					(mid 211.726779 -65.713801)
					(end 211.807298 -65.695322)
				)
				(arc
					(start 211.807298 -65.695322)
					(mid 212.227144 -65.372344)
					(end 211.897214 -65.786762)
				)
				(arc
					(start 211.897214 -65.786762)
					(mid 211.740218 -65.841528)
					(end 211.58327 -65.786508)
				)
				(xy 211.580984 -65.786508) (xy 211.562442 -65.767966) (xy 211.44738 -65.652904) (xy 211.426044 -65.631568)
				(xy 211.300314 -65.757298) (xy 211.455254 -65.912238)
				(arc
					(start 211.455254 -65.914524)
					(mid 211.510392 -66.071294)
					(end 211.455762 -66.228214)
				)
				(arc
					(start 211.455762 -66.228214)
					(mid 211.041336 -66.558151)
					(end 211.364322 -66.138298)
				)
				(arc
					(start 211.364322 -66.138298)
					(mid 211.382598 -66.057907)
					(end 211.346796 -65.983612)
				)
				(xy 211.210398 -65.847214) (xy 210.959192 -66.09842)
				(arc
					(start 210.959446 -66.098674)
					(mid 210.959446 -66.637154)
					(end 211.497926 -66.637154)
				)
				(xy 211.49818 -66.637408) (xy 212.306154 -65.82918)
			)
		)
	)
	(zone
		(layer "In5.Cu")
		(hatch none 0.5)
		(connect_pads
			(clearance 0)
		)
		(min_thickness 0.25)
		(keepout
			(tracks not_allowed)
			(vias allowed)
			(pads allowed)
			(copperpour not_allowed)
			(footprints allowed)
		)
		(placement
			(enabled no)
			(sheetname "")
		)
		(fill
			(thermal_gap 0.5)
			(thermal_bridge_width 0.5)
			(island_removal_mode 0)
		)
		(polygon
			(pts
				(xy 204.44206 -85.402928) (xy 204.346048 -85.30717)
				(arc
					(start 204.346048 -85.30463)
					(mid 204.287255 -85.20278)
					(end 204.26426 -85.08746)
				)
				(arc
					(start 204.26426 -85.08746)
					(mid 204.509362 -84.62322)
					(end 204.441552 -85.143848)
				)
				(arc
					(start 204.441552 -85.143848)
					(mid 204.460462 -85.181618)
					(end 204.487018 -85.21446)
				)
				(xy 204.558646 -85.286342)
				(arc
					(start 204.698092 -85.146896)
					(mid 204.698092 -84.607908)
					(end 204.159104 -84.607908)
				)
				(arc
					(start 203.535534 -85.231732)
					(mid 203.528455 -85.772846)
					(end 204.069696 -85.775292)
				)
				(xy 204.20838 -85.636608)
				(arc
					(start 204.129894 -85.558376)
					(mid 204.100134 -85.535808)
					(end 204.066648 -85.51926)
				)
				(arc
					(start 204.066648 -85.51926)
					(mid 203.545812 -85.586175)
					(end 204.010514 -85.341714)
				)
				(arc
					(start 204.010514 -85.341714)
					(mid 204.125482 -85.365068)
					(end 204.226922 -85.42401)
				)
				(xy 204.229208 -85.42401) (xy 204.244448 -85.439504) (xy 204.25283 -85.447378) (xy 204.256386 -85.451442)
				(xy 204.324966 -85.520022)
			)
		)
	)
	(zone
		(net "SAS0_AVDD")
		(layer "In5.Cu")
		(hatch none 0.5)
		(connect_pads
			(clearance 0.5)
		)
		(min_thickness 0.25)
		(fill yes
			(thermal_gap 0.5)
			(thermal_bridge_width 0.5)
			(island_removal_mode 0)
		)
		(polygon
			(pts
				(xy 204.6986 -62.8396) (xy 203.7588 -62.8396) (xy 202.7936 -62.8396) (xy 202.5777 -63.0555) (xy 201.75728 -63.87592)
				(xy 201.37374 -63.87592) (xy 201.19086 -63.69304) (xy 198.31558 -63.69304) (xy 197.98284 -64.02578)
				(xy 197.98284 -67.72148) (xy 197.74154 -67.96278) (xy 195.89496 -67.96278) (xy 195.7832 -68.07454)
				(xy 195.7832 -68.5546) (xy 195.7832 -70.9676) (xy 196.9008 -72.0852) (xy 197.0278 -72.2122) (xy 197.8914 -72.2122)
				(xy 198.0184 -72.0852) (xy 198.1962 -71.9074) (xy 199.517 -71.9074) (xy 199.644 -71.7804) (xy 199.644 -71.2978)
				(xy 199.5424 -71.1962) (xy 199.4154 -71.0692) (xy 198.9582 -71.0692) (xy 198.7804 -70.8914) (xy 198.7804 -70.485)
				(xy 199.009 -70.2564) (xy 199.7964 -70.2564) (xy 200.4314 -70.2564) (xy 200.5584 -70.1294) (xy 200.5584 -69.6976)
				(xy 200.3806 -69.5198) (xy 198.247 -69.5198) (xy 198.0184 -69.2912) (xy 198.0184 -68.9102) (xy 198.2724 -68.6562)
				(xy 200.1774 -68.6562) (xy 200.3552 -68.4784) (xy 200.3552 -67.9704) (xy 200.3552 -67.3608) (xy 201.3966 -66.3194)
				(xy 203.4286 -66.3194) (xy 203.581 -66.4718) (xy 203.581 -67.8942) (xy 202.692 -68.7832) (xy 202.2856 -68.7832)
				(xy 202.1586 -68.9102) (xy 202.1586 -69.2658) (xy 202.1713 -69.2785) (xy 202.1713 -69.7865) (xy 202.4634 -70.0786)
				(xy 203.3778 -70.0786) (xy 203.6064 -70.3072) (xy 203.6064 -70.8152) (xy 203.2508 -71.1708) (xy 202.3364 -71.1708)
				(xy 202.1078 -71.3994) (xy 202.1078 -71.9328) (xy 202.1078 -72.263) (xy 202.7936 -72.9488) (xy 202.7936 -73.3298)
				(xy 202.5904 -73.533) (xy 202.2094 -73.533) (xy 202.1332 -73.6092) (xy 202.1332 -74.168) (xy 202.1332 -74.6506)
				(xy 202.5396 -75.057) (xy 202.5904 -75.057) (xy 202.7428 -75.2094) (xy 202.7428 -75.7936) (xy 201.93 -76.6064)
				(xy 201.93 -77.4954) (xy 201.974704 -77.540104) (xy 201.974704 -79.543656) (xy 204.317854 -81.886806)
				(xy 208.77784 -81.886806) (xy 209.776568 -82.885534) (xy 210.725004 -83.83397) (xy 210.725004 -86.529926)
				(xy 210.725004 -89.076022) (xy 210.96859 -89.319608) (xy 210.96859 -90.034364) (xy 210.7311 -90.271854)
				(xy 208.5467 -90.271854) (xy 208.224882 -90.593672) (xy 208.224882 -92.877386) (xy 208.52384 -93.176344)
				(xy 213.098888 -93.176344) (xy 214.586058 -91.689174) (xy 215.4682 -90.807032) (xy 215.4682 -82.818732)
				(xy 207.479646 -74.830178) (xy 207.479646 -65.620646) (xy 206.53375 -64.67475) (xy 206.53375 -63.96355)
				(xy 205.4098 -62.8396)
			)
		)
	)
	(zone
		(layer "In5.Cu")
		(hatch none 0.5)
		(connect_pads
			(clearance 0)
		)
		(min_thickness 0.25)
		(keepout
			(tracks not_allowed)
			(vias allowed)
			(pads allowed)
			(copperpour not_allowed)
			(footprints allowed)
		)
		(placement
			(enabled no)
			(sheetname "")
		)
		(fill
			(thermal_gap 0.5)
			(thermal_bridge_width 0.5)
			(island_removal_mode 0)
		)
		(polygon
			(pts
				(xy 182.212742 -30.170374) (xy 182.300372 -30.006544) (xy 182.127906 -29.834078) (xy 182.007002 -29.769562)
				(xy 181.983888 -29.757116) (xy 181.976268 -29.73197) (xy 181.941978 -29.619702) (xy 181.941978 -29.619448)
				(xy 181.934358 -29.594556) (xy 181.926738 -29.56941) (xy 181.926738 -29.569156) (xy 181.93893 -29.546042)
				(xy 181.951376 -29.522928)
				(arc
					(start 182.016654 -29.401262)
					(mid 182.429503 -28.764111)
					(end 182.128668 -29.461206)
				)
				(xy 182.06339 -29.582618) (xy 182.09006 -29.66974) (xy 182.182262 -29.719016) (xy 182.192676 -29.719016)
				(xy 182.204614 -29.730954) (xy 182.219346 -29.738828) (xy 182.222394 -29.748734) (xy 182.36311 -29.88945)
				(arc
					(start 182.663592 -29.328618)
					(mid 182.47589 -28.684976)
					(end 181.83352 -28.877006)
				)
				(arc
					(start 181.083458 -30.277054)
					(mid 181.277006 -30.916626)
					(end 181.916578 -30.723078)
				)
				(xy 182.150004 -30.287214) (xy 181.944264 -30.081728) (xy 181.885844 -30.050486) (xy 181.798722 -30.076648)
				(arc
					(start 181.733444 -30.198822)
					(mid 181.320595 -30.835973)
					(end 181.62143 -30.138878)
				)
				(xy 181.686962 -30.016704) (xy 181.699408 -29.99359) (xy 181.711854 -29.970476) (xy 181.737 -29.962856)
				(xy 181.762146 -29.955236) (xy 181.874414 -29.921454) (xy 181.899306 -29.913834) (xy 181.89956 -29.913834)
				(xy 181.922674 -29.92628) (xy 181.99862 -29.966666) (xy 182.009034 -29.966666) (xy 182.020972 -29.978604)
				(xy 182.035704 -29.986478) (xy 182.038752 -29.996384)
			)
		)
	)
	(zone
		(layer "In5.Cu")
		(hatch none 0.5)
		(connect_pads
			(clearance 0)
		)
		(min_thickness 0.25)
		(keepout
			(tracks not_allowed)
			(vias allowed)
			(pads allowed)
			(copperpour not_allowed)
			(footprints allowed)
		)
		(placement
			(enabled no)
			(sheetname "")
		)
		(fill
			(thermal_gap 0.5)
			(thermal_bridge_width 0.5)
			(island_removal_mode 0)
		)
		(polygon
			(pts
				(arc
					(start 197.793864 -85.604096)
					(mid 197.793864 -85.065108)
					(end 197.254876 -85.065108)
				)
				(arc
					(start 196.631306 -85.688932)
					(mid 196.624227 -86.230046)
					(end 197.165468 -86.232492)
				)
				(xy 197.304152 -86.093808)
				(arc
					(start 197.231762 -86.021164)
					(mid 197.199469 -85.995123)
					(end 197.16242 -85.97646)
				)
				(arc
					(start 197.16242 -85.97646)
					(mid 196.641584 -86.043375)
					(end 197.106286 -85.798914)
				)
				(arc
					(start 197.106286 -85.798914)
					(mid 197.220793 -85.822007)
					(end 197.321932 -85.880448)
				)
				(xy 197.324472 -85.880448) (xy 197.348348 -85.904578) (xy 197.348602 -85.904578) (xy 197.420992 -85.976968)
				(xy 197.537832 -85.860128) (xy 197.44182 -85.76437)
				(arc
					(start 197.44182 -85.76183)
					(mid 197.383027 -85.65998)
					(end 197.360032 -85.54466)
				)
				(arc
					(start 197.360032 -85.54466)
					(mid 197.605134 -85.08042)
					(end 197.537324 -85.601048)
				)
				(arc
					(start 197.537324 -85.601048)
					(mid 197.556234 -85.638818)
					(end 197.58279 -85.67166)
				)
				(xy 197.654418 -85.743542)
			)
		)
	)
	(zone
		(layer "In5.Cu")
		(hatch none 0.5)
		(connect_pads
			(clearance 0)
		)
		(min_thickness 0.25)
		(keepout
			(tracks not_allowed)
			(vias allowed)
			(pads allowed)
			(copperpour not_allowed)
			(footprints allowed)
		)
		(placement
			(enabled no)
			(sheetname "")
		)
		(fill
			(thermal_gap 0.5)
			(thermal_bridge_width 0.5)
			(island_removal_mode 0)
		)
		(polygon
			(pts
				(arc
					(start 83.741768 -81.705196)
					(mid 83.358228 -81.321656)
					(end 82.974688 -81.705196)
				)
				(arc
					(start 82.974688 -82.593942)
					(mid 83.358101 -82.977736)
					(end 83.741768 -82.594196)
				)
				(xy 83.741768 -82.397346)
				(arc
					(start 83.637628 -82.397346)
					(mid 83.595778 -82.40184)
					(end 83.55584 -82.415126)
				)
				(arc
					(start 83.55584 -82.415126)
					(mid 83.235459 -82.830933)
					(end 83.39074 -82.329528)
				)
				(arc
					(start 83.39074 -82.329528)
					(mid 83.488315 -82.264486)
					(end 83.60156 -82.234024)
				)
				(xy 83.603338 -82.232246) (xy 83.741768 -82.232246) (xy 83.741768 -82.067146) (xy 83.603338 -82.067146)
				(arc
					(start 83.60156 -82.065368)
					(mid 83.488302 -82.034933)
					(end 83.39074 -81.969864)
				)
				(arc
					(start 83.39074 -81.969864)
					(mid 83.235468 -81.468476)
					(end 83.55584 -81.884266)
				)
				(arc
					(start 83.55584 -81.884266)
					(mid 83.59578 -81.897543)
					(end 83.637628 -81.902046)
				)
				(xy 83.741768 -81.902046)
			)
		)
	)
	(zone
		(layer "In5.Cu")
		(hatch none 0.5)
		(connect_pads
			(clearance 0)
		)
		(min_thickness 0.25)
		(keepout
			(tracks not_allowed)
			(vias allowed)
			(pads allowed)
			(copperpour not_allowed)
			(footprints allowed)
		)
		(placement
			(enabled no)
			(sheetname "")
		)
		(fill
			(thermal_gap 0.5)
			(thermal_bridge_width 0.5)
			(island_removal_mode 0)
		)
		(polygon
			(pts
				(arc
					(start 116.584984 -35.600386)
					(mid 116.099971 -35.114992)
					(end 115.614704 -35.600132)
				)
				(arc
					(start 115.614704 -36.026344)
					(mid 115.672982 -36.045869)
					(end 115.734084 -36.052506)
				)
				(arc
					(start 115.911884 -36.052506)
					(mid 115.972108 -36.033608)
					(end 116.01069 -35.983672)
				)
				(arc
					(start 116.01069 -35.983672)
					(mid 116.104652 -35.206396)
					(end 116.1796 -35.985704)
				)
				(arc
					(start 116.1796 -35.985704)
					(mid 116.102421 -36.139081)
					(end 115.94846 -36.215066)
				)
				(xy 115.946174 -36.217606) (xy 115.699794 -36.217606)
				(arc
					(start 115.698524 -36.216082)
					(mid 115.656271 -36.210828)
					(end 115.614704 -36.201604)
				)
				(arc
					(start 115.614704 -36.371022)
					(mid 115.67411 -36.379764)
					(end 115.734084 -36.382706)
				)
				(xy 115.946174 -36.382706)
				(arc
					(start 115.94846 -36.385246)
					(mid 116.102399 -36.461253)
					(end 116.1796 -36.614608)
				)
				(arc
					(start 116.1796 -36.614608)
					(mid 116.104651 -37.393885)
					(end 116.01069 -36.61664)
				)
				(arc
					(start 116.01069 -36.61664)
					(mid 115.972079 -36.566746)
					(end 115.911884 -36.547806)
				)
				(xy 115.699794 -36.547806)
				(arc
					(start 115.699032 -36.547044)
					(mid 115.656754 -36.543996)
					(end 115.614704 -36.538662)
				)
				(arc
					(start 115.614704 -37.00018)
					(mid 116.099844 -37.48532)
					(end 116.584984 -37.00018)
				)
			)
		)
	)
	(zone
		(layer "In5.Cu")
		(hatch none 0.5)
		(connect_pads
			(clearance 0)
		)
		(min_thickness 0.25)
		(keepout
			(tracks not_allowed)
			(vias allowed)
			(pads allowed)
			(copperpour not_allowed)
			(footprints allowed)
		)
		(placement
			(enabled no)
			(sheetname "")
		)
		(fill
			(thermal_gap 0.5)
			(thermal_bridge_width 0.5)
			(island_removal_mode 0)
		)
		(polygon
			(pts
				(arc
					(start 111.185198 -36.800282)
					(mid 110.700185 -36.314888)
					(end 110.214918 -36.800028)
				)
				(arc
					(start 110.214918 -37.22624)
					(mid 110.273196 -37.245765)
					(end 110.334298 -37.252402)
				)
				(arc
					(start 110.512098 -37.252402)
					(mid 110.572322 -37.233504)
					(end 110.610904 -37.183568)
				)
				(arc
					(start 110.610904 -37.183568)
					(mid 110.704866 -36.406292)
					(end 110.779814 -37.1856)
				)
				(arc
					(start 110.779814 -37.1856)
					(mid 110.702635 -37.338977)
					(end 110.548674 -37.414962)
				)
				(xy 110.546388 -37.417502) (xy 110.300008 -37.417502)
				(arc
					(start 110.298738 -37.415978)
					(mid 110.256485 -37.410724)
					(end 110.214918 -37.4015)
				)
				(arc
					(start 110.214918 -37.570918)
					(mid 110.274324 -37.57966)
					(end 110.334298 -37.582602)
				)
				(xy 110.546388 -37.582602)
				(arc
					(start 110.548674 -37.585142)
					(mid 110.702613 -37.661149)
					(end 110.779814 -37.814504)
				)
				(arc
					(start 110.779814 -37.814504)
					(mid 110.704865 -38.593781)
					(end 110.610904 -37.816536)
				)
				(arc
					(start 110.610904 -37.816536)
					(mid 110.572293 -37.766642)
					(end 110.512098 -37.747702)
				)
				(xy 110.300008 -37.747702)
				(arc
					(start 110.299246 -37.74694)
					(mid 110.256968 -37.743892)
					(end 110.214918 -37.738558)
				)
				(arc
					(start 110.214918 -38.200076)
					(mid 110.700058 -38.685216)
					(end 111.185198 -38.200076)
				)
			)
		)
	)
	(zone
		(net "GND")
		(layer "In5.Cu")
		(hatch none 0.5)
		(connect_pads
			(clearance 0.5)
		)
		(min_thickness 0.25)
		(fill yes
			(thermal_gap 0.5)
			(thermal_bridge_width 0.5)
			(island_removal_mode 0)
		)
		(polygon
			(pts
				(xy 53.5559 -148.1582) (xy 53.5559 -149.1996) (xy 53.0098 -149.7457) (xy 53.0098 -150.9141) (xy 52.8701 -151.0538)
				(xy 51.308 -151.0538) (xy 51.181 -150.9268) (xy 51.181 -150.495) (xy 50.3809 -149.6949) (xy 50.3809 -148.2471)
				(xy 50.7111 -147.9169) (xy 53.3146 -147.9169)
			)
		)
	)
	(zone
		(layer "In5.Cu")
		(hatch none 0.5)
		(connect_pads
			(clearance 0)
		)
		(min_thickness 0.25)
		(keepout
			(tracks not_allowed)
			(vias allowed)
			(pads allowed)
			(copperpour not_allowed)
			(footprints allowed)
		)
		(placement
			(enabled no)
			(sheetname "")
		)
		(fill
			(thermal_gap 0.5)
			(thermal_bridge_width 0.5)
			(island_removal_mode 0)
		)
		(polygon
			(pts
				(xy 128.225042 -33.81883) (xy 128.214882 -33.817814) (xy 128.214882 -33.983676) (xy 128.260856 -33.985708)
				(xy 128.518412 -33.985708)
				(arc
					(start 128.520444 -33.987994)
					(mid 128.682441 -34.061219)
					(end 128.77419 -34.213546)
				)
				(arc
					(start 128.77419 -34.213546)
					(mid 128.712523 -34.993614)
					(end 128.600454 -34.219134)
				)
				(arc
					(start 128.600454 -34.219134)
					(mid 128.551592 -34.169117)
					(end 128.484122 -34.150808)
				)
				(xy 128.226566 -34.150808) (xy 128.225804 -34.150046) (xy 128.214882 -34.149284)
				(arc
					(start 128.214882 -34.600134)
					(mid 128.700022 -35.085274)
					(end 129.185162 -34.600134)
				)
				(arc
					(start 129.185162 -33.20034)
					(mid 128.700149 -32.714946)
					(end 128.214882 -33.200086)
				)
				(arc
					(start 128.214882 -33.650428)
					(mid 128.237731 -33.654216)
					(end 128.260856 -33.655508)
				)
				(arc
					(start 128.484122 -33.655508)
					(mid 128.554265 -33.635614)
					(end 128.603502 -33.581848)
				)
				(arc
					(start 128.603502 -33.581848)
					(mid 128.710306 -32.806515)
					(end 128.77546 -33.58642)
				)
				(arc
					(start 128.77546 -33.58642)
					(mid 128.684819 -33.742903)
					(end 128.520444 -33.818322)
				)
				(xy 128.518412 -33.820608) (xy 128.226566 -33.820608)
			)
		)
	)
	(zone
		(layer "In5.Cu")
		(hatch none 0.5)
		(connect_pads
			(clearance 0)
		)
		(min_thickness 0.25)
		(keepout
			(tracks not_allowed)
			(vias allowed)
			(pads allowed)
			(copperpour not_allowed)
			(footprints allowed)
		)
		(placement
			(enabled no)
			(sheetname "")
		)
		(fill
			(thermal_gap 0.5)
			(thermal_bridge_width 0.5)
			(island_removal_mode 0)
		)
		(polygon
			(pts
				(xy 194.46494 -88.90762) (xy 194.36842 -88.8111)
				(arc
					(start 194.36842 -88.80856)
					(mid 194.310103 -88.707397)
					(end 194.28714 -88.592914)
				)
				(arc
					(start 194.28714 -88.592914)
					(mid 194.53171 -88.128286)
					(end 194.464432 -88.649048)
				)
				(arc
					(start 194.464432 -88.649048)
					(mid 194.483209 -88.68612)
					(end 194.50939 -88.71839)
				)
				(xy 194.58178 -88.79078)
				(arc
					(start 194.720464 -88.652096)
					(mid 194.720464 -88.113108)
					(end 194.181476 -88.113108)
				)
				(arc
					(start 193.557906 -88.736932)
					(mid 193.550827 -89.278046)
					(end 194.092068 -89.280492)
				)
				(xy 194.23126 -89.1413)
				(arc
					(start 194.159378 -89.069164)
					(mid 194.126631 -89.042771)
					(end 194.08902 -89.023952)
				)
				(arc
					(start 194.08902 -89.023952)
					(mid 193.568338 -89.091779)
					(end 194.032632 -88.84666)
				)
				(arc
					(start 194.032632 -88.84666)
					(mid 194.147824 -88.869701)
					(end 194.249548 -88.928448)
				)
				(xy 194.252088 -88.928448) (xy 194.275964 -88.952578) (xy 194.276218 -88.952578) (xy 194.3481 -89.02446)
			)
		)
	)
	(zone
		(layer "In5.Cu")
		(hatch none 0.5)
		(connect_pads
			(clearance 0)
		)
		(min_thickness 0.25)
		(keepout
			(tracks not_allowed)
			(vias allowed)
			(pads allowed)
			(copperpour not_allowed)
			(footprints allowed)
		)
		(placement
			(enabled no)
			(sheetname "")
		)
		(fill
			(thermal_gap 0.5)
			(thermal_bridge_width 0.5)
			(island_removal_mode 0)
		)
		(polygon
			(pts
				(xy 131.824984 -33.81883) (xy 131.814824 -33.817814) (xy 131.814824 -33.983676) (xy 131.860798 -33.985708)
				(xy 132.118354 -33.985708)
				(arc
					(start 132.120386 -33.987994)
					(mid 132.282383 -34.061219)
					(end 132.374132 -34.213546)
				)
				(arc
					(start 132.374132 -34.213546)
					(mid 132.312465 -34.993614)
					(end 132.200396 -34.219134)
				)
				(arc
					(start 132.200396 -34.219134)
					(mid 132.151534 -34.169117)
					(end 132.084064 -34.150808)
				)
				(xy 131.826508 -34.150808) (xy 131.825746 -34.150046) (xy 131.814824 -34.149284)
				(arc
					(start 131.814824 -34.600134)
					(mid 132.299964 -35.085274)
					(end 132.785104 -34.600134)
				)
				(arc
					(start 132.785104 -33.20034)
					(mid 132.300091 -32.714946)
					(end 131.814824 -33.200086)
				)
				(arc
					(start 131.814824 -33.650428)
					(mid 131.837673 -33.654216)
					(end 131.860798 -33.655508)
				)
				(arc
					(start 132.084064 -33.655508)
					(mid 132.154207 -33.635614)
					(end 132.203444 -33.581848)
				)
				(arc
					(start 132.203444 -33.581848)
					(mid 132.310248 -32.806515)
					(end 132.375402 -33.58642)
				)
				(arc
					(start 132.375402 -33.58642)
					(mid 132.284761 -33.742903)
					(end 132.120386 -33.818322)
				)
				(xy 132.118354 -33.820608) (xy 131.826508 -33.820608)
			)
		)
	)
	(zone
		(net "GND")
		(layer "In5.Cu")
		(hatch none 0.5)
		(connect_pads
			(clearance 0.5)
		)
		(min_thickness 0.25)
		(fill yes
			(thermal_gap 0.5)
			(thermal_bridge_width 0.5)
			(island_removal_mode 0)
		)
		(polygon
			(pts
				(arc
					(start 74.030078 -0.763016)
					(mid 73.862506 -0.832426)
					(end 73.793096 -0.999998)
				)
				(xy 73.793096 -8.768334) (xy 75.82408 -8.768334) (xy 75.82408 -2.794) (xy 80.370172 -2.794) (xy 80.370172 -0.763016)
			)
		)
	)
	(zone
		(layer "In5.Cu")
		(hatch none 0.5)
		(connect_pads
			(clearance 0)
		)
		(min_thickness 0.25)
		(keepout
			(tracks not_allowed)
			(vias allowed)
			(pads allowed)
			(copperpour not_allowed)
			(footprints allowed)
		)
		(placement
			(enabled no)
			(sheetname "")
		)
		(fill
			(thermal_gap 0.5)
			(thermal_bridge_width 0.5)
			(island_removal_mode 0)
		)
		(polygon
			(pts
				(arc
					(start 85.367368 -78.504796)
					(mid 84.983828 -78.121256)
					(end 84.600288 -78.504796)
				)
				(arc
					(start 84.600288 -79.393542)
					(mid 84.983701 -79.777336)
					(end 85.367368 -79.393796)
				)
				(xy 85.367368 -79.196946)
				(arc
					(start 85.263228 -79.196946)
					(mid 85.221378 -79.20144)
					(end 85.18144 -79.214726)
				)
				(arc
					(start 85.18144 -79.214726)
					(mid 84.861059 -79.630533)
					(end 85.01634 -79.129128)
				)
				(arc
					(start 85.01634 -79.129128)
					(mid 85.113915 -79.064086)
					(end 85.22716 -79.033624)
				)
				(xy 85.228938 -79.031846) (xy 85.367368 -79.031846) (xy 85.367368 -78.866746) (xy 85.228938 -78.866746)
				(arc
					(start 85.22716 -78.864968)
					(mid 85.113902 -78.834533)
					(end 85.01634 -78.769464)
				)
				(arc
					(start 85.01634 -78.769464)
					(mid 84.861068 -78.268076)
					(end 85.18144 -78.683866)
				)
				(arc
					(start 85.18144 -78.683866)
					(mid 85.22138 -78.697143)
					(end 85.263228 -78.701646)
				)
				(xy 85.367368 -78.701646)
			)
		)
	)
	(zone
		(layer "In5.Cu")
		(hatch none 0.5)
		(connect_pads
			(clearance 0)
		)
		(min_thickness 0.25)
		(keepout
			(tracks not_allowed)
			(vias allowed)
			(pads allowed)
			(copperpour not_allowed)
			(footprints allowed)
		)
		(placement
			(enabled no)
			(sheetname "")
		)
		(fill
			(thermal_gap 0.5)
			(thermal_bridge_width 0.5)
			(island_removal_mode 0)
		)
		(polygon
			(pts
				(arc
					(start 120.18518 -35.600386)
					(mid 119.700167 -35.114992)
					(end 119.2149 -35.600132)
				)
				(arc
					(start 119.2149 -36.026344)
					(mid 119.273178 -36.045869)
					(end 119.33428 -36.052506)
				)
				(arc
					(start 119.51208 -36.052506)
					(mid 119.572304 -36.033608)
					(end 119.610886 -35.983672)
				)
				(arc
					(start 119.610886 -35.983672)
					(mid 119.704848 -35.206396)
					(end 119.779796 -35.985704)
				)
				(arc
					(start 119.779796 -35.985704)
					(mid 119.702617 -36.139081)
					(end 119.548656 -36.215066)
				)
				(xy 119.54637 -36.217606) (xy 119.29999 -36.217606)
				(arc
					(start 119.29872 -36.216082)
					(mid 119.256467 -36.210828)
					(end 119.2149 -36.201604)
				)
				(arc
					(start 119.2149 -36.371022)
					(mid 119.274306 -36.379764)
					(end 119.33428 -36.382706)
				)
				(xy 119.54637 -36.382706)
				(arc
					(start 119.548656 -36.385246)
					(mid 119.702595 -36.461253)
					(end 119.779796 -36.614608)
				)
				(arc
					(start 119.779796 -36.614608)
					(mid 119.704847 -37.393885)
					(end 119.610886 -36.61664)
				)
				(arc
					(start 119.610886 -36.61664)
					(mid 119.572275 -36.566746)
					(end 119.51208 -36.547806)
				)
				(xy 119.29999 -36.547806)
				(arc
					(start 119.299228 -36.547044)
					(mid 119.25695 -36.543996)
					(end 119.2149 -36.538662)
				)
				(arc
					(start 119.2149 -37.00018)
					(mid 119.70004 -37.48532)
					(end 120.18518 -37.00018)
				)
			)
		)
	)
	(zone
		(layer "In5.Cu")
		(hatch none 0.5)
		(connect_pads
			(clearance 0)
		)
		(min_thickness 0.25)
		(keepout
			(tracks not_allowed)
			(vias allowed)
			(pads allowed)
			(copperpour not_allowed)
			(footprints allowed)
		)
		(placement
			(enabled no)
			(sheetname "")
		)
		(fill
			(thermal_gap 0.5)
			(thermal_bridge_width 0.5)
			(island_removal_mode 0)
		)
		(polygon
			(pts
				(xy 180.05044 -30.006544) (xy 179.878228 -29.834332) (xy 179.75707 -29.769816) (xy 179.733702 -29.75737)
				(xy 179.726082 -29.732224) (xy 179.691792 -29.619956) (xy 179.684172 -29.59481) (xy 179.676552 -29.569664)
				(xy 179.676552 -29.56941) (xy 179.688744 -29.546296) (xy 179.70119 -29.523182)
				(arc
					(start 179.766468 -29.401262)
					(mid 180.179317 -28.764111)
					(end 179.878482 -29.461206)
				)
				(xy 179.813204 -29.582872) (xy 179.839874 -29.669994) (xy 179.932076 -29.71927) (xy 179.942744 -29.71927)
				(xy 179.954428 -29.731208) (xy 179.969414 -29.739082) (xy 179.972462 -29.748988) (xy 180.112924 -29.889704)
				(arc
					(start 180.413406 -29.328618)
					(mid 180.225704 -28.684976)
					(end 179.583334 -28.877006)
				)
				(arc
					(start 178.833526 -30.277054)
					(mid 179.027074 -30.916626)
					(end 179.666646 -30.723078)
				)
				(xy 179.84089 -30.397704) (xy 179.84089 -30.22854) (xy 179.694332 -30.081982) (xy 179.635912 -30.05074)
				(xy 179.54879 -30.076902)
				(arc
					(start 179.483512 -30.199076)
					(mid 179.069114 -30.835371)
					(end 179.371498 -30.138878)
				)
				(xy 179.43703 -30.016958) (xy 179.449476 -29.993844) (xy 179.461922 -29.97073) (xy 179.487068 -29.96311)
				(xy 179.512214 -29.95549) (xy 179.624482 -29.921708) (xy 179.649374 -29.914088) (xy 179.649628 -29.914088)
				(xy 179.672742 -29.926534) (xy 179.748688 -29.96692) (xy 179.759102 -29.96692) (xy 179.77104 -29.978858)
				(xy 179.785772 -29.986732) (xy 179.78882 -29.996638) (xy 179.930806 -30.138624) (xy 179.962556 -30.170374)
			)
		)
	)
	(zone
		(layer "In5.Cu")
		(hatch none 0.5)
		(connect_pads
			(clearance 0)
		)
		(min_thickness 0.25)
		(keepout
			(tracks not_allowed)
			(vias allowed)
			(pads allowed)
			(copperpour not_allowed)
			(footprints allowed)
		)
		(placement
			(enabled no)
			(sheetname "")
		)
		(fill
			(thermal_gap 0.5)
			(thermal_bridge_width 0.5)
			(island_removal_mode 0)
		)
		(polygon
			(pts
				(arc
					(start 199.084692 -88.728296)
					(mid 199.084692 -88.189308)
					(end 198.545704 -88.189308)
				)
				(arc
					(start 197.922134 -88.813132)
					(mid 197.915055 -89.354246)
					(end 198.456296 -89.356692)
				)
				(xy 198.595488 -89.2175)
				(arc
					(start 198.523606 -89.145364)
					(mid 198.490859 -89.118971)
					(end 198.453248 -89.100152)
				)
				(arc
					(start 198.453248 -89.100152)
					(mid 197.932566 -89.167979)
					(end 198.39686 -88.92286)
				)
				(arc
					(start 198.39686 -88.92286)
					(mid 198.512052 -88.945901)
					(end 198.613776 -89.004648)
				)
				(xy 198.616316 -89.004648) (xy 198.640192 -89.028778) (xy 198.640446 -89.028778) (xy 198.712328 -89.10066)
				(xy 198.829168 -88.98382) (xy 198.732648 -88.8873)
				(arc
					(start 198.732648 -88.88476)
					(mid 198.674331 -88.783597)
					(end 198.651368 -88.669114)
				)
				(arc
					(start 198.651368 -88.669114)
					(mid 198.895938 -88.204486)
					(end 198.82866 -88.725248)
				)
				(arc
					(start 198.82866 -88.725248)
					(mid 198.847437 -88.76232)
					(end 198.873618 -88.79459)
				)
				(xy 198.946008 -88.86698)
			)
		)
	)
	(zone
		(layer "In5.Cu")
		(hatch none 0.5)
		(connect_pads
			(clearance 0)
		)
		(min_thickness 0.25)
		(keepout
			(tracks not_allowed)
			(vias allowed)
			(pads allowed)
			(copperpour not_allowed)
			(footprints allowed)
		)
		(placement
			(enabled no)
			(sheetname "")
		)
		(fill
			(thermal_gap 0.5)
			(thermal_bridge_width 0.5)
			(island_removal_mode 0)
		)
		(polygon
			(pts
				(arc
					(start 216.192354 -73.652126)
					(mid 216.192354 -73.113646)
					(end 215.653874 -73.113646)
				)
				(xy 215.65362 -73.113392) (xy 215.40216 -73.364852)
				(arc
					(start 215.538558 -73.50125)
					(mid 215.612979 -73.537001)
					(end 215.693498 -73.518522)
				)
				(arc
					(start 215.693498 -73.518522)
					(mid 216.113344 -73.195544)
					(end 215.783414 -73.609962)
				)
				(arc
					(start 215.783414 -73.609962)
					(mid 215.626418 -73.664728)
					(end 215.46947 -73.609708)
				)
				(xy 215.467184 -73.609708) (xy 215.448642 -73.591166) (xy 215.312244 -73.454768) (xy 215.186514 -73.580498)
				(xy 215.341454 -73.735438)
				(arc
					(start 215.341454 -73.737724)
					(mid 215.396592 -73.894494)
					(end 215.341962 -74.051414)
				)
				(arc
					(start 215.341962 -74.051414)
					(mid 214.927536 -74.381351)
					(end 215.250522 -73.961498)
				)
				(arc
					(start 215.250522 -73.961498)
					(mid 215.268798 -73.881107)
					(end 215.232996 -73.806812)
				)
				(xy 215.096598 -73.670414) (xy 214.845392 -73.92162)
				(arc
					(start 214.845646 -73.921874)
					(mid 214.845646 -74.460354)
					(end 215.384126 -74.460354)
				)
				(xy 215.38438 -74.460608) (xy 216.192354 -73.65238)
			)
		)
	)
	(zone
		(layer "In5.Cu")
		(hatch none 0.5)
		(connect_pads
			(clearance 0)
		)
		(min_thickness 0.25)
		(keepout
			(tracks not_allowed)
			(vias allowed)
			(pads allowed)
			(copperpour not_allowed)
			(footprints allowed)
		)
		(placement
			(enabled no)
			(sheetname "")
		)
		(fill
			(thermal_gap 0.5)
			(thermal_bridge_width 0.5)
			(island_removal_mode 0)
		)
		(polygon
			(pts
				(arc
					(start 130.985006 -32.000444)
					(mid 130.499993 -31.51505)
					(end 130.014726 -32.00019)
				)
				(arc
					(start 130.014726 -32.450278)
					(mid 130.037575 -32.454066)
					(end 130.0607 -32.455358)
				)
				(arc
					(start 130.283966 -32.455358)
					(mid 130.353987 -32.43545)
					(end 130.403092 -32.381698)
				)
				(arc
					(start 130.403092 -32.381698)
					(mid 130.510803 -31.606751)
					(end 130.575304 -32.386524)
				)
				(arc
					(start 130.575304 -32.386524)
					(mid 130.484608 -32.542877)
					(end 130.320288 -32.618172)
				)
				(xy 130.318256 -32.620458) (xy 130.02641 -32.620458) (xy 130.024886 -32.61868) (xy 130.014726 -32.617664)
				(xy 130.014726 -32.783526) (xy 130.0607 -32.785558) (xy 130.318256 -32.785558)
				(arc
					(start 130.320288 -32.787844)
					(mid 130.482285 -32.861069)
					(end 130.574034 -33.013396)
				)
				(arc
					(start 130.574034 -33.013396)
					(mid 130.512367 -33.793464)
					(end 130.400298 -33.018984)
				)
				(arc
					(start 130.400298 -33.018984)
					(mid 130.351436 -32.968967)
					(end 130.283966 -32.950658)
				)
				(xy 130.02641 -32.950658) (xy 130.025648 -32.949896) (xy 130.014726 -32.949134)
				(arc
					(start 130.014726 -33.399984)
					(mid 130.499866 -33.885124)
					(end 130.985006 -33.399984)
				)
			)
		)
	)
	(zone
		(layer "In5.Cu")
		(hatch none 0.5)
		(connect_pads
			(clearance 0)
		)
		(min_thickness 0.25)
		(keepout
			(tracks not_allowed)
			(vias allowed)
			(pads allowed)
			(copperpour not_allowed)
			(footprints allowed)
		)
		(placement
			(enabled no)
			(sheetname "")
		)
		(fill
			(thermal_gap 0.5)
			(thermal_bridge_width 0.5)
			(island_removal_mode 0)
		)
		(polygon
			(pts
				(arc
					(start 83.741768 -88.105488)
					(mid 83.358355 -87.721694)
					(end 82.974688 -88.105234)
				)
				(arc
					(start 82.974688 -88.994234)
					(mid 83.358228 -89.377774)
					(end 83.741768 -88.994234)
				)
				(xy 83.741768 -88.797384)
				(arc
					(start 83.637628 -88.797384)
					(mid 83.595778 -88.801878)
					(end 83.55584 -88.815164)
				)
				(arc
					(start 83.55584 -88.815164)
					(mid 83.235459 -89.230971)
					(end 83.39074 -88.729566)
				)
				(arc
					(start 83.39074 -88.729566)
					(mid 83.488315 -88.664524)
					(end 83.60156 -88.634062)
				)
				(xy 83.603338 -88.632284) (xy 83.741768 -88.632284) (xy 83.741768 -88.467184) (xy 83.603338 -88.467184)
				(arc
					(start 83.60156 -88.465406)
					(mid 83.488302 -88.434971)
					(end 83.39074 -88.369902)
				)
				(arc
					(start 83.39074 -88.369902)
					(mid 83.235468 -87.868514)
					(end 83.55584 -88.284304)
				)
				(arc
					(start 83.55584 -88.284304)
					(mid 83.59578 -88.297581)
					(end 83.637628 -88.302084)
				)
				(xy 83.741768 -88.302084)
			)
		)
	)
	(zone
		(net "GND")
		(layer "In5.Cu")
		(hatch none 0.5)
		(connect_pads
			(clearance 0.5)
		)
		(min_thickness 0.25)
		(fill yes
			(thermal_gap 0.5)
			(thermal_bridge_width 0.5)
			(island_removal_mode 0)
		)
		(polygon
			(pts
				(arc
					(start 0.999998 -0.763016)
					(mid 0.832426 -0.832426)
					(end 0.763016 -0.999998)
				)
				(arc
					(start 0.763016 -183.76392)
					(mid 0.769411 -183.818347)
					(end 0.788162 -183.869838)
				)
				(arc
					(start 5.406136 -193.10604)
					(mid 5.493436 -193.201687)
					(end 5.617972 -193.237104)
				)
				(arc
					(start 98.0821 -193.237104)
					(mid 98.206591 -193.201614)
					(end 98.293936 -193.10604)
				)
				(arc
					(start 102.91191 -183.869838)
					(mid 102.930633 -183.818341)
					(end 102.937056 -183.76392)
				)
				(xy 102.937056 -183.403748) (xy 100.874322 -183.403748) (xy 96.97339 -191.20612) (xy 6.726682 -191.20612)
				(xy 2.82575 -183.403748) (xy 2.767584 -183.403748) (xy 2.7305 -183.366664) (xy 2.7305 -183.313832)
				(xy 2.767584 -183.276748) (xy 2.794 -183.276748) (xy 2.794 -2.794) (xy 27.736038 -2.794)
				(arc
					(start 27.736038 -109.050074)
					(mid 27.777747 -109.610847)
					(end 27.9019 -110.159292)
				)
				(xy 30.050994 -110.159292) (xy 30.050994 -112.324134)
				(arc
					(start 29.613098 -112.324134)
					(mid 29.934606 -112.492272)
					(end 30.270704 -112.628934)
				)
				(xy 30.270704 -111.100362) (xy 66.190368 -111.100362) (xy 66.190368 -112.844072)
				(arc
					(start 72.030082 -112.844072)
					(mid 73.81565 -112.397636)
					(end 75.180952 -111.163354)
				)
				(xy 71.743062 -111.163354) (xy 71.743062 -110.813088)
				(arc
					(start 31.530036 -110.813088)
					(mid 30.283397 -110.296713)
					(end 29.767022 -109.050074)
				)
				(arc
					(start 29.767022 -0.999998)
					(mid 29.697612 -0.832426)
					(end 29.53004 -0.763016)
				)
			)
		)
	)
	(zone
		(layer "In5.Cu")
		(hatch none 0.5)
		(connect_pads
			(clearance 0)
		)
		(min_thickness 0.25)
		(keepout
			(tracks not_allowed)
			(vias allowed)
			(pads allowed)
			(copperpour not_allowed)
			(footprints allowed)
		)
		(placement
			(enabled no)
			(sheetname "")
		)
		(fill
			(thermal_gap 0.5)
			(thermal_bridge_width 0.5)
			(island_removal_mode 0)
		)
		(polygon
			(pts
				(arc
					(start 85.367368 -91.306396)
					(mid 84.983828 -90.922856)
					(end 84.600288 -91.306396)
				)
				(arc
					(start 84.600288 -92.195142)
					(mid 84.983701 -92.578936)
					(end 85.367368 -92.195396)
				)
				(xy 85.367368 -91.998546)
				(arc
					(start 85.263228 -91.998546)
					(mid 85.221378 -92.00304)
					(end 85.18144 -92.016326)
				)
				(arc
					(start 85.18144 -92.016326)
					(mid 84.861059 -92.432133)
					(end 85.01634 -91.930728)
				)
				(arc
					(start 85.01634 -91.930728)
					(mid 85.113915 -91.865686)
					(end 85.22716 -91.835224)
				)
				(xy 85.228938 -91.833446) (xy 85.367368 -91.833446) (xy 85.367368 -91.668346) (xy 85.228938 -91.668346)
				(arc
					(start 85.22716 -91.666568)
					(mid 85.113902 -91.636133)
					(end 85.01634 -91.571064)
				)
				(arc
					(start 85.01634 -91.571064)
					(mid 84.861068 -91.069676)
					(end 85.18144 -91.485466)
				)
				(arc
					(start 85.18144 -91.485466)
					(mid 85.22138 -91.498743)
					(end 85.263228 -91.503246)
				)
				(xy 85.367368 -91.503246)
			)
		)
	)
	(zone
		(layer "In5.Cu")
		(hatch none 0.5)
		(connect_pads
			(clearance 0)
		)
		(min_thickness 0.25)
		(keepout
			(tracks not_allowed)
			(vias allowed)
			(pads allowed)
			(copperpour not_allowed)
			(footprints allowed)
		)
		(placement
			(enabled no)
			(sheetname "")
		)
		(fill
			(thermal_gap 0.5)
			(thermal_bridge_width 0.5)
			(island_removal_mode 0)
		)
		(polygon
			(pts
				(xy 160.043622 -30.01899) (xy 159.837882 -29.81325) (xy 159.756602 -29.769816) (xy 159.733488 -29.75737)
				(xy 159.725868 -29.732224) (xy 159.691578 -29.619956) (xy 159.691578 -29.619702) (xy 159.683958 -29.59481)
				(xy 159.676338 -29.569664) (xy 159.676338 -29.56941) (xy 159.68853 -29.546296) (xy 159.700976 -29.523182)
				(arc
					(start 159.766508 -29.401008)
					(mid 160.180906 -28.764713)
					(end 159.878522 -29.461206)
				)
				(xy 159.81299 -29.582872) (xy 159.83966 -29.669994) (xy 159.892238 -29.698188) (xy 159.902652 -29.698188)
				(xy 159.91459 -29.710126) (xy 159.929322 -29.718) (xy 159.93237 -29.72816) (xy 160.10636 -29.901896)
				(arc
					(start 160.413446 -29.328618)
					(mid 160.225744 -28.684976)
					(end 159.583374 -28.877006)
				)
				(arc
					(start 158.833566 -30.277054)
					(mid 159.027114 -30.916626)
					(end 159.666686 -30.723078)
				)
				(xy 159.82569 -30.426152) (xy 159.82569 -30.23235) (xy 159.653986 -30.0609) (xy 159.635698 -30.05074)
				(xy 159.548576 -30.076902)
				(arc
					(start 159.483552 -30.198822)
					(mid 159.070703 -30.835973)
					(end 159.371538 -30.138878)
				)
				(xy 159.436816 -30.016958) (xy 159.449262 -29.993844) (xy 159.461454 -29.97073) (xy 159.461708 -29.97073)
				(xy 159.486854 -29.96311) (xy 159.512 -29.95549) (xy 159.599122 -29.929074) (xy 159.624268 -29.921708)
				(xy 159.649414 -29.914088) (xy 159.649668 -29.914088) (xy 159.672782 -29.926534) (xy 159.695642 -29.93898)
				(xy 159.695896 -29.93898) (xy 159.708342 -29.945838) (xy 159.718502 -29.945838) (xy 159.730694 -29.957776)
				(xy 159.74568 -29.965904) (xy 159.748474 -29.97581) (xy 159.915352 -30.142434) (xy 159.915606 -30.142434)
				(xy 159.934148 -30.160976) (xy 159.95269 -30.179518) (xy 159.95269 -30.188916)
			)
		)
	)
	(zone
		(layer "In5.Cu")
		(hatch none 0.5)
		(connect_pads
			(clearance 0)
		)
		(min_thickness 0.25)
		(keepout
			(tracks allowed)
			(vias allowed)
			(pads allowed)
			(copperpour allowed)
			(footprints allowed)
		)
		(placement
			(enabled no)
			(sheetname "")
		)
		(fill
			(thermal_gap 0.5)
			(thermal_bridge_width 0.5)
			(island_removal_mode 0)
		)
		(polygon
			(pts
				(xy 106.342688 -38.951916) (xy 106.342688 -27.662632) (xy 122.20575 -27.662632) (xy 122.20575 -38.951916)
			)
		)
	)
	(zone
		(layer "In5.Cu")
		(hatch none 0.5)
		(connect_pads
			(clearance 0)
		)
		(min_thickness 0.25)
		(keepout
			(tracks not_allowed)
			(vias allowed)
			(pads allowed)
			(copperpour not_allowed)
			(footprints allowed)
		)
		(placement
			(enabled no)
			(sheetname "")
		)
		(fill
			(thermal_gap 0.5)
			(thermal_bridge_width 0.5)
			(island_removal_mode 0)
		)
		(polygon
			(pts
				(arc
					(start 136.385046 -33.20034)
					(mid 135.900033 -32.714946)
					(end 135.414766 -33.200086)
				)
				(arc
					(start 135.414766 -33.650428)
					(mid 135.437615 -33.654216)
					(end 135.46074 -33.655508)
				)
				(arc
					(start 135.684006 -33.655508)
					(mid 135.754149 -33.635614)
					(end 135.803386 -33.581848)
				)
				(arc
					(start 135.803386 -33.581848)
					(mid 135.91019 -32.806515)
					(end 135.975344 -33.58642)
				)
				(arc
					(start 135.975344 -33.58642)
					(mid 135.884703 -33.742903)
					(end 135.720328 -33.818322)
				)
				(xy 135.718296 -33.820608) (xy 135.42645 -33.820608) (xy 135.424926 -33.81883) (xy 135.414766 -33.817814)
				(xy 135.414766 -33.983676) (xy 135.46074 -33.985708) (xy 135.718296 -33.985708)
				(arc
					(start 135.720328 -33.987994)
					(mid 135.882325 -34.061219)
					(end 135.974074 -34.213546)
				)
				(arc
					(start 135.974074 -34.213546)
					(mid 135.912407 -34.993614)
					(end 135.800338 -34.219134)
				)
				(arc
					(start 135.800338 -34.219134)
					(mid 135.751476 -34.169117)
					(end 135.684006 -34.150808)
				)
				(xy 135.42645 -34.150808) (xy 135.425688 -34.150046) (xy 135.414766 -34.149284)
				(arc
					(start 135.414766 -34.600134)
					(mid 135.899906 -35.085274)
					(end 136.385046 -34.600134)
				)
			)
		)
	)
	(zone
		(layer "In5.Cu")
		(hatch none 0.5)
		(connect_pads
			(clearance 0)
		)
		(min_thickness 0.25)
		(keepout
			(tracks not_allowed)
			(vias allowed)
			(pads allowed)
			(copperpour not_allowed)
			(footprints allowed)
		)
		(placement
			(enabled no)
			(sheetname "")
		)
		(fill
			(thermal_gap 0.5)
			(thermal_bridge_width 0.5)
			(island_removal_mode 0)
		)
		(polygon
			(pts
				(arc
					(start 138.185144 -32.000444)
					(mid 137.700131 -31.51505)
					(end 137.214864 -32.00019)
				)
				(arc
					(start 137.214864 -32.450278)
					(mid 137.237713 -32.454066)
					(end 137.260838 -32.455358)
				)
				(arc
					(start 137.484104 -32.455358)
					(mid 137.554125 -32.43545)
					(end 137.60323 -32.381698)
				)
				(arc
					(start 137.60323 -32.381698)
					(mid 137.710941 -31.606751)
					(end 137.775442 -32.386524)
				)
				(arc
					(start 137.775442 -32.386524)
					(mid 137.684746 -32.542877)
					(end 137.520426 -32.618172)
				)
				(xy 137.518394 -32.620458) (xy 137.226548 -32.620458) (xy 137.225024 -32.61868) (xy 137.214864 -32.617664)
				(xy 137.214864 -32.783526) (xy 137.260838 -32.785558) (xy 137.518394 -32.785558)
				(arc
					(start 137.520426 -32.787844)
					(mid 137.682423 -32.861069)
					(end 137.774172 -33.013396)
				)
				(arc
					(start 137.774172 -33.013396)
					(mid 137.712505 -33.793464)
					(end 137.600436 -33.018984)
				)
				(arc
					(start 137.600436 -33.018984)
					(mid 137.551574 -32.968967)
					(end 137.484104 -32.950658)
				)
				(xy 137.226548 -32.950658) (xy 137.225786 -32.949896) (xy 137.214864 -32.949134)
				(arc
					(start 137.214864 -33.399984)
					(mid 137.700004 -33.885124)
					(end 138.185144 -33.399984)
				)
			)
		)
	)
	(zone
		(layer "In5.Cu")
		(hatch none 0.5)
		(connect_pads
			(clearance 0)
		)
		(min_thickness 0.25)
		(keepout
			(tracks not_allowed)
			(vias allowed)
			(pads allowed)
			(copperpour not_allowed)
			(footprints allowed)
		)
		(placement
			(enabled no)
			(sheetname "")
		)
		(fill
			(thermal_gap 0.5)
			(thermal_bridge_width 0.5)
			(island_removal_mode 0)
		)
		(polygon
			(pts
				(xy 159.955992 -26.382726) (xy 160.043622 -26.218896) (xy 159.837882 -26.013156) (xy 159.756602 -25.969722)
				(xy 159.733488 -25.957276) (xy 159.725868 -25.93213) (xy 159.691578 -25.819862) (xy 159.691578 -25.819608)
				(xy 159.683958 -25.794716) (xy 159.676338 -25.76957) (xy 159.676338 -25.769316) (xy 159.68853 -25.746202)
				(xy 159.700976 -25.723088)
				(arc
					(start 159.766508 -25.600914)
					(mid 160.180906 -24.964619)
					(end 159.878522 -25.661112)
				)
				(xy 159.81299 -25.782778) (xy 159.83966 -25.8699) (xy 159.892238 -25.898094) (xy 159.902652 -25.898094)
				(xy 159.91459 -25.910032) (xy 159.929322 -25.917906) (xy 159.93237 -25.928066) (xy 160.10636 -26.101802)
				(arc
					(start 160.413446 -25.528524)
					(mid 160.225744 -24.884882)
					(end 159.583374 -25.076912)
				)
				(arc
					(start 158.833566 -26.47696)
					(mid 159.027114 -27.116532)
					(end 159.666686 -26.922984)
				)
				(xy 159.87649 -26.531062) (xy 159.87649 -26.483056) (xy 159.654748 -26.26106) (xy 159.635444 -26.250646)
				(xy 159.548576 -26.276808)
				(arc
					(start 159.483552 -26.398728)
					(mid 159.070703 -27.035879)
					(end 159.371538 -26.338784)
				)
				(xy 159.436816 -26.216864) (xy 159.449262 -26.19375) (xy 159.461454 -26.170636) (xy 159.461708 -26.170636)
				(xy 159.486854 -26.163016) (xy 159.512 -26.155396) (xy 159.599122 -26.12898) (xy 159.599376 -26.12898)
				(xy 159.624268 -26.12136) (xy 159.649414 -26.113994) (xy 159.649668 -26.113994) (xy 159.672782 -26.12644)
				(xy 159.695642 -26.138886) (xy 159.695896 -26.138886) (xy 159.709104 -26.146252) (xy 159.719518 -26.146252)
				(xy 159.731456 -26.158444) (xy 159.746442 -26.166572) (xy 159.74949 -26.176224)
			)
		)
	)
	(zone
		(layer "In5.Cu")
		(hatch none 0.5)
		(connect_pads
			(clearance 0)
		)
		(min_thickness 0.25)
		(keepout
			(tracks not_allowed)
			(vias allowed)
			(pads allowed)
			(copperpour not_allowed)
			(footprints allowed)
		)
		(placement
			(enabled no)
			(sheetname "")
		)
		(fill
			(thermal_gap 0.5)
			(thermal_bridge_width 0.5)
			(island_removal_mode 0)
		)
		(polygon
			(pts
				(arc
					(start 202.107292 -85.731096)
					(mid 202.107292 -85.192108)
					(end 201.568304 -85.192108)
				)
				(arc
					(start 200.944734 -85.815932)
					(mid 200.937655 -86.357046)
					(end 201.478896 -86.359492)
				)
				(xy 201.61758 -86.220808)
				(arc
					(start 201.54519 -86.148164)
					(mid 201.512897 -86.122123)
					(end 201.475848 -86.10346)
				)
				(arc
					(start 201.475848 -86.10346)
					(mid 200.955012 -86.170375)
					(end 201.419714 -85.925914)
				)
				(arc
					(start 201.419714 -85.925914)
					(mid 201.534221 -85.949007)
					(end 201.63536 -86.007448)
				)
				(xy 201.6379 -86.007448) (xy 201.661776 -86.031578) (xy 201.66203 -86.031578) (xy 201.73442 -86.103968)
				(xy 201.85126 -85.987128) (xy 201.755248 -85.89137)
				(arc
					(start 201.755248 -85.88883)
					(mid 201.696455 -85.78698)
					(end 201.67346 -85.67166)
				)
				(arc
					(start 201.67346 -85.67166)
					(mid 201.918562 -85.20742)
					(end 201.850752 -85.728048)
				)
				(arc
					(start 201.850752 -85.728048)
					(mid 201.869662 -85.765818)
					(end 201.896218 -85.79866)
				)
				(xy 201.967846 -85.870542)
			)
		)
	)
	(zone
		(layer "In5.Cu")
		(hatch none 0.5)
		(connect_pads
			(clearance 0)
		)
		(min_thickness 0.25)
		(keepout
			(tracks not_allowed)
			(vias allowed)
			(pads allowed)
			(copperpour not_allowed)
			(footprints allowed)
		)
		(placement
			(enabled no)
			(sheetname "")
		)
		(fill
			(thermal_gap 0.5)
			(thermal_bridge_width 0.5)
			(island_removal_mode 0)
		)
		(polygon
			(pts
				(arc
					(start 217.716354 -75.176126)
					(mid 217.716354 -74.637646)
					(end 217.177874 -74.637646)
				)
				(xy 217.17762 -74.637392) (xy 216.92616 -74.888852)
				(arc
					(start 217.062558 -75.02525)
					(mid 217.136979 -75.061001)
					(end 217.217498 -75.042522)
				)
				(arc
					(start 217.217498 -75.042522)
					(mid 217.637344 -74.719544)
					(end 217.307414 -75.133962)
				)
				(arc
					(start 217.307414 -75.133962)
					(mid 217.150418 -75.188728)
					(end 216.99347 -75.133708)
				)
				(xy 216.991184 -75.133708) (xy 216.972642 -75.115166) (xy 216.836244 -74.978768) (xy 216.710514 -75.104498)
				(xy 216.865454 -75.259438)
				(arc
					(start 216.865454 -75.261724)
					(mid 216.920592 -75.418494)
					(end 216.865962 -75.575414)
				)
				(arc
					(start 216.865962 -75.575414)
					(mid 216.451536 -75.905351)
					(end 216.774522 -75.485498)
				)
				(arc
					(start 216.774522 -75.485498)
					(mid 216.792798 -75.405107)
					(end 216.756996 -75.330812)
				)
				(xy 216.620598 -75.194414) (xy 216.369392 -75.44562)
				(arc
					(start 216.369646 -75.445874)
					(mid 216.369646 -75.984354)
					(end 216.908126 -75.984354)
				)
				(xy 216.90838 -75.984608) (xy 217.716354 -75.17638)
			)
		)
	)
	(zone
		(layer "In5.Cu")
		(hatch none 0.5)
		(connect_pads
			(clearance 0)
		)
		(min_thickness 0.25)
		(keepout
			(tracks not_allowed)
			(vias allowed)
			(pads allowed)
			(copperpour not_allowed)
			(footprints allowed)
		)
		(placement
			(enabled no)
			(sheetname "")
		)
		(fill
			(thermal_gap 0.5)
			(thermal_bridge_width 0.5)
			(island_removal_mode 0)
		)
		(polygon
			(pts
				(arc
					(start 194.944492 -83.927696)
					(mid 194.944492 -83.388708)
					(end 194.405504 -83.388708)
				)
				(arc
					(start 193.781934 -84.012532)
					(mid 193.774855 -84.553646)
					(end 194.316096 -84.556092)
				)
				(xy 194.45478 -84.417408)
				(arc
					(start 194.38239 -84.344764)
					(mid 194.350097 -84.318723)
					(end 194.313048 -84.30006)
				)
				(arc
					(start 194.313048 -84.30006)
					(mid 193.792212 -84.366975)
					(end 194.256914 -84.122514)
				)
				(arc
					(start 194.256914 -84.122514)
					(mid 194.371421 -84.145607)
					(end 194.47256 -84.204048)
				)
				(xy 194.4751 -84.204048) (xy 194.498976 -84.228178) (xy 194.49923 -84.228178) (xy 194.57162 -84.300568)
				(xy 194.68846 -84.183728) (xy 194.592448 -84.08797)
				(arc
					(start 194.592448 -84.08543)
					(mid 194.533655 -83.98358)
					(end 194.51066 -83.86826)
				)
				(arc
					(start 194.51066 -83.86826)
					(mid 194.755762 -83.40402)
					(end 194.687952 -83.924648)
				)
				(arc
					(start 194.687952 -83.924648)
					(mid 194.706862 -83.962418)
					(end 194.733418 -83.99526)
				)
				(xy 194.805046 -84.067142)
			)
		)
	)
	(zone
		(layer "In5.Cu")
		(hatch none 0.5)
		(connect_pads
			(clearance 0)
		)
		(min_thickness 0.25)
		(keepout
			(tracks not_allowed)
			(vias allowed)
			(pads allowed)
			(copperpour not_allowed)
			(footprints allowed)
		)
		(placement
			(enabled no)
			(sheetname "")
		)
		(fill
			(thermal_gap 0.5)
			(thermal_bridge_width 0.5)
			(island_removal_mode 0)
		)
		(polygon
			(pts
				(arc
					(start 85.367368 -72.08139)
					(mid 84.983955 -71.697596)
					(end 84.600288 -72.081136)
				)
				(arc
					(start 84.600288 -72.970136)
					(mid 84.983828 -73.353676)
					(end 85.367368 -72.970136)
				)
				(xy 85.367368 -72.773286)
				(arc
					(start 85.263228 -72.773286)
					(mid 85.221378 -72.77778)
					(end 85.18144 -72.791066)
				)
				(arc
					(start 85.18144 -72.791066)
					(mid 84.861059 -73.206873)
					(end 85.01634 -72.705468)
				)
				(arc
					(start 85.01634 -72.705468)
					(mid 85.113915 -72.640426)
					(end 85.22716 -72.609964)
				)
				(xy 85.228938 -72.608186) (xy 85.367368 -72.608186) (xy 85.367368 -72.443086) (xy 85.228938 -72.443086)
				(arc
					(start 85.22716 -72.441308)
					(mid 85.113902 -72.410873)
					(end 85.01634 -72.345804)
				)
				(arc
					(start 85.01634 -72.345804)
					(mid 84.861068 -71.844416)
					(end 85.18144 -72.260206)
				)
				(arc
					(start 85.18144 -72.260206)
					(mid 85.22138 -72.273483)
					(end 85.263228 -72.277986)
				)
				(xy 85.367368 -72.277986)
			)
		)
	)
	(zone
		(layer "In5.Cu")
		(hatch none 0.5)
		(connect_pads
			(clearance 0)
		)
		(min_thickness 0.25)
		(keepout
			(tracks not_allowed)
			(vias allowed)
			(pads allowed)
			(copperpour not_allowed)
			(footprints allowed)
		)
		(placement
			(enabled no)
			(sheetname "")
		)
		(fill
			(thermal_gap 0.5)
			(thermal_bridge_width 0.5)
			(island_removal_mode 0)
		)
		(polygon
			(pts
				(xy 211.131658 -63.314072) (xy 211.249768 -63.431928) (xy 211.286852 -63.469012)
				(arc
					(start 211.286852 -63.471552)
					(mid 211.341776 -63.628246)
					(end 211.287106 -63.784988)
				)
				(arc
					(start 211.287106 -63.784988)
					(mid 210.87268 -64.114925)
					(end 211.195666 -63.695072)
				)
				(arc
					(start 211.195666 -63.695072)
					(mid 211.214108 -63.614697)
					(end 211.178394 -63.540386)
				)
				(xy 211.159598 -63.521844) (xy 211.159598 -63.52159) (xy 211.041996 -63.403734) (xy 210.790536 -63.655194)
				(arc
					(start 210.79079 -63.655448)
					(mid 210.79079 -64.193928)
					(end 211.32927 -64.193928)
				)
				(xy 211.329524 -64.194182) (xy 212.05444 -63.469012) (xy 212.137498 -63.385954)
				(arc
					(start 212.137498 -63.3857)
					(mid 212.137498 -62.84722)
					(end 211.599018 -62.84722)
				)
				(xy 211.598764 -62.846966) (xy 211.347304 -63.098426)
				(arc
					(start 211.483956 -63.234824)
					(mid 211.55827 -63.270563)
					(end 211.638642 -63.252096)
				)
				(arc
					(start 211.638642 -63.252096)
					(mid 212.058488 -62.929118)
					(end 211.728558 -63.343536)
				)
				(arc
					(start 211.728558 -63.343536)
					(mid 211.571662 -63.398302)
					(end 211.414868 -63.343282)
				)
				(xy 211.412582 -63.343282) (xy 211.39404 -63.32474) (xy 211.257642 -63.188088)
			)
		)
	)
	(zone
		(layer "In5.Cu")
		(hatch none 0.5)
		(connect_pads
			(clearance 0)
		)
		(min_thickness 0.25)
		(keepout
			(tracks not_allowed)
			(vias allowed)
			(pads allowed)
			(copperpour not_allowed)
			(footprints allowed)
		)
		(placement
			(enabled no)
			(sheetname "")
		)
		(fill
			(thermal_gap 0.5)
			(thermal_bridge_width 0.5)
			(island_removal_mode 0)
		)
		(polygon
			(pts
				(arc
					(start 134.585202 -32.000444)
					(mid 134.100189 -31.51505)
					(end 133.614922 -32.00019)
				)
				(arc
					(start 133.614922 -32.450278)
					(mid 133.637771 -32.454066)
					(end 133.660896 -32.455358)
				)
				(arc
					(start 133.884162 -32.455358)
					(mid 133.954183 -32.43545)
					(end 134.003288 -32.381698)
				)
				(arc
					(start 134.003288 -32.381698)
					(mid 134.110999 -31.606751)
					(end 134.1755 -32.386524)
				)
				(arc
					(start 134.1755 -32.386524)
					(mid 134.084804 -32.542877)
					(end 133.920484 -32.618172)
				)
				(xy 133.918452 -32.620458) (xy 133.626606 -32.620458) (xy 133.625082 -32.61868) (xy 133.614922 -32.617664)
				(xy 133.614922 -32.783526) (xy 133.660896 -32.785558) (xy 133.918452 -32.785558)
				(arc
					(start 133.920484 -32.787844)
					(mid 134.082481 -32.861069)
					(end 134.17423 -33.013396)
				)
				(arc
					(start 134.17423 -33.013396)
					(mid 134.112563 -33.793464)
					(end 134.000494 -33.018984)
				)
				(arc
					(start 134.000494 -33.018984)
					(mid 133.951632 -32.968967)
					(end 133.884162 -32.950658)
				)
				(xy 133.626606 -32.950658) (xy 133.625844 -32.949896) (xy 133.614922 -32.949134)
				(arc
					(start 133.614922 -33.399984)
					(mid 134.100062 -33.885124)
					(end 134.585202 -33.399984)
				)
			)
		)
	)
	(zone
		(layers "In5.Cu" "In6.Cu")
		(hatch none 0.5)
		(connect_pads
			(clearance 0)
		)
		(min_thickness 0.25)
		(keepout
			(tracks not_allowed)
			(vias allowed)
			(pads allowed)
			(copperpour not_allowed)
			(footprints allowed)
		)
		(placement
			(enabled no)
			(sheetname "")
		)
		(fill yes
			(thermal_gap 0.5)
			(thermal_bridge_width 0.5)
			(island_removal_mode 0)
		)
		(polygon
			(pts
				(arc
					(start 189.539118 -80.6958)
					(mid 189.503197 -80.710679)
					(end 189.488318 -80.7466)
				)
				(arc
					(start 189.488318 -81.5594)
					(mid 189.503197 -81.595321)
					(end 189.539118 -81.6102)
				)
				(arc
					(start 189.742318 -81.6102)
					(mid 189.778239 -81.595321)
					(end 189.793118 -81.5594)
				)
				(arc
					(start 189.793118 -80.7466)
					(mid 189.778239 -80.710679)
					(end 189.742318 -80.6958)
				)
			)
		)
	)
	(zone
		(layers "In5.Cu" "In6.Cu")
		(hatch none 0.5)
		(connect_pads
			(clearance 0)
		)
		(min_thickness 0.25)
		(keepout
			(tracks not_allowed)
			(vias allowed)
			(pads allowed)
			(copperpour not_allowed)
			(footprints allowed)
		)
		(placement
			(enabled no)
			(sheetname "")
		)
		(fill yes
			(thermal_gap 0.5)
			(thermal_bridge_width 0.5)
			(island_removal_mode 0)
		)
		(polygon
			(pts
				(arc
					(start 191.28359 -21.0566)
					(mid 191.247669 -21.071479)
					(end 191.23279 -21.1074)
				)
				(arc
					(start 191.23279 -21.3106)
					(mid 191.247669 -21.346521)
					(end 191.28359 -21.3614)
				)
				(arc
					(start 192.09639 -21.3614)
					(mid 192.132311 -21.346521)
					(end 192.14719 -21.3106)
				)
				(arc
					(start 192.14719 -21.1074)
					(mid 192.132311 -21.071479)
					(end 192.09639 -21.0566)
				)
			)
		)
	)
	(zone
		(layers "In5.Cu" "In6.Cu")
		(hatch none 0.5)
		(connect_pads
			(clearance 0)
		)
		(min_thickness 0.25)
		(keepout
			(tracks not_allowed)
			(vias allowed)
			(pads allowed)
			(copperpour not_allowed)
			(footprints allowed)
		)
		(placement
			(enabled no)
			(sheetname "")
		)
		(fill yes
			(thermal_gap 0.5)
			(thermal_bridge_width 0.5)
			(island_removal_mode 0)
		)
		(polygon
			(pts
				(arc
					(start 198.429118 -80.6958)
					(mid 198.393197 -80.710679)
					(end 198.378318 -80.7466)
				)
				(arc
					(start 198.378318 -81.5594)
					(mid 198.393197 -81.595321)
					(end 198.429118 -81.6102)
				)
				(arc
					(start 198.632318 -81.6102)
					(mid 198.668239 -81.595321)
					(end 198.683118 -81.5594)
				)
				(arc
					(start 198.683118 -80.7466)
					(mid 198.668239 -80.710679)
					(end 198.632318 -80.6958)
				)
			)
		)
	)
	(zone
		(layers "In5.Cu" "In6.Cu")
		(hatch none 0.5)
		(connect_pads
			(clearance 0)
		)
		(min_thickness 0.25)
		(keepout
			(tracks not_allowed)
			(vias allowed)
			(pads allowed)
			(copperpour not_allowed)
			(footprints allowed)
		)
		(placement
			(enabled no)
			(sheetname "")
		)
		(fill yes
			(thermal_gap 0.5)
			(thermal_bridge_width 0.5)
			(island_removal_mode 0)
		)
		(polygon
			(pts
				(arc
					(start 200.257918 -80.6958)
					(mid 200.221997 -80.710679)
					(end 200.207118 -80.7466)
				)
				(arc
					(start 200.207118 -81.5594)
					(mid 200.221997 -81.595321)
					(end 200.257918 -81.6102)
				)
				(arc
					(start 200.461118 -81.6102)
					(mid 200.497039 -81.595321)
					(end 200.511918 -81.5594)
				)
				(arc
					(start 200.511918 -80.7466)
					(mid 200.497039 -80.710679)
					(end 200.461118 -80.6958)
				)
			)
		)
	)
	(zone
		(layers "In5.Cu" "In6.Cu")
		(hatch none 0.5)
		(connect_pads
			(clearance 0)
		)
		(min_thickness 0.25)
		(keepout
			(tracks not_allowed)
			(vias allowed)
			(pads allowed)
			(copperpour not_allowed)
			(footprints allowed)
		)
		(placement
			(enabled no)
			(sheetname "")
		)
		(fill yes
			(thermal_gap 0.5)
			(thermal_bridge_width 0.5)
			(island_removal_mode 0)
		)
		(polygon
			(pts
				(arc
					(start 201.527918 -80.6958)
					(mid 201.491997 -80.710679)
					(end 201.477118 -80.7466)
				)
				(arc
					(start 201.477118 -81.5594)
					(mid 201.491997 -81.595321)
					(end 201.527918 -81.6102)
				)
				(arc
					(start 201.731118 -81.6102)
					(mid 201.767039 -81.595321)
					(end 201.781918 -81.5594)
				)
				(arc
					(start 201.781918 -80.7466)
					(mid 201.767039 -80.710679)
					(end 201.731118 -80.6958)
				)
			)
		)
	)
	(zone
		(layers "In5.Cu" "In6.Cu")
		(hatch none 0.5)
		(connect_pads
			(clearance 0)
		)
		(min_thickness 0.25)
		(keepout
			(tracks not_allowed)
			(vias allowed)
			(pads allowed)
			(copperpour not_allowed)
			(footprints allowed)
		)
		(placement
			(enabled no)
			(sheetname "")
		)
		(fill yes
			(thermal_gap 0.5)
			(thermal_bridge_width 0.5)
			(island_removal_mode 0)
		)
		(polygon
			(pts
				(arc
					(start 191.571118 -80.6958)
					(mid 191.535197 -80.710679)
					(end 191.520318 -80.7466)
				)
				(arc
					(start 191.520318 -81.5594)
					(mid 191.535197 -81.595321)
					(end 191.571118 -81.6102)
				)
				(arc
					(start 191.774318 -81.6102)
					(mid 191.810239 -81.595321)
					(end 191.825118 -81.5594)
				)
				(arc
					(start 191.825118 -80.7466)
					(mid 191.810239 -80.710679)
					(end 191.774318 -80.6958)
				)
			)
		)
	)
	(zone
		(layers "In5.Cu" "In6.Cu")
		(hatch none 0.5)
		(connect_pads
			(clearance 0)
		)
		(min_thickness 0.25)
		(keepout
			(tracks not_allowed)
			(vias allowed)
			(pads allowed)
			(copperpour not_allowed)
			(footprints allowed)
		)
		(placement
			(enabled no)
			(sheetname "")
		)
		(fill yes
			(thermal_gap 0.5)
			(thermal_bridge_width 0.5)
			(island_removal_mode 0)
		)
		(polygon
			(pts
				(arc
					(start 190.097918 -80.6958)
					(mid 190.061997 -80.710679)
					(end 190.047118 -80.7466)
				)
				(arc
					(start 190.047118 -81.5594)
					(mid 190.061997 -81.595321)
					(end 190.097918 -81.6102)
				)
				(arc
					(start 190.301118 -81.6102)
					(mid 190.337039 -81.595321)
					(end 190.351918 -81.5594)
				)
				(arc
					(start 190.351918 -80.7466)
					(mid 190.337039 -80.710679)
					(end 190.301118 -80.6958)
				)
			)
		)
	)
	(zone
		(layers "In5.Cu" "In6.Cu")
		(hatch none 0.5)
		(connect_pads
			(clearance 0)
		)
		(min_thickness 0.25)
		(keepout
			(tracks not_allowed)
			(vias allowed)
			(pads allowed)
			(copperpour not_allowed)
			(footprints allowed)
		)
		(placement
			(enabled no)
			(sheetname "")
		)
		(fill yes
			(thermal_gap 0.5)
			(thermal_bridge_width 0.5)
			(island_removal_mode 0)
		)
		(polygon
			(pts
				(arc
					(start 197.159118 -80.6958)
					(mid 197.123197 -80.710679)
					(end 197.108318 -80.7466)
				)
				(arc
					(start 197.108318 -81.5594)
					(mid 197.123197 -81.595321)
					(end 197.159118 -81.6102)
				)
				(arc
					(start 197.362318 -81.6102)
					(mid 197.398239 -81.595321)
					(end 197.413118 -81.5594)
				)
				(arc
					(start 197.413118 -80.7466)
					(mid 197.398239 -80.710679)
					(end 197.362318 -80.6958)
				)
			)
		)
	)
	(zone
		(layers "In5.Cu" "In6.Cu")
		(hatch none 0.5)
		(connect_pads
			(clearance 0)
		)
		(min_thickness 0.25)
		(keepout
			(tracks not_allowed)
			(vias allowed)
			(pads allowed)
			(copperpour not_allowed)
			(footprints allowed)
		)
		(placement
			(enabled no)
			(sheetname "")
		)
		(fill yes
			(thermal_gap 0.5)
			(thermal_bridge_width 0.5)
			(island_removal_mode 0)
		)
		(polygon
			(pts
				(arc
					(start 191.28359 -19.0246)
					(mid 191.247669 -19.039479)
					(end 191.23279 -19.0754)
				)
				(arc
					(start 191.23279 -19.2786)
					(mid 191.247669 -19.314521)
					(end 191.28359 -19.3294)
				)
				(arc
					(start 192.09639 -19.3294)
					(mid 192.132311 -19.314521)
					(end 192.14719 -19.2786)
				)
				(arc
					(start 192.14719 -19.0754)
					(mid 192.132311 -19.039479)
					(end 192.09639 -19.0246)
				)
			)
		)
	)
	(zone
		(layers "In5.Cu" "In6.Cu")
		(hatch none 0.5)
		(connect_pads
			(clearance 0)
		)
		(min_thickness 0.25)
		(keepout
			(tracks not_allowed)
			(vias allowed)
			(pads allowed)
			(copperpour not_allowed)
			(footprints allowed)
		)
		(placement
			(enabled no)
			(sheetname "")
		)
		(fill yes
			(thermal_gap 0.5)
			(thermal_bridge_width 0.5)
			(island_removal_mode 0)
		)
		(polygon
			(pts
				(arc
					(start 192.841118 -80.6958)
					(mid 192.805197 -80.710679)
					(end 192.790318 -80.7466)
				)
				(arc
					(start 192.790318 -81.5594)
					(mid 192.805197 -81.595321)
					(end 192.841118 -81.6102)
				)
				(arc
					(start 193.044318 -81.6102)
					(mid 193.080239 -81.595321)
					(end 193.095118 -81.5594)
				)
				(arc
					(start 193.095118 -80.7466)
					(mid 193.080239 -80.710679)
					(end 193.044318 -80.6958)
				)
			)
		)
	)
	(zone
		(layers "In5.Cu" "In6.Cu")
		(hatch none 0.5)
		(connect_pads
			(clearance 0)
		)
		(min_thickness 0.25)
		(keepout
			(tracks not_allowed)
			(vias allowed)
			(pads allowed)
			(copperpour not_allowed)
			(footprints allowed)
		)
		(placement
			(enabled no)
			(sheetname "")
		)
		(fill yes
			(thermal_gap 0.5)
			(thermal_bridge_width 0.5)
			(island_removal_mode 0)
		)
		(polygon
			(pts
				(arc
					(start 191.28359 -23.7236)
					(mid 191.247669 -23.738479)
					(end 191.23279 -23.7744)
				)
				(arc
					(start 191.23279 -23.9776)
					(mid 191.247669 -24.013521)
					(end 191.28359 -24.0284)
				)
				(arc
					(start 192.09639 -24.0284)
					(mid 192.132311 -24.013521)
					(end 192.14719 -23.9776)
				)
				(arc
					(start 192.14719 -23.7744)
					(mid 192.132311 -23.738479)
					(end 192.09639 -23.7236)
				)
			)
		)
	)
	(zone
		(layers "In5.Cu" "In6.Cu")
		(hatch none 0.5)
		(connect_pads
			(clearance 0)
		)
		(min_thickness 0.25)
		(keepout
			(tracks not_allowed)
			(vias allowed)
			(pads allowed)
			(copperpour not_allowed)
			(footprints allowed)
		)
		(placement
			(enabled no)
			(sheetname "")
		)
		(fill yes
			(thermal_gap 0.5)
			(thermal_bridge_width 0.5)
			(island_removal_mode 0)
		)
		(polygon
			(pts
				(arc
					(start 191.283336 -25.1206)
					(mid 191.247415 -25.135479)
					(end 191.232536 -25.1714)
				)
				(arc
					(start 191.232536 -25.3746)
					(mid 191.247415 -25.410521)
					(end 191.283336 -25.4254)
				)
				(arc
					(start 192.096136 -25.4254)
					(mid 192.132057 -25.410521)
					(end 192.146936 -25.3746)
				)
				(arc
					(start 192.146936 -25.1714)
					(mid 192.132057 -25.135479)
					(end 192.096136 -25.1206)
				)
			)
		)
	)
	(zone
		(layers "In5.Cu" "In6.Cu")
		(hatch none 0.5)
		(connect_pads
			(clearance 0)
		)
		(min_thickness 0.25)
		(keepout
			(tracks not_allowed)
			(vias allowed)
			(pads allowed)
			(copperpour not_allowed)
			(footprints allowed)
		)
		(placement
			(enabled no)
			(sheetname "")
		)
		(fill yes
			(thermal_gap 0.5)
			(thermal_bridge_width 0.5)
			(island_removal_mode 0)
		)
		(polygon
			(pts
				(arc
					(start 197.717918 -80.6958)
					(mid 197.681997 -80.710679)
					(end 197.667118 -80.7466)
				)
				(arc
					(start 197.667118 -81.5594)
					(mid 197.681997 -81.595321)
					(end 197.717918 -81.6102)
				)
				(arc
					(start 197.921118 -81.6102)
					(mid 197.957039 -81.595321)
					(end 197.971918 -81.5594)
				)
				(arc
					(start 197.971918 -80.7466)
					(mid 197.957039 -80.710679)
					(end 197.921118 -80.6958)
				)
			)
		)
	)
	(zone
		(layers "In5.Cu" "In6.Cu")
		(hatch none 0.5)
		(connect_pads
			(clearance 0)
		)
		(min_thickness 0.25)
		(keepout
			(tracks not_allowed)
			(vias allowed)
			(pads allowed)
			(copperpour not_allowed)
			(footprints allowed)
		)
		(placement
			(enabled no)
			(sheetname "")
		)
		(fill yes
			(thermal_gap 0.5)
			(thermal_bridge_width 0.5)
			(island_removal_mode 0)
		)
		(polygon
			(pts
				(arc
					(start 199.699118 -80.6958)
					(mid 199.663197 -80.710679)
					(end 199.648318 -80.7466)
				)
				(arc
					(start 199.648318 -81.5594)
					(mid 199.663197 -81.595321)
					(end 199.699118 -81.6102)
				)
				(arc
					(start 199.902318 -81.6102)
					(mid 199.938239 -81.595321)
					(end 199.953118 -81.5594)
				)
				(arc
					(start 199.953118 -80.7466)
					(mid 199.938239 -80.710679)
					(end 199.902318 -80.6958)
				)
			)
		)
	)
	(zone
		(layers "In5.Cu" "In6.Cu")
		(hatch none 0.5)
		(connect_pads
			(clearance 0)
		)
		(min_thickness 0.25)
		(keepout
			(tracks not_allowed)
			(vias allowed)
			(pads allowed)
			(copperpour not_allowed)
			(footprints allowed)
		)
		(placement
			(enabled no)
			(sheetname "")
		)
		(fill yes
			(thermal_gap 0.5)
			(thermal_bridge_width 0.5)
			(island_removal_mode 0)
		)
		(polygon
			(pts
				(arc
					(start 191.28359 -21.6916)
					(mid 191.247669 -21.706479)
					(end 191.23279 -21.7424)
				)
				(arc
					(start 191.23279 -21.9456)
					(mid 191.247669 -21.981521)
					(end 191.28359 -21.9964)
				)
				(arc
					(start 192.09639 -21.9964)
					(mid 192.132311 -21.981521)
					(end 192.14719 -21.9456)
				)
				(arc
					(start 192.14719 -21.7424)
					(mid 192.132311 -21.706479)
					(end 192.09639 -21.6916)
				)
			)
		)
	)
	(zone
		(layers "In5.Cu" "In6.Cu")
		(hatch none 0.5)
		(connect_pads
			(clearance 0)
		)
		(min_thickness 0.25)
		(keepout
			(tracks not_allowed)
			(vias allowed)
			(pads allowed)
			(copperpour not_allowed)
			(footprints allowed)
		)
		(placement
			(enabled no)
			(sheetname "")
		)
		(fill yes
			(thermal_gap 0.5)
			(thermal_bridge_width 0.5)
			(island_removal_mode 0)
		)
		(polygon
			(pts
				(arc
					(start 193.399918 -80.6958)
					(mid 193.363997 -80.710679)
					(end 193.349118 -80.7466)
				)
				(arc
					(start 193.349118 -81.5594)
					(mid 193.363997 -81.595321)
					(end 193.399918 -81.6102)
				)
				(arc
					(start 193.603118 -81.6102)
					(mid 193.639039 -81.595321)
					(end 193.653918 -81.5594)
				)
				(arc
					(start 193.653918 -80.7466)
					(mid 193.639039 -80.710679)
					(end 193.603118 -80.6958)
				)
			)
		)
	)
	(zone
		(layers "In5.Cu" "In6.Cu")
		(hatch none 0.5)
		(connect_pads
			(clearance 0)
		)
		(min_thickness 0.25)
		(keepout
			(tracks not_allowed)
			(vias allowed)
			(pads allowed)
			(copperpour not_allowed)
			(footprints allowed)
		)
		(placement
			(enabled no)
			(sheetname "")
		)
		(fill yes
			(thermal_gap 0.5)
			(thermal_bridge_width 0.5)
			(island_removal_mode 0)
		)
		(polygon
			(pts
				(arc
					(start 198.987918 -80.6958)
					(mid 198.951997 -80.710679)
					(end 198.937118 -80.7466)
				)
				(arc
					(start 198.937118 -81.5594)
					(mid 198.951997 -81.595321)
					(end 198.987918 -81.6102)
				)
				(arc
					(start 199.191118 -81.6102)
					(mid 199.227039 -81.595321)
					(end 199.241918 -81.5594)
				)
				(arc
					(start 199.241918 -80.7466)
					(mid 199.227039 -80.710679)
					(end 199.191118 -80.6958)
				)
			)
		)
	)
	(zone
		(layers "In5.Cu" "In6.Cu")
		(hatch none 0.5)
		(connect_pads
			(clearance 0)
		)
		(min_thickness 0.25)
		(keepout
			(tracks not_allowed)
			(vias allowed)
			(pads allowed)
			(copperpour not_allowed)
			(footprints allowed)
		)
		(placement
			(enabled no)
			(sheetname "")
		)
		(fill yes
			(thermal_gap 0.5)
			(thermal_bridge_width 0.5)
			(island_removal_mode 0)
		)
		(polygon
			(pts
				(arc
					(start 191.283336 -25.7556)
					(mid 191.247415 -25.770479)
					(end 191.232536 -25.8064)
				)
				(arc
					(start 191.232536 -26.0096)
					(mid 191.247415 -26.045521)
					(end 191.283336 -26.0604)
				)
				(arc
					(start 192.096136 -26.0604)
					(mid 192.132057 -26.045521)
					(end 192.146936 -26.0096)
				)
				(arc
					(start 192.146936 -25.8064)
					(mid 192.132057 -25.770479)
					(end 192.096136 -25.7556)
				)
			)
		)
	)
	(zone
		(layers "In5.Cu" "In6.Cu")
		(hatch none 0.5)
		(connect_pads
			(clearance 0)
		)
		(min_thickness 0.25)
		(keepout
			(tracks not_allowed)
			(vias allowed)
			(pads allowed)
			(copperpour not_allowed)
			(footprints allowed)
		)
		(placement
			(enabled no)
			(sheetname "")
		)
		(fill yes
			(thermal_gap 0.5)
			(thermal_bridge_width 0.5)
			(island_removal_mode 0)
		)
		(polygon
			(pts
				(arc
					(start 200.969118 -80.6958)
					(mid 200.933197 -80.710679)
					(end 200.918318 -80.7466)
				)
				(arc
					(start 200.918318 -81.5594)
					(mid 200.933197 -81.595321)
					(end 200.969118 -81.6102)
				)
				(arc
					(start 201.172318 -81.6102)
					(mid 201.208239 -81.595321)
					(end 201.223118 -81.5594)
				)
				(arc
					(start 201.223118 -80.7466)
					(mid 201.208239 -80.710679)
					(end 201.172318 -80.6958)
				)
			)
		)
	)
	(zone
		(layers "In5.Cu" "In6.Cu")
		(hatch none 0.5)
		(connect_pads
			(clearance 0)
		)
		(min_thickness 0.25)
		(keepout
			(tracks not_allowed)
			(vias allowed)
			(pads allowed)
			(copperpour not_allowed)
			(footprints allowed)
		)
		(placement
			(enabled no)
			(sheetname "")
		)
		(fill yes
			(thermal_gap 0.5)
			(thermal_bridge_width 0.5)
			(island_removal_mode 0)
		)
		(polygon
			(pts
				(arc
					(start 191.28359 -19.6596)
					(mid 191.247669 -19.674479)
					(end 191.23279 -19.7104)
				)
				(arc
					(start 191.23279 -19.9136)
					(mid 191.247669 -19.949521)
					(end 191.28359 -19.9644)
				)
				(arc
					(start 192.09639 -19.9644)
					(mid 192.132311 -19.949521)
					(end 192.14719 -19.9136)
				)
				(arc
					(start 192.14719 -19.7104)
					(mid 192.132311 -19.674479)
					(end 192.09639 -19.6596)
				)
			)
		)
	)
	(zone
		(layers "In5.Cu" "In6.Cu")
		(hatch none 0.5)
		(connect_pads
			(clearance 0)
		)
		(min_thickness 0.25)
		(keepout
			(tracks not_allowed)
			(vias allowed)
			(pads allowed)
			(copperpour not_allowed)
			(footprints allowed)
		)
		(placement
			(enabled no)
			(sheetname "")
		)
		(fill yes
			(thermal_gap 0.5)
			(thermal_bridge_width 0.5)
			(island_removal_mode 0)
		)
		(polygon
			(pts
				(arc
					(start 191.28359 -23.0886)
					(mid 191.247669 -23.103479)
					(end 191.23279 -23.1394)
				)
				(arc
					(start 191.23279 -23.3426)
					(mid 191.247669 -23.378521)
					(end 191.28359 -23.3934)
				)
				(arc
					(start 192.09639 -23.3934)
					(mid 192.132311 -23.378521)
					(end 192.14719 -23.3426)
				)
				(arc
					(start 192.14719 -23.1394)
					(mid 192.132311 -23.103479)
					(end 192.09639 -23.0886)
				)
			)
		)
	)
	(zone
		(layers "In5.Cu" "In6.Cu")
		(hatch none 0.5)
		(connect_pads
			(clearance 0)
		)
		(min_thickness 0.25)
		(keepout
			(tracks not_allowed)
			(vias allowed)
			(pads allowed)
			(copperpour not_allowed)
			(footprints allowed)
		)
		(placement
			(enabled no)
			(sheetname "")
		)
		(fill yes
			(thermal_gap 0.5)
			(thermal_bridge_width 0.5)
			(island_removal_mode 0)
		)
		(polygon
			(pts
				(arc
					(start 192.129918 -80.6958)
					(mid 192.093997 -80.710679)
					(end 192.079118 -80.7466)
				)
				(arc
					(start 192.079118 -81.5594)
					(mid 192.093997 -81.595321)
					(end 192.129918 -81.6102)
				)
				(arc
					(start 192.333118 -81.6102)
					(mid 192.369039 -81.595321)
					(end 192.383918 -81.5594)
				)
				(arc
					(start 192.383918 -80.7466)
					(mid 192.369039 -80.710679)
					(end 192.333118 -80.6958)
				)
			)
		)
	)
	(zone
		(layer "In6.Cu")
		(hatch none 0.5)
		(connect_pads
			(clearance 0)
		)
		(min_thickness 0.25)
		(keepout
			(tracks not_allowed)
			(vias allowed)
			(pads allowed)
			(copperpour not_allowed)
			(footprints allowed)
		)
		(placement
			(enabled no)
			(sheetname "")
		)
		(fill
			(thermal_gap 0.5)
			(thermal_bridge_width 0.5)
			(island_removal_mode 0)
		)
		(polygon
			(pts
				(arc
					(start 169.23639 -37.984938)
					(mid 169.200469 -37.999817)
					(end 169.18559 -38.035738)
				)
				(arc
					(start 169.18559 -38.848538)
					(mid 169.200469 -38.884459)
					(end 169.23639 -38.899338)
				)
				(arc
					(start 169.43959 -38.899338)
					(mid 169.475511 -38.884459)
					(end 169.49039 -38.848538)
				)
				(arc
					(start 169.49039 -38.035738)
					(mid 169.475511 -37.999817)
					(end 169.43959 -37.984938)
				)
			)
		)
	)
	(zone
		(layer "In6.Cu")
		(hatch none 0.5)
		(connect_pads
			(clearance 0)
		)
		(min_thickness 0.25)
		(keepout
			(tracks not_allowed)
			(vias allowed)
			(pads allowed)
			(copperpour not_allowed)
			(footprints allowed)
		)
		(placement
			(enabled no)
			(sheetname "")
		)
		(fill
			(thermal_gap 0.5)
			(thermal_bridge_width 0.5)
			(island_removal_mode 0)
		)
		(polygon
			(pts
				(arc
					(start 165.857936 -37.959538)
					(mid 165.822015 -37.974417)
					(end 165.807136 -38.010338)
				)
				(arc
					(start 165.807136 -38.823138)
					(mid 165.822015 -38.859059)
					(end 165.857936 -38.873938)
				)
				(arc
					(start 166.061136 -38.873938)
					(mid 166.097057 -38.859059)
					(end 166.111936 -38.823138)
				)
				(arc
					(start 166.111936 -38.010338)
					(mid 166.097057 -37.974417)
					(end 166.061136 -37.959538)
				)
			)
		)
	)
	(zone
		(layer "In6.Cu")
		(hatch none 0.5)
		(connect_pads
			(clearance 0)
		)
		(min_thickness 0.25)
		(keepout
			(tracks not_allowed)
			(vias allowed)
			(pads allowed)
			(copperpour not_allowed)
			(footprints allowed)
		)
		(placement
			(enabled no)
			(sheetname "")
		)
		(fill
			(thermal_gap 0.5)
			(thermal_bridge_width 0.5)
			(island_removal_mode 0)
		)
		(polygon
			(pts
				(arc
					(start 165.222936 -37.959538)
					(mid 165.187015 -37.974417)
					(end 165.172136 -38.010338)
				)
				(arc
					(start 165.172136 -38.823138)
					(mid 165.187015 -38.859059)
					(end 165.222936 -38.873938)
				)
				(arc
					(start 165.426136 -38.873938)
					(mid 165.462057 -38.859059)
					(end 165.476936 -38.823138)
				)
				(arc
					(start 165.476936 -38.010338)
					(mid 165.462057 -37.974417)
					(end 165.426136 -37.959538)
				)
			)
		)
	)
	(zone
		(layer "In6.Cu")
		(hatch none 0.5)
		(connect_pads
			(clearance 0)
		)
		(min_thickness 0.25)
		(keepout
			(tracks not_allowed)
			(vias allowed)
			(pads allowed)
			(copperpour not_allowed)
			(footprints allowed)
		)
		(placement
			(enabled no)
			(sheetname "")
		)
		(fill
			(thermal_gap 0.5)
			(thermal_bridge_width 0.5)
			(island_removal_mode 0)
		)
		(polygon
			(pts
				(arc
					(start 167.864536 -37.984938)
					(mid 167.828615 -37.999817)
					(end 167.813736 -38.035738)
				)
				(arc
					(start 167.813736 -38.848538)
					(mid 167.828615 -38.884459)
					(end 167.864536 -38.899338)
				)
				(arc
					(start 168.067736 -38.899338)
					(mid 168.103657 -38.884459)
					(end 168.118536 -38.848538)
				)
				(arc
					(start 168.118536 -38.035738)
					(mid 168.103657 -37.999817)
					(end 168.067736 -37.984938)
				)
			)
		)
	)
	(zone
		(layer "In6.Cu")
		(hatch none 0.5)
		(connect_pads
			(clearance 0)
		)
		(min_thickness 0.25)
		(keepout
			(tracks not_allowed)
			(vias allowed)
			(pads allowed)
			(copperpour not_allowed)
			(footprints allowed)
		)
		(placement
			(enabled no)
			(sheetname "")
		)
		(fill
			(thermal_gap 0.5)
			(thermal_bridge_width 0.5)
			(island_removal_mode 0)
		)
		(polygon
			(pts
				(arc
					(start 167.17899 -37.959538)
					(mid 167.143069 -37.974417)
					(end 167.12819 -38.010338)
				)
				(arc
					(start 167.12819 -38.823138)
					(mid 167.143069 -38.859059)
					(end 167.17899 -38.873938)
				)
				(arc
					(start 167.38219 -38.873938)
					(mid 167.418111 -38.859059)
					(end 167.43299 -38.823138)
				)
				(arc
					(start 167.43299 -38.010338)
					(mid 167.418111 -37.974417)
					(end 167.38219 -37.959538)
				)
			)
		)
	)
	(zone
		(layer "In6.Cu")
		(hatch none 0.5)
		(connect_pads
			(clearance 0)
		)
		(min_thickness 0.25)
		(keepout
			(tracks not_allowed)
			(vias allowed)
			(pads allowed)
			(copperpour not_allowed)
			(footprints allowed)
		)
		(placement
			(enabled no)
			(sheetname "")
		)
		(fill
			(thermal_gap 0.5)
			(thermal_bridge_width 0.5)
			(island_removal_mode 0)
		)
		(polygon
			(pts
				(arc
					(start 168.499536 -37.984938)
					(mid 168.463615 -37.999817)
					(end 168.448736 -38.035738)
				)
				(arc
					(start 168.448736 -38.848538)
					(mid 168.463615 -38.884459)
					(end 168.499536 -38.899338)
				)
				(arc
					(start 168.702736 -38.899338)
					(mid 168.738657 -38.884459)
					(end 168.753536 -38.848538)
				)
				(arc
					(start 168.753536 -38.035738)
					(mid 168.738657 -37.999817)
					(end 168.702736 -37.984938)
				)
			)
		)
	)
	(zone
		(net "GND")
		(layer "In6.Cu")
		(hatch none 0.5)
		(connect_pads
			(clearance 0.5)
		)
		(min_thickness 0.25)
		(fill yes
			(thermal_gap 0.5)
			(thermal_bridge_width 0.5)
			(island_removal_mode 0)
		)
		(polygon
			(pts
				(arc
					(start 0.999998 -0.763016)
					(mid 0.832426 -0.832426)
					(end 0.763016 -0.999998)
				)
				(arc
					(start 0.763016 -183.76392)
					(mid 0.769411 -183.818347)
					(end 0.788162 -183.869838)
				)
				(arc
					(start 5.406136 -193.10604)
					(mid 5.493436 -193.201687)
					(end 5.617972 -193.237104)
				)
				(arc
					(start 98.0821 -193.237104)
					(mid 98.206591 -193.201614)
					(end 98.293936 -193.10604)
				)
				(arc
					(start 102.91191 -183.869838)
					(mid 102.930633 -183.818341)
					(end 102.937056 -183.76392)
				)
				(arc
					(start 102.937056 -47.999904)
					(mid 103.797626 -46.802631)
					(end 105.206546 -47.236888)
				)
				(arc
					(start 142.793466 -47.236888)
					(mid 144.202311 -46.802855)
					(end 145.062956 -47.999904)
				)
				(arc
					(start 145.062956 -183.76392)
					(mid 145.069351 -183.818347)
					(end 145.088102 -183.869838)
				)
				(arc
					(start 149.706076 -193.10604)
					(mid 149.793376 -193.201687)
					(end 149.917912 -193.237104)
				)
				(arc
					(start 229.382066 -193.237104)
					(mid 229.506557 -193.201614)
					(end 229.593902 -193.10604)
				)
				(arc
					(start 234.211876 -183.869838)
					(mid 234.230599 -183.818341)
					(end 234.237022 -183.76392)
				)
				(arc
					(start 234.237022 -0.999998)
					(mid 234.167612 -0.832426)
					(end 234.00004 -0.763016)
				)
				(arc
					(start 74.030078 -0.763016)
					(mid 73.862506 -0.832426)
					(end 73.793096 -0.999998)
				)
				(arc
					(start 73.793096 -109.050074)
					(mid 73.276721 -110.296713)
					(end 72.030082 -110.813088)
				)
				(arc
					(start 31.530036 -110.813088)
					(mid 30.283397 -110.296713)
					(end 29.767022 -109.050074)
				)
				(arc
					(start 29.767022 -0.999998)
					(mid 29.697612 -0.832426)
					(end 29.53004 -0.763016)
				)
			)
		)
		(polygon
			(pts
				(arc
					(start 83.741768 -94.492572)
					(mid 83.358228 -94.109032)
					(end 82.974688 -94.492572)
				)
				(arc
					(start 82.974688 -95.381826)
					(mid 83.358355 -95.765112)
					(end 83.741768 -95.381572)
				)
			)
		)
		(polygon
			(pts
				(arc
					(start 77.667358 -92.911168)
					(mid 77.283818 -92.527628)
					(end 76.900278 -92.911168)
				)
				(arc
					(start 76.900278 -93.800422)
					(mid 77.283945 -94.183708)
					(end 77.667358 -93.800168)
				)
			)
		)
		(polygon
			(pts
				(arc
					(start 85.367368 -91.306396)
					(mid 84.983828 -90.922856)
					(end 84.600288 -91.306396)
				)
				(arc
					(start 84.600288 -92.19565)
					(mid 84.983955 -92.578936)
					(end 85.367368 -92.195396)
				)
			)
		)
		(polygon
			(pts
				(arc
					(start 78.505558 -89.710768)
					(mid 78.122018 -89.327228)
					(end 77.738478 -89.710768)
				)
				(arc
					(start 77.738478 -90.600022)
					(mid 78.122145 -90.983308)
					(end 78.505558 -90.599768)
				)
			)
		)
		(polygon
			(pts
				(arc
					(start 199.084692 -88.728296)
					(mid 199.084692 -88.189308)
					(end 198.545704 -88.189308)
				)
				(arc
					(start 197.922134 -88.813132)
					(mid 197.915055 -89.354246)
					(end 198.456296 -89.356692)
				)
			)
		)
		(polygon
			(pts
				(arc
					(start 194.720464 -88.652096)
					(mid 194.720464 -88.113108)
					(end 194.181476 -88.113108)
				)
				(arc
					(start 193.557906 -88.736932)
					(mid 193.550827 -89.278046)
					(end 194.092068 -89.280492)
				)
			)
		)
		(polygon
			(pts
				(arc
					(start 83.741768 -88.10498)
					(mid 83.358101 -87.721694)
					(end 82.974688 -88.105234)
				)
				(arc
					(start 82.974688 -88.994234)
					(mid 83.358228 -89.377774)
					(end 83.741768 -88.994234)
				)
			)
		)
		(polygon
			(pts
				(arc
					(start 191.998092 -86.950296)
					(mid 191.998092 -86.411308)
					(end 191.459104 -86.411308)
				)
				(arc
					(start 190.835534 -87.035132)
					(mid 190.828455 -87.576246)
					(end 191.369696 -87.578692)
				)
			)
		)
		(polygon
			(pts
				(arc
					(start 77.667358 -86.510368)
					(mid 77.283818 -86.126828)
					(end 76.900278 -86.510368)
				)
				(arc
					(start 76.900278 -87.399622)
					(mid 77.283945 -87.782908)
					(end 77.667358 -87.399368)
				)
			)
		)
		(polygon
			(pts
				(arc
					(start 202.107292 -85.731096)
					(mid 202.107292 -85.192108)
					(end 201.568304 -85.192108)
				)
				(arc
					(start 200.944734 -85.815932)
					(mid 200.937655 -86.357046)
					(end 201.478896 -86.359492)
				)
			)
		)
		(polygon
			(pts
				(arc
					(start 197.793864 -85.604096)
					(mid 197.793864 -85.065108)
					(end 197.254876 -85.065108)
				)
				(arc
					(start 196.631306 -85.688932)
					(mid 196.624227 -86.230046)
					(end 197.165468 -86.232492)
				)
			)
		)
		(polygon
			(pts
				(arc
					(start 85.367368 -84.904834)
					(mid 84.983828 -84.521294)
					(end 84.600288 -84.904834)
				)
				(arc
					(start 84.600288 -85.794088)
					(mid 84.983955 -86.177374)
					(end 85.367368 -85.793834)
				)
			)
		)
		(polygon
			(pts
				(arc
					(start 204.698092 -85.146896)
					(mid 204.698092 -84.607908)
					(end 204.159104 -84.607908)
				)
				(arc
					(start 203.535534 -85.231732)
					(mid 203.528455 -85.772846)
					(end 204.069696 -85.775292)
				)
			)
		)
		(polygon
			(pts
				(arc
					(start 190.448692 -84.156296)
					(mid 190.448692 -83.617308)
					(end 189.909704 -83.617308)
				)
				(arc
					(start 189.286134 -84.241132)
					(mid 189.279055 -84.782246)
					(end 189.820296 -84.784692)
				)
			)
		)
		(polygon
			(pts
				(arc
					(start 194.944492 -83.927696)
					(mid 194.944492 -83.388708)
					(end 194.405504 -83.388708)
				)
				(arc
					(start 193.781934 -84.012532)
					(mid 193.774855 -84.553646)
					(end 194.316096 -84.556092)
				)
			)
		)
		(polygon
			(pts
				(arc
					(start 78.505558 -83.335368)
					(mid 78.122018 -82.951828)
					(end 77.738478 -83.335368)
				)
				(arc
					(start 77.738478 -84.224622)
					(mid 78.122145 -84.607908)
					(end 78.505558 -84.224368)
				)
			)
		)
		(polygon
			(pts
				(arc
					(start 83.741768 -81.705196)
					(mid 83.358228 -81.321656)
					(end 82.974688 -81.705196)
				)
				(arc
					(start 82.974688 -82.59445)
					(mid 83.358355 -82.977736)
					(end 83.741768 -82.594196)
				)
			)
		)
		(polygon
			(pts
				(arc
					(start 201.781918 -80.7466)
					(mid 201.767039 -80.710679)
					(end 201.731118 -80.6958)
				)
				(arc
					(start 201.527918 -80.6958)
					(mid 201.491997 -80.710679)
					(end 201.477118 -80.7466)
				)
				(arc
					(start 201.477118 -81.5594)
					(mid 201.491997 -81.595321)
					(end 201.527918 -81.6102)
				)
				(arc
					(start 201.731118 -81.6102)
					(mid 201.767039 -81.595321)
					(end 201.781918 -81.5594)
				)
			)
		)
		(polygon
			(pts
				(arc
					(start 201.223118 -80.7466)
					(mid 201.208239 -80.710679)
					(end 201.172318 -80.6958)
				)
				(arc
					(start 200.969118 -80.6958)
					(mid 200.933197 -80.710679)
					(end 200.918318 -80.7466)
				)
				(arc
					(start 200.918318 -81.5594)
					(mid 200.933197 -81.595321)
					(end 200.969118 -81.6102)
				)
				(arc
					(start 201.172318 -81.6102)
					(mid 201.208239 -81.595321)
					(end 201.223118 -81.5594)
				)
			)
		)
		(polygon
			(pts
				(arc
					(start 200.511918 -80.7466)
					(mid 200.497039 -80.710679)
					(end 200.461118 -80.6958)
				)
				(arc
					(start 200.257918 -80.6958)
					(mid 200.221997 -80.710679)
					(end 200.207118 -80.7466)
				)
				(arc
					(start 200.207118 -81.5594)
					(mid 200.221997 -81.595321)
					(end 200.257918 -81.6102)
				)
				(arc
					(start 200.461118 -81.6102)
					(mid 200.497039 -81.595321)
					(end 200.511918 -81.5594)
				)
			)
		)
		(polygon
			(pts
				(arc
					(start 199.953118 -80.7466)
					(mid 199.938239 -80.710679)
					(end 199.902318 -80.6958)
				)
				(arc
					(start 199.699118 -80.6958)
					(mid 199.663197 -80.710679)
					(end 199.648318 -80.7466)
				)
				(arc
					(start 199.648318 -81.5594)
					(mid 199.663197 -81.595321)
					(end 199.699118 -81.6102)
				)
				(arc
					(start 199.902318 -81.6102)
					(mid 199.938239 -81.595321)
					(end 199.953118 -81.5594)
				)
			)
		)
		(polygon
			(pts
				(arc
					(start 199.241918 -80.7466)
					(mid 199.227039 -80.710679)
					(end 199.191118 -80.6958)
				)
				(arc
					(start 198.987918 -80.6958)
					(mid 198.951997 -80.710679)
					(end 198.937118 -80.7466)
				)
				(arc
					(start 198.937118 -81.5594)
					(mid 198.951997 -81.595321)
					(end 198.987918 -81.6102)
				)
				(arc
					(start 199.191118 -81.6102)
					(mid 199.227039 -81.595321)
					(end 199.241918 -81.5594)
				)
			)
		)
		(polygon
			(pts
				(arc
					(start 198.683118 -80.7466)
					(mid 198.668239 -80.710679)
					(end 198.632318 -80.6958)
				)
				(arc
					(start 198.429118 -80.6958)
					(mid 198.393197 -80.710679)
					(end 198.378318 -80.7466)
				)
				(arc
					(start 198.378318 -81.5594)
					(mid 198.393197 -81.595321)
					(end 198.429118 -81.6102)
				)
				(arc
					(start 198.632318 -81.6102)
					(mid 198.668239 -81.595321)
					(end 198.683118 -81.5594)
				)
			)
		)
		(polygon
			(pts
				(arc
					(start 197.971918 -80.7466)
					(mid 197.957039 -80.710679)
					(end 197.921118 -80.6958)
				)
				(arc
					(start 197.717918 -80.6958)
					(mid 197.681997 -80.710679)
					(end 197.667118 -80.7466)
				)
				(arc
					(start 197.667118 -81.5594)
					(mid 197.681997 -81.595321)
					(end 197.717918 -81.6102)
				)
				(arc
					(start 197.921118 -81.6102)
					(mid 197.957039 -81.595321)
					(end 197.971918 -81.5594)
				)
			)
		)
		(polygon
			(pts
				(arc
					(start 197.413118 -80.7466)
					(mid 197.398239 -80.710679)
					(end 197.362318 -80.6958)
				)
				(arc
					(start 197.159118 -80.6958)
					(mid 197.123197 -80.710679)
					(end 197.108318 -80.7466)
				)
				(arc
					(start 197.108318 -81.5594)
					(mid 197.123197 -81.595321)
					(end 197.159118 -81.6102)
				)
				(arc
					(start 197.362318 -81.6102)
					(mid 197.398239 -81.595321)
					(end 197.413118 -81.5594)
				)
			)
		)
		(polygon
			(pts
				(arc
					(start 193.653918 -80.7466)
					(mid 193.639039 -80.710679)
					(end 193.603118 -80.6958)
				)
				(arc
					(start 193.399918 -80.6958)
					(mid 193.363997 -80.710679)
					(end 193.349118 -80.7466)
				)
				(arc
					(start 193.349118 -81.5594)
					(mid 193.363997 -81.595321)
					(end 193.399918 -81.6102)
				)
				(arc
					(start 193.603118 -81.6102)
					(mid 193.639039 -81.595321)
					(end 193.653918 -81.5594)
				)
			)
		)
		(polygon
			(pts
				(arc
					(start 193.095118 -80.7466)
					(mid 193.080239 -80.710679)
					(end 193.044318 -80.6958)
				)
				(arc
					(start 192.841118 -80.6958)
					(mid 192.805197 -80.710679)
					(end 192.790318 -80.7466)
				)
				(arc
					(start 192.790318 -81.5594)
					(mid 192.805197 -81.595321)
					(end 192.841118 -81.6102)
				)
				(arc
					(start 193.044318 -81.6102)
					(mid 193.080239 -81.595321)
					(end 193.095118 -81.5594)
				)
			)
		)
		(polygon
			(pts
				(arc
					(start 192.383918 -80.7466)
					(mid 192.369039 -80.710679)
					(end 192.333118 -80.6958)
				)
				(arc
					(start 192.129918 -80.6958)
					(mid 192.093997 -80.710679)
					(end 192.079118 -80.7466)
				)
				(arc
					(start 192.079118 -81.5594)
					(mid 192.093997 -81.595321)
					(end 192.129918 -81.6102)
				)
				(arc
					(start 192.333118 -81.6102)
					(mid 192.369039 -81.595321)
					(end 192.383918 -81.5594)
				)
			)
		)
		(polygon
			(pts
				(arc
					(start 191.825118 -80.7466)
					(mid 191.810239 -80.710679)
					(end 191.774318 -80.6958)
				)
				(arc
					(start 191.571118 -80.6958)
					(mid 191.535197 -80.710679)
					(end 191.520318 -80.7466)
				)
				(arc
					(start 191.520318 -81.5594)
					(mid 191.535197 -81.595321)
					(end 191.571118 -81.6102)
				)
				(arc
					(start 191.774318 -81.6102)
					(mid 191.810239 -81.595321)
					(end 191.825118 -81.5594)
				)
			)
		)
		(polygon
			(pts
				(arc
					(start 190.351918 -80.7466)
					(mid 190.337039 -80.710679)
					(end 190.301118 -80.6958)
				)
				(arc
					(start 190.097918 -80.6958)
					(mid 190.061997 -80.710679)
					(end 190.047118 -80.7466)
				)
				(arc
					(start 190.047118 -81.5594)
					(mid 190.061997 -81.595321)
					(end 190.097918 -81.6102)
				)
				(arc
					(start 190.301118 -81.6102)
					(mid 190.337039 -81.595321)
					(end 190.351918 -81.5594)
				)
			)
		)
		(polygon
			(pts
				(arc
					(start 189.793118 -80.7466)
					(mid 189.778239 -80.710679)
					(end 189.742318 -80.6958)
				)
				(arc
					(start 189.539118 -80.6958)
					(mid 189.503197 -80.710679)
					(end 189.488318 -80.7466)
				)
				(arc
					(start 189.488318 -81.5594)
					(mid 189.503197 -81.595321)
					(end 189.539118 -81.6102)
				)
				(arc
					(start 189.742318 -81.6102)
					(mid 189.778239 -81.595321)
					(end 189.793118 -81.5594)
				)
			)
		)
		(polygon
			(pts
				(arc
					(start 188.700918 -80.7466)
					(mid 188.686039 -80.710679)
					(end 188.650118 -80.6958)
				)
				(arc
					(start 188.446918 -80.6958)
					(mid 188.410997 -80.710679)
					(end 188.396118 -80.7466)
				)
				(arc
					(start 188.396118 -81.5594)
					(mid 188.410997 -81.595321)
					(end 188.446918 -81.6102)
				)
				(arc
					(start 188.650118 -81.6102)
					(mid 188.686039 -81.595321)
					(end 188.700918 -81.5594)
				)
			)
		)
		(polygon
			(pts
				(arc
					(start 188.142118 -80.7466)
					(mid 188.127239 -80.710679)
					(end 188.091318 -80.6958)
				)
				(arc
					(start 187.888118 -80.6958)
					(mid 187.852197 -80.710679)
					(end 187.837318 -80.7466)
				)
				(arc
					(start 187.837318 -81.5594)
					(mid 187.852197 -81.595321)
					(end 187.888118 -81.6102)
				)
				(arc
					(start 188.091318 -81.6102)
					(mid 188.127239 -81.595321)
					(end 188.142118 -81.5594)
				)
			)
		)
		(polygon
			(pts
				(arc
					(start 216.573354 -79.113126)
					(mid 216.573354 -78.574646)
					(end 216.034874 -78.574646)
				)
				(xy 216.03462 -78.574392) (xy 215.226392 -79.38262)
				(arc
					(start 215.226646 -79.382874)
					(mid 215.226646 -79.921354)
					(end 215.765126 -79.921354)
				)
				(xy 215.76538 -79.921608) (xy 216.573354 -79.11338)
			)
		)
		(polygon
			(pts
				(arc
					(start 85.367368 -78.504796)
					(mid 84.983828 -78.121256)
					(end 84.600288 -78.504796)
				)
				(arc
					(start 84.600288 -79.39405)
					(mid 84.983955 -79.777336)
					(end 85.367368 -79.393796)
				)
			)
		)
		(polygon
			(pts
				(arc
					(start 78.505558 -76.909168)
					(mid 78.122018 -76.525628)
					(end 77.738478 -76.909168)
				)
				(arc
					(start 77.738478 -77.798422)
					(mid 78.122145 -78.181708)
					(end 78.505558 -77.798168)
				)
			)
		)
		(polygon
			(pts
				(arc
					(start 202.399646 -75.883262)
					(mid 202.783186 -75.499722)
					(end 202.399646 -75.116182)
				)
				(arc
					(start 201.599546 -75.116182)
					(mid 201.21626 -75.499849)
					(end 201.5998 -75.883262)
				)
			)
		)
		(polygon
			(pts
				(arc
					(start 83.741768 -75.305158)
					(mid 83.358228 -74.921618)
					(end 82.974688 -75.305158)
				)
				(arc
					(start 82.974688 -76.194412)
					(mid 83.358355 -76.577698)
					(end 83.741768 -76.194158)
				)
			)
		)
		(polygon
			(pts
				(arc
					(start 217.716354 -75.176126)
					(mid 217.716354 -74.637646)
					(end 217.177874 -74.637646)
				)
				(xy 217.17762 -74.637392) (xy 216.369392 -75.44562)
				(arc
					(start 216.369646 -75.445874)
					(mid 216.369646 -75.984354)
					(end 216.908126 -75.984354)
				)
				(xy 216.90838 -75.984608) (xy 217.716354 -75.17638)
			)
		)
		(polygon
			(pts
				(arc
					(start 200.357994 -73.899268)
					(mid 199.999219 -73.54189)
					(end 199.641714 -73.900538)
				)
				(xy 199.643492 -74.691494) (xy 199.643492 -74.692256)
				(arc
					(start 199.643492 -74.695558)
					(mid 200.002394 -75.052936)
					(end 200.359772 -74.694034)
				)
				(xy 200.357994 -73.900538)
			)
		)
		(polygon
			(pts
				(arc
					(start 199.557894 -73.899268)
					(mid 199.199119 -73.54189)
					(end 198.841614 -73.900538)
				)
				(arc
					(start 198.843392 -74.693018)
					(mid 199.202294 -75.050396)
					(end 199.559672 -74.691494)
				)
				(xy 199.557894 -73.900538) (xy 199.557894 -73.899776)
			)
		)
		(polygon
			(pts
				(arc
					(start 195.557902 -73.900538)
					(mid 195.200397 -73.54189)
					(end 194.841622 -73.899268)
				)
				(xy 194.841622 -73.899776) (xy 194.841622 -73.903332) (xy 194.840352 -74.70521)
				(arc
					(start 194.840352 -74.706988)
					(mid 195.197984 -75.065636)
					(end 195.556632 -74.708004)
				)
				(xy 195.556632 -74.706988)
			)
		)
		(polygon
			(pts
				(arc
					(start 194.757802 -73.903332)
					(mid 194.403091 -73.541891)
					(end 194.041522 -73.896474)
				)
				(arc
					(start 194.03441 -74.698606)
					(mid 194.389248 -75.060048)
					(end 194.75069 -74.70521)
				)
			)
		)
		(polygon
			(pts
				(arc
					(start 197.157848 -73.89622)
					(mid 196.796025 -73.541889)
					(end 196.441568 -73.903586)
				)
				(arc
					(start 196.44995 -74.702162)
					(mid 196.8119 -75.056492)
					(end 197.16623 -74.694542)
				)
			)
		)
		(polygon
			(pts
				(arc
					(start 197.957948 -73.895712)
					(mid 197.595617 -73.541888)
					(end 197.241668 -73.904094)
				)
				(arc
					(start 197.251066 -74.70394)
					(mid 197.613524 -75.057762)
					(end 197.967346 -74.695304)
				)
			)
		)
		(polygon
			(pts
				(arc
					(start 192.35801 -73.899522)
					(mid 191.999743 -73.541636)
					(end 191.64173 -73.899776)
				)
				(arc
					(start 191.64173 -74.699622)
					(mid 191.99987 -75.057762)
					(end 192.35801 -74.699622)
				)
			)
		)
		(polygon
			(pts
				(arc
					(start 193.157856 -73.90003)
					(mid 192.799716 -73.541636)
					(end 192.441576 -73.90003)
				)
				(xy 192.44183 -74.699622)
				(arc
					(start 192.44183 -74.699876)
					(mid 192.800097 -75.058016)
					(end 193.15811 -74.699622)
				)
			)
		)
		(polygon
			(pts
				(arc
					(start 201.598276 -74.287126)
					(mid 201.981816 -73.903586)
					(end 201.598276 -73.520046)
				)
				(arc
					(start 200.798176 -73.520046)
					(mid 200.41489 -73.903713)
					(end 200.79843 -74.287126)
				)
			)
		)
		(polygon
			(pts
				(arc
					(start 77.667358 -73.708768)
					(mid 77.283818 -73.325228)
					(end 76.900278 -73.708768)
				)
				(arc
					(start 76.900278 -74.598022)
					(mid 77.283945 -74.981308)
					(end 77.667358 -74.597768)
				)
			)
		)
		(polygon
			(pts
				(arc
					(start 216.192354 -73.652126)
					(mid 216.192354 -73.113646)
					(end 215.653874 -73.113646)
				)
				(xy 215.65362 -73.113392) (xy 214.845392 -73.92162)
				(arc
					(start 214.845646 -73.921874)
					(mid 214.845646 -74.460354)
					(end 215.384126 -74.460354)
				)
				(xy 215.38438 -74.460608) (xy 216.192354 -73.65238)
			)
		)
		(polygon
			(pts
				(arc
					(start 202.39863 -73.480676)
					(mid 202.780646 -73.095612)
					(end 202.395582 -72.713596)
				)
				(arc
					(start 201.599292 -72.716898)
					(mid 201.217276 -73.101835)
					(end 201.602086 -73.483978)
				)
			)
		)
		(polygon
			(pts
				(arc
					(start 85.367368 -72.080882)
					(mid 84.983701 -71.697596)
					(end 84.600288 -72.081136)
				)
				(arc
					(start 84.600288 -72.970136)
					(mid 84.983828 -73.353676)
					(end 85.367368 -72.970136)
				)
			)
		)
		(polygon
			(pts
				(arc
					(start 214.795354 -72.255126)
					(mid 214.795354 -71.716646)
					(end 214.256874 -71.716646)
				)
				(xy 214.25662 -71.716392) (xy 213.448392 -72.52462)
				(arc
					(start 213.448646 -72.524874)
					(mid 213.448646 -73.063354)
					(end 213.987126 -73.063354)
				)
				(xy 213.98738 -73.063608) (xy 214.795354 -72.25538)
			)
		)
		(polygon
			(pts
				(arc
					(start 201.978006 -71.50354)
					(mid 201.594974 -71.119492)
					(end 201.210926 -71.502524)
				)
				(arc
					(start 201.20991 -72.297036)
					(mid 201.592815 -72.681338)
					(end 201.97699 -72.298306)
				)
				(xy 201.97699 -72.297544) (xy 201.97699 -72.297036)
			)
		)
		(polygon
			(pts
				(arc
					(start 201.594466 -70.319138)
					(mid 201.210164 -70.701789)
					(end 201.592688 -71.086218)
				)
				(arc
					(start 202.40371 -71.087996)
					(mid 202.788012 -70.705218)
					(end 202.405234 -70.320916)
				)
			)
		)
		(polygon
			(pts
				(arc
					(start 78.505558 -70.508368)
					(mid 78.122018 -70.124828)
					(end 77.738478 -70.508368)
				)
				(arc
					(start 77.738478 -71.397622)
					(mid 78.122145 -71.780908)
					(end 78.505558 -71.397368)
				)
			)
		)
		(polygon
			(pts
				(arc
					(start 201.978768 -69.097398)
					(mid 201.58837 -68.720716)
					(end 201.211688 -69.111114)
				)
				(arc
					(start 201.225658 -69.906388)
					(mid 201.615929 -70.283322)
					(end 201.992738 -69.892926)
				)
			)
		)
		(polygon
			(pts
				(arc
					(start 215.303354 -68.953126)
					(mid 215.303354 -68.414646)
					(end 214.764874 -68.414646)
				)
				(xy 214.76462 -68.414392) (xy 213.956392 -69.22262)
				(arc
					(start 213.956646 -69.222874)
					(mid 213.956646 -69.761354)
					(end 214.495126 -69.761354)
				)
				(xy 214.49538 -69.761608) (xy 215.303354 -68.95338)
			)
		)
		(polygon
			(pts
				(arc
					(start 201.599546 -67.911726)
					(mid 201.212197 -68.291329)
					(end 201.591672 -68.678806)
				)
				(arc
					(start 202.39609 -68.68668)
					(mid 202.78344 -68.30695)
					(end 202.40371 -67.9196)
				)
			)
		)
		(polygon
			(pts
				(arc
					(start 77.658214 -67.322192)
					(mid 77.274674 -66.938652)
					(end 76.891134 -67.322192)
				)
				(arc
					(start 76.891134 -68.211446)
					(mid 77.274801 -68.594732)
					(end 77.658214 -68.211192)
				)
			)
		)
		(polygon
			(pts
				(arc
					(start 213.779354 -67.479926)
					(mid 213.779354 -66.941446)
					(end 213.240874 -66.941446)
				)
				(xy 213.24062 -66.941192) (xy 212.432392 -67.74942)
				(arc
					(start 212.432646 -67.749674)
					(mid 212.432646 -68.288154)
					(end 212.971126 -68.288154)
				)
				(xy 212.97138 -68.288408) (xy 213.779354 -67.48018)
			)
		)
		(polygon
			(pts
				(arc
					(start 201.983086 -66.712084)
					(mid 201.602594 -66.325496)
					(end 201.216006 -66.705988)
				)
				(arc
					(start 201.209656 -67.49923)
					(mid 201.590021 -67.886073)
					(end 201.976736 -67.50558)
				)
			)
		)
		(polygon
			(pts
				(arc
					(start 212.306154 -65.828926)
					(mid 212.306154 -65.290446)
					(end 211.767674 -65.290446)
				)
				(xy 211.76742 -65.290192) (xy 210.959192 -66.09842)
				(arc
					(start 210.959446 -66.098674)
					(mid 210.959446 -66.637154)
					(end 211.497926 -66.637154)
				)
				(xy 211.49818 -66.637408) (xy 212.306154 -65.82918)
			)
		)
		(polygon
			(pts
				(arc
					(start 212.137498 -63.3857)
					(mid 212.137498 -62.84722)
					(end 211.599018 -62.84722)
				)
				(xy 211.598764 -62.846966) (xy 210.790536 -63.655194)
				(arc
					(start 210.79079 -63.655448)
					(mid 210.79079 -64.193928)
					(end 211.32927 -64.193928)
				)
				(xy 211.329524 -64.194182) (xy 212.137498 -63.385954)
			)
		)
		(polygon
			(pts
				(arc
					(start 170.12539 -38.035738)
					(mid 170.110511 -37.999817)
					(end 170.07459 -37.984938)
				)
				(arc
					(start 169.87139 -37.984938)
					(mid 169.835469 -37.999817)
					(end 169.82059 -38.035738)
				)
				(arc
					(start 169.82059 -38.848538)
					(mid 169.835469 -38.884459)
					(end 169.87139 -38.899338)
				)
				(arc
					(start 170.07459 -38.899338)
					(mid 170.110511 -38.884459)
					(end 170.12539 -38.848538)
				)
			)
		)
		(polygon
			(pts
				(arc
					(start 169.49039 -38.035738)
					(mid 169.475511 -37.999817)
					(end 169.43959 -37.984938)
				)
				(arc
					(start 169.23639 -37.984938)
					(mid 169.200469 -37.999817)
					(end 169.18559 -38.035738)
				)
				(arc
					(start 169.18559 -38.848538)
					(mid 169.200469 -38.884459)
					(end 169.23639 -38.899338)
				)
				(arc
					(start 169.43959 -38.899338)
					(mid 169.475511 -38.884459)
					(end 169.49039 -38.848538)
				)
			)
		)
		(polygon
			(pts
				(arc
					(start 168.753536 -38.035738)
					(mid 168.738657 -37.999817)
					(end 168.702736 -37.984938)
				)
				(arc
					(start 168.499536 -37.984938)
					(mid 168.463615 -37.999817)
					(end 168.448736 -38.035738)
				)
				(arc
					(start 168.448736 -38.848538)
					(mid 168.463615 -38.884459)
					(end 168.499536 -38.899338)
				)
				(arc
					(start 168.702736 -38.899338)
					(mid 168.738657 -38.884459)
					(end 168.753536 -38.848538)
				)
			)
		)
		(polygon
			(pts
				(arc
					(start 168.118536 -38.035738)
					(mid 168.103657 -37.999817)
					(end 168.067736 -37.984938)
				)
				(arc
					(start 167.864536 -37.984938)
					(mid 167.828615 -37.999817)
					(end 167.813736 -38.035738)
				)
				(arc
					(start 167.813736 -38.848538)
					(mid 167.828615 -38.884459)
					(end 167.864536 -38.899338)
				)
				(arc
					(start 168.067736 -38.899338)
					(mid 168.103657 -38.884459)
					(end 168.118536 -38.848538)
				)
			)
		)
		(polygon
			(pts
				(arc
					(start 167.43299 -38.010338)
					(mid 167.418111 -37.974417)
					(end 167.38219 -37.959538)
				)
				(arc
					(start 167.17899 -37.959538)
					(mid 167.143069 -37.974417)
					(end 167.12819 -38.010338)
				)
				(arc
					(start 167.12819 -38.823138)
					(mid 167.143069 -38.859059)
					(end 167.17899 -38.873938)
				)
				(arc
					(start 167.38219 -38.873938)
					(mid 167.418111 -38.859059)
					(end 167.43299 -38.823138)
				)
			)
		)
		(polygon
			(pts
				(arc
					(start 166.79799 -38.010338)
					(mid 166.783111 -37.974417)
					(end 166.74719 -37.959538)
				)
				(arc
					(start 166.54399 -37.959538)
					(mid 166.508069 -37.974417)
					(end 166.49319 -38.010338)
				)
				(arc
					(start 166.49319 -38.823138)
					(mid 166.508069 -38.859059)
					(end 166.54399 -38.873938)
				)
				(arc
					(start 166.74719 -38.873938)
					(mid 166.783111 -38.859059)
					(end 166.79799 -38.823138)
				)
			)
		)
		(polygon
			(pts
				(arc
					(start 166.111936 -38.010338)
					(mid 166.097057 -37.974417)
					(end 166.061136 -37.959538)
				)
				(arc
					(start 165.857936 -37.959538)
					(mid 165.822015 -37.974417)
					(end 165.807136 -38.010338)
				)
				(arc
					(start 165.807136 -38.823138)
					(mid 165.822015 -38.859059)
					(end 165.857936 -38.873938)
				)
				(arc
					(start 166.061136 -38.873938)
					(mid 166.097057 -38.859059)
					(end 166.111936 -38.823138)
				)
			)
		)
		(polygon
			(pts
				(arc
					(start 165.476936 -38.010338)
					(mid 165.462057 -37.974417)
					(end 165.426136 -37.959538)
				)
				(arc
					(start 165.222936 -37.959538)
					(mid 165.187015 -37.974417)
					(end 165.172136 -38.010338)
				)
				(arc
					(start 165.172136 -38.823138)
					(mid 165.187015 -38.859059)
					(end 165.222936 -38.873938)
				)
				(arc
					(start 165.426136 -38.873938)
					(mid 165.462057 -38.859059)
					(end 165.476936 -38.823138)
				)
			)
		)
		(polygon
			(pts
				(arc
					(start 139.984988 -36.799774)
					(mid 139.499721 -36.314888)
					(end 139.014708 -36.800028)
				)
				(arc
					(start 139.014708 -38.200076)
					(mid 139.499848 -38.685216)
					(end 139.984988 -38.200076)
				)
			)
		)
		(polygon
			(pts
				(arc
					(start 136.385046 -36.799774)
					(mid 135.899779 -36.314888)
					(end 135.414766 -36.800028)
				)
				(arc
					(start 135.414766 -38.200076)
					(mid 135.899906 -38.685216)
					(end 136.385046 -38.200076)
				)
			)
		)
		(polygon
			(pts
				(arc
					(start 132.785104 -36.799774)
					(mid 132.299837 -36.314888)
					(end 131.814824 -36.800028)
				)
				(arc
					(start 131.814824 -38.200076)
					(mid 132.299964 -38.685216)
					(end 132.785104 -38.200076)
				)
			)
		)
		(polygon
			(pts
				(arc
					(start 129.185162 -36.799774)
					(mid 128.699895 -36.314888)
					(end 128.214882 -36.800028)
				)
				(arc
					(start 128.214882 -38.200076)
					(mid 128.700022 -38.685216)
					(end 129.185162 -38.200076)
				)
			)
		)
		(polygon
			(pts
				(arc
					(start 118.385082 -36.799774)
					(mid 117.899815 -36.314888)
					(end 117.414802 -36.800028)
				)
				(arc
					(start 117.414802 -38.200076)
					(mid 117.899942 -38.685216)
					(end 118.385082 -38.200076)
				)
			)
		)
		(polygon
			(pts
				(arc
					(start 114.78514 -36.799774)
					(mid 114.299873 -36.314888)
					(end 113.81486 -36.800028)
				)
				(arc
					(start 113.81486 -38.200076)
					(mid 114.3 -38.685216)
					(end 114.78514 -38.200076)
				)
			)
		)
		(polygon
			(pts
				(arc
					(start 111.185198 -36.799774)
					(mid 110.699931 -36.314888)
					(end 110.214918 -36.800028)
				)
				(arc
					(start 110.214918 -38.200076)
					(mid 110.700058 -38.685216)
					(end 111.185198 -38.200076)
				)
			)
		)
		(polygon
			(pts
				(arc
					(start 107.585002 -36.799774)
					(mid 107.099735 -36.314888)
					(end 106.614722 -36.800028)
				)
				(arc
					(start 106.614722 -38.200076)
					(mid 107.099862 -38.685216)
					(end 107.585002 -38.200076)
				)
			)
		)
		(polygon
			(pts
				(arc
					(start 141.785086 -35.599878)
					(mid 141.299819 -35.114992)
					(end 140.814806 -35.600132)
				)
				(arc
					(start 140.814806 -37.00018)
					(mid 141.299946 -37.48532)
					(end 141.785086 -37.00018)
				)
			)
		)
		(polygon
			(pts
				(arc
					(start 138.185144 -35.599878)
					(mid 137.699877 -35.114992)
					(end 137.214864 -35.600132)
				)
				(arc
					(start 137.214864 -37.00018)
					(mid 137.700004 -37.48532)
					(end 138.185144 -37.00018)
				)
			)
		)
		(polygon
			(pts
				(arc
					(start 134.585202 -35.599878)
					(mid 134.099935 -35.114992)
					(end 133.614922 -35.600132)
				)
				(arc
					(start 133.614922 -37.00018)
					(mid 134.100062 -37.48532)
					(end 134.585202 -37.00018)
				)
			)
		)
		(polygon
			(pts
				(arc
					(start 130.985006 -35.599878)
					(mid 130.499739 -35.114992)
					(end 130.014726 -35.600132)
				)
				(arc
					(start 130.014726 -37.00018)
					(mid 130.499866 -37.48532)
					(end 130.985006 -37.00018)
				)
			)
		)
		(polygon
			(pts
				(arc
					(start 120.18518 -35.599878)
					(mid 119.699913 -35.114992)
					(end 119.2149 -35.600132)
				)
				(arc
					(start 119.2149 -37.00018)
					(mid 119.70004 -37.48532)
					(end 120.18518 -37.00018)
				)
			)
		)
		(polygon
			(pts
				(arc
					(start 116.584984 -35.599878)
					(mid 116.099717 -35.114992)
					(end 115.614704 -35.600132)
				)
				(arc
					(start 115.614704 -37.00018)
					(mid 116.099844 -37.48532)
					(end 116.584984 -37.00018)
				)
			)
		)
		(polygon
			(pts
				(arc
					(start 112.985042 -35.599878)
					(mid 112.499775 -35.114992)
					(end 112.014762 -35.600132)
				)
				(arc
					(start 112.014762 -37.00018)
					(mid 112.499902 -37.48532)
					(end 112.985042 -37.00018)
				)
			)
		)
		(polygon
			(pts
				(arc
					(start 109.3851 -35.599878)
					(mid 108.899833 -35.114992)
					(end 108.41482 -35.600132)
				)
				(arc
					(start 108.41482 -37.00018)
					(mid 108.89996 -37.48532)
					(end 109.3851 -37.00018)
				)
			)
		)
		(polygon
			(pts
				(arc
					(start 139.984988 -33.199832)
					(mid 139.499721 -32.714946)
					(end 139.014708 -33.200086)
				)
				(arc
					(start 139.014708 -34.600134)
					(mid 139.499848 -35.085274)
					(end 139.984988 -34.600134)
				)
			)
		)
		(polygon
			(pts
				(arc
					(start 136.385046 -33.199832)
					(mid 135.899779 -32.714946)
					(end 135.414766 -33.200086)
				)
				(arc
					(start 135.414766 -34.600134)
					(mid 135.899906 -35.085274)
					(end 136.385046 -34.600134)
				)
			)
		)
		(polygon
			(pts
				(arc
					(start 132.785104 -33.199832)
					(mid 132.299837 -32.714946)
					(end 131.814824 -33.200086)
				)
				(arc
					(start 131.814824 -34.600134)
					(mid 132.299964 -35.085274)
					(end 132.785104 -34.600134)
				)
			)
		)
		(polygon
			(pts
				(arc
					(start 129.185162 -33.199832)
					(mid 128.699895 -32.714946)
					(end 128.214882 -33.200086)
				)
				(arc
					(start 128.214882 -34.600134)
					(mid 128.700022 -35.085274)
					(end 129.185162 -34.600134)
				)
			)
		)
		(polygon
			(pts
				(arc
					(start 118.385082 -33.199832)
					(mid 117.899815 -32.714946)
					(end 117.414802 -33.200086)
				)
				(arc
					(start 117.414802 -34.600134)
					(mid 117.899942 -35.085274)
					(end 118.385082 -34.600134)
				)
			)
		)
		(polygon
			(pts
				(arc
					(start 114.78514 -33.199832)
					(mid 114.299873 -32.714946)
					(end 113.81486 -33.200086)
				)
				(arc
					(start 113.81486 -34.600134)
					(mid 114.3 -35.085274)
					(end 114.78514 -34.600134)
				)
			)
		)
		(polygon
			(pts
				(arc
					(start 111.185198 -33.199832)
					(mid 110.699931 -32.714946)
					(end 110.214918 -33.200086)
				)
				(arc
					(start 110.214918 -34.600134)
					(mid 110.700058 -35.085274)
					(end 111.185198 -34.600134)
				)
			)
		)
		(polygon
			(pts
				(arc
					(start 107.585002 -33.199832)
					(mid 107.099735 -32.714946)
					(end 106.614722 -33.200086)
				)
				(arc
					(start 106.614722 -34.600134)
					(mid 107.099862 -35.085274)
					(end 107.585002 -34.600134)
				)
			)
		)
		(polygon
			(pts
				(arc
					(start 141.785086 -31.999936)
					(mid 141.299819 -31.51505)
					(end 140.814806 -32.00019)
				)
				(arc
					(start 140.814806 -33.399984)
					(mid 141.299946 -33.885124)
					(end 141.785086 -33.399984)
				)
			)
		)
		(polygon
			(pts
				(arc
					(start 138.185144 -31.999936)
					(mid 137.699877 -31.51505)
					(end 137.214864 -32.00019)
				)
				(arc
					(start 137.214864 -33.399984)
					(mid 137.700004 -33.885124)
					(end 138.185144 -33.399984)
				)
			)
		)
		(polygon
			(pts
				(arc
					(start 134.585202 -31.999936)
					(mid 134.099935 -31.51505)
					(end 133.614922 -32.00019)
				)
				(arc
					(start 133.614922 -33.399984)
					(mid 134.100062 -33.885124)
					(end 134.585202 -33.399984)
				)
			)
		)
		(polygon
			(pts
				(arc
					(start 130.985006 -31.999936)
					(mid 130.499739 -31.51505)
					(end 130.014726 -32.00019)
				)
				(arc
					(start 130.014726 -33.399984)
					(mid 130.499866 -33.885124)
					(end 130.985006 -33.399984)
				)
			)
		)
		(polygon
			(pts
				(arc
					(start 120.18518 -31.999936)
					(mid 119.699913 -31.51505)
					(end 119.2149 -32.00019)
				)
				(arc
					(start 119.2149 -33.399984)
					(mid 119.70004 -33.885124)
					(end 120.18518 -33.399984)
				)
			)
		)
		(polygon
			(pts
				(arc
					(start 116.584984 -31.999936)
					(mid 116.099717 -31.51505)
					(end 115.614704 -32.00019)
				)
				(arc
					(start 115.614704 -33.399984)
					(mid 116.099844 -33.885124)
					(end 116.584984 -33.399984)
				)
			)
		)
		(polygon
			(pts
				(arc
					(start 112.985042 -31.999936)
					(mid 112.499775 -31.51505)
					(end 112.014762 -32.00019)
				)
				(arc
					(start 112.014762 -33.399984)
					(mid 112.499902 -33.885124)
					(end 112.985042 -33.399984)
				)
			)
		)
		(polygon
			(pts
				(arc
					(start 109.3851 -31.999936)
					(mid 108.899833 -31.51505)
					(end 108.41482 -32.00019)
				)
				(arc
					(start 108.41482 -33.399984)
					(mid 108.89996 -33.885124)
					(end 109.3851 -33.399984)
				)
			)
		)
		(polygon
			(pts
				(arc
					(start 182.663592 -29.328618)
					(mid 182.47589 -28.684976)
					(end 181.83352 -28.877006)
				)
				(arc
					(start 181.083458 -30.277054)
					(mid 181.277006 -30.916626)
					(end 181.916578 -30.723078)
				)
			)
		)
		(polygon
			(pts
				(arc
					(start 180.413406 -29.328618)
					(mid 180.225704 -28.684976)
					(end 179.583334 -28.877006)
				)
				(arc
					(start 178.833526 -30.277054)
					(mid 179.027074 -30.916626)
					(end 179.666646 -30.723078)
				)
			)
		)
		(polygon
			(pts
				(arc
					(start 162.663632 -29.328618)
					(mid 162.47593 -28.684976)
					(end 161.83356 -28.877006)
				)
				(arc
					(start 161.083498 -30.277054)
					(mid 161.277046 -30.916626)
					(end 161.916618 -30.723078)
				)
			)
		)
		(polygon
			(pts
				(arc
					(start 160.413446 -29.328618)
					(mid 160.225744 -28.684976)
					(end 159.583374 -28.877006)
				)
				(arc
					(start 158.833566 -30.277054)
					(mid 159.027114 -30.916626)
					(end 159.666686 -30.723078)
				)
			)
		)
		(polygon
			(pts
				(arc
					(start 192.146936 -25.8064)
					(mid 192.132057 -25.770479)
					(end 192.096136 -25.7556)
				)
				(arc
					(start 191.283336 -25.7556)
					(mid 191.247415 -25.770479)
					(end 191.232536 -25.8064)
				)
				(arc
					(start 191.232536 -26.0096)
					(mid 191.247415 -26.045521)
					(end 191.283336 -26.0604)
				)
				(arc
					(start 192.096136 -26.0604)
					(mid 192.132057 -26.045521)
					(end 192.146936 -26.0096)
				)
			)
		)
		(polygon
			(pts
				(arc
					(start 192.146936 -25.1714)
					(mid 192.132057 -25.135479)
					(end 192.096136 -25.1206)
				)
				(arc
					(start 191.283336 -25.1206)
					(mid 191.247415 -25.135479)
					(end 191.232536 -25.1714)
				)
				(arc
					(start 191.232536 -25.3746)
					(mid 191.247415 -25.410521)
					(end 191.283336 -25.4254)
				)
				(arc
					(start 192.096136 -25.4254)
					(mid 192.132057 -25.410521)
					(end 192.146936 -25.3746)
				)
			)
		)
		(polygon
			(pts
				(arc
					(start 162.663632 -25.528524)
					(mid 162.47593 -24.884882)
					(end 161.83356 -25.076912)
				)
				(arc
					(start 161.083498 -26.47696)
					(mid 161.277046 -27.116532)
					(end 161.916618 -26.922984)
				)
			)
		)
		(polygon
			(pts
				(arc
					(start 160.413446 -25.528524)
					(mid 160.225744 -24.884882)
					(end 159.583374 -25.076912)
				)
				(arc
					(start 158.833566 -26.47696)
					(mid 159.027114 -27.116532)
					(end 159.666686 -26.922984)
				)
			)
		)
		(polygon
			(pts
				(arc
					(start 180.43398 -25.543764)
					(mid 180.239312 -24.863383)
					(end 179.560982 -25.064974)
				)
				(arc
					(start 178.811174 -26.465022)
					(mid 179.015136 -27.138884)
					(end 179.688998 -26.934922)
				)
			)
		)
		(polygon
			(pts
				(arc
					(start 182.684166 -25.543764)
					(mid 182.489596 -24.863437)
					(end 181.811168 -25.06472)
				)
				(arc
					(start 181.061106 -26.464768)
					(mid 181.264814 -27.138884)
					(end 181.93893 -26.935176)
				)
			)
		)
		(polygon
			(pts
				(arc
					(start 192.14719 -23.7744)
					(mid 192.132311 -23.738479)
					(end 192.09639 -23.7236)
				)
				(arc
					(start 191.28359 -23.7236)
					(mid 191.247669 -23.738479)
					(end 191.23279 -23.7744)
				)
				(arc
					(start 191.23279 -23.9776)
					(mid 191.247669 -24.013521)
					(end 191.28359 -24.0284)
				)
				(arc
					(start 192.09639 -24.0284)
					(mid 192.132311 -24.013521)
					(end 192.14719 -23.9776)
				)
			)
		)
		(polygon
			(pts
				(arc
					(start 192.14719 -23.1394)
					(mid 192.132311 -23.103479)
					(end 192.09639 -23.0886)
				)
				(arc
					(start 191.28359 -23.0886)
					(mid 191.247669 -23.103479)
					(end 191.23279 -23.1394)
				)
				(arc
					(start 191.23279 -23.3426)
					(mid 191.247669 -23.378521)
					(end 191.28359 -23.3934)
				)
				(arc
					(start 192.09639 -23.3934)
					(mid 192.132311 -23.378521)
					(end 192.14719 -23.3426)
				)
			)
		)
		(polygon
			(pts
				(arc
					(start 192.14719 -21.7424)
					(mid 192.132311 -21.706479)
					(end 192.09639 -21.6916)
				)
				(arc
					(start 191.28359 -21.6916)
					(mid 191.247669 -21.706479)
					(end 191.23279 -21.7424)
				)
				(arc
					(start 191.23279 -21.9456)
					(mid 191.247669 -21.981521)
					(end 191.28359 -21.9964)
				)
				(arc
					(start 192.09639 -21.9964)
					(mid 192.132311 -21.981521)
					(end 192.14719 -21.9456)
				)
			)
		)
		(polygon
			(pts
				(arc
					(start 192.14719 -21.1074)
					(mid 192.132311 -21.071479)
					(end 192.09639 -21.0566)
				)
				(arc
					(start 191.28359 -21.0566)
					(mid 191.247669 -21.071479)
					(end 191.23279 -21.1074)
				)
				(arc
					(start 191.23279 -21.3106)
					(mid 191.247669 -21.346521)
					(end 191.28359 -21.3614)
				)
				(arc
					(start 192.09639 -21.3614)
					(mid 192.132311 -21.346521)
					(end 192.14719 -21.3106)
				)
			)
		)
		(polygon
			(pts
				(arc
					(start 182.666386 -21.72335)
					(mid 182.473247 -21.083725)
					(end 181.833774 -21.277072)
				)
				(xy 181.831488 -21.275802) (xy 181.081426 -22.675596)
				(arc
					(start 181.083712 -22.676866)
					(mid 181.277006 -23.316184)
					(end 181.916324 -23.12289)
				)
				(xy 181.91861 -23.12416) (xy 182.668672 -21.72462) (xy 182.668418 -21.724366)
			)
		)
		(polygon
			(pts
				(arc
					(start 162.666426 -21.72335)
					(mid 162.473287 -21.083725)
					(end 161.833814 -21.277072)
				)
				(xy 161.831528 -21.275802) (xy 161.081466 -22.675596)
				(arc
					(start 161.083752 -22.676866)
					(mid 161.277046 -23.316184)
					(end 161.916364 -23.12289)
				)
				(xy 161.91865 -23.12416) (xy 162.668712 -21.72462) (xy 162.668458 -21.724366)
			)
		)
		(polygon
			(pts
				(arc
					(start 180.416454 -21.723096)
					(mid 180.222906 -21.083524)
					(end 179.583334 -21.277072)
				)
				(arc
					(start 178.836574 -22.671278)
					(mid 179.024276 -23.31492)
					(end 179.666646 -23.12289)
				)
			)
		)
		(polygon
			(pts
				(arc
					(start 160.416494 -21.723096)
					(mid 160.222946 -21.083524)
					(end 159.583374 -21.277072)
				)
				(arc
					(start 158.836614 -22.671278)
					(mid 159.024316 -23.31492)
					(end 159.666686 -23.12289)
				)
			)
		)
		(polygon
			(pts
				(arc
					(start 192.14719 -19.7104)
					(mid 192.132311 -19.674479)
					(end 192.09639 -19.6596)
				)
				(arc
					(start 191.28359 -19.6596)
					(mid 191.247669 -19.674479)
					(end 191.23279 -19.7104)
				)
				(arc
					(start 191.23279 -19.9136)
					(mid 191.247669 -19.949521)
					(end 191.28359 -19.9644)
				)
				(arc
					(start 192.09639 -19.9644)
					(mid 192.132311 -19.949521)
					(end 192.14719 -19.9136)
				)
			)
		)
		(polygon
			(pts
				(arc
					(start 192.14719 -19.0754)
					(mid 192.132311 -19.039479)
					(end 192.09639 -19.0246)
				)
				(arc
					(start 191.28359 -19.0246)
					(mid 191.247669 -19.039479)
					(end 191.23279 -19.0754)
				)
				(arc
					(start 191.23279 -19.2786)
					(mid 191.247669 -19.314521)
					(end 191.28359 -19.3294)
				)
				(arc
					(start 192.09639 -19.3294)
					(mid 192.132311 -19.314521)
					(end 192.14719 -19.2786)
				)
			)
		)
		(polygon
			(pts
				(arc
					(start 182.663592 -17.92859)
					(mid 182.47589 -17.284948)
					(end 181.83352 -17.476978)
				)
				(arc
					(start 181.083458 -18.877026)
					(mid 181.277006 -19.516598)
					(end 181.916578 -19.32305)
				)
			)
		)
		(polygon
			(pts
				(arc
					(start 180.413406 -17.92859)
					(mid 180.225704 -17.284948)
					(end 179.583334 -17.476978)
				)
				(arc
					(start 178.833526 -18.877026)
					(mid 179.027074 -19.516598)
					(end 179.666646 -19.32305)
				)
			)
		)
		(polygon
			(pts
				(arc
					(start 162.663632 -17.92859)
					(mid 162.47593 -17.284948)
					(end 161.83356 -17.476978)
				)
				(arc
					(start 161.083498 -18.877026)
					(mid 161.277046 -19.516598)
					(end 161.916618 -19.32305)
				)
			)
		)
		(polygon
			(pts
				(arc
					(start 160.413446 -17.92859)
					(mid 160.225744 -17.284948)
					(end 159.583374 -17.476978)
				)
				(arc
					(start 158.833566 -18.877026)
					(mid 159.027114 -19.516598)
					(end 159.666686 -19.32305)
				)
			)
		)
	)
	(zone
		(layer "In6.Cu")
		(hatch none 0.5)
		(connect_pads
			(clearance 0)
		)
		(min_thickness 0.25)
		(keepout
			(tracks not_allowed)
			(vias allowed)
			(pads allowed)
			(copperpour not_allowed)
			(footprints allowed)
		)
		(placement
			(enabled no)
			(sheetname "")
		)
		(fill
			(thermal_gap 0.5)
			(thermal_bridge_width 0.5)
			(island_removal_mode 0)
		)
		(polygon
			(pts
				(arc
					(start 187.888118 -80.6958)
					(mid 187.852197 -80.710679)
					(end 187.837318 -80.7466)
				)
				(arc
					(start 187.837318 -81.5594)
					(mid 187.852197 -81.595321)
					(end 187.888118 -81.6102)
				)
				(arc
					(start 188.091318 -81.6102)
					(mid 188.127239 -81.595321)
					(end 188.142118 -81.5594)
				)
				(arc
					(start 188.142118 -80.7466)
					(mid 188.127239 -80.710679)
					(end 188.091318 -80.6958)
				)
			)
		)
	)
	(zone
		(layer "In6.Cu")
		(hatch none 0.5)
		(connect_pads
			(clearance 0)
		)
		(min_thickness 0.25)
		(keepout
			(tracks not_allowed)
			(vias allowed)
			(pads allowed)
			(copperpour not_allowed)
			(footprints allowed)
		)
		(placement
			(enabled no)
			(sheetname "")
		)
		(fill
			(thermal_gap 0.5)
			(thermal_bridge_width 0.5)
			(island_removal_mode 0)
		)
		(polygon
			(pts
				(arc
					(start 169.87139 -37.984938)
					(mid 169.835469 -37.999817)
					(end 169.82059 -38.035738)
				)
				(arc
					(start 169.82059 -38.848538)
					(mid 169.835469 -38.884459)
					(end 169.87139 -38.899338)
				)
				(arc
					(start 170.07459 -38.899338)
					(mid 170.110511 -38.884459)
					(end 170.12539 -38.848538)
				)
				(arc
					(start 170.12539 -38.035738)
					(mid 170.110511 -37.999817)
					(end 170.07459 -37.984938)
				)
			)
		)
	)
	(zone
		(layer "In6.Cu")
		(hatch none 0.5)
		(connect_pads
			(clearance 0)
		)
		(min_thickness 0.25)
		(keepout
			(tracks not_allowed)
			(vias allowed)
			(pads allowed)
			(copperpour not_allowed)
			(footprints allowed)
		)
		(placement
			(enabled no)
			(sheetname "")
		)
		(fill
			(thermal_gap 0.5)
			(thermal_bridge_width 0.5)
			(island_removal_mode 0)
		)
		(polygon
			(pts
				(arc
					(start 188.446918 -80.6958)
					(mid 188.410997 -80.710679)
					(end 188.396118 -80.7466)
				)
				(arc
					(start 188.396118 -81.5594)
					(mid 188.410997 -81.595321)
					(end 188.446918 -81.6102)
				)
				(arc
					(start 188.650118 -81.6102)
					(mid 188.686039 -81.595321)
					(end 188.700918 -81.5594)
				)
				(arc
					(start 188.700918 -80.7466)
					(mid 188.686039 -80.710679)
					(end 188.650118 -80.6958)
				)
			)
		)
	)
	(zone
		(layer "In6.Cu")
		(hatch none 0.5)
		(connect_pads
			(clearance 0)
		)
		(min_thickness 0.25)
		(keepout
			(tracks not_allowed)
			(vias allowed)
			(pads allowed)
			(copperpour not_allowed)
			(footprints allowed)
		)
		(placement
			(enabled no)
			(sheetname "")
		)
		(fill
			(thermal_gap 0.5)
			(thermal_bridge_width 0.5)
			(island_removal_mode 0)
		)
		(polygon
			(pts
				(arc
					(start 166.54399 -37.959538)
					(mid 166.508069 -37.974417)
					(end 166.49319 -38.010338)
				)
				(arc
					(start 166.49319 -38.823138)
					(mid 166.508069 -38.859059)
					(end 166.54399 -38.873938)
				)
				(arc
					(start 166.74719 -38.873938)
					(mid 166.783111 -38.859059)
					(end 166.79799 -38.823138)
				)
				(arc
					(start 166.79799 -38.010338)
					(mid 166.783111 -37.974417)
					(end 166.74719 -37.959538)
				)
			)
		)
	)
	(zone
		(layer "Cmts.User")
		(hatch none 0.5)
		(connect_pads
			(clearance 0)
		)
		(min_thickness 0.25)
		(keepout
			(tracks allowed)
			(vias allowed)
			(pads allowed)
			(copperpour allowed)
			(footprints allowed)
		)
		(placement
			(enabled no)
			(sheetname "")
		)
		(fill
			(thermal_gap 0.5)
			(thermal_bridge_width 0.5)
			(island_removal_mode 0)
		)
		(polygon
			(pts
				(xy 178.225958 -79.600044) (xy 178.225958 -50.56378) (xy 207.299814 -50.56378) (xy 207.299814 -79.600044)
			)
		)
	)
	(zone
		(layer "Cmts.User")
		(hatch none 0.5)
		(connect_pads
			(clearance 0)
		)
		(min_thickness 0.25)
		(keepout
			(tracks allowed)
			(vias allowed)
			(pads allowed)
			(copperpour allowed)
			(footprints allowed)
		)
		(placement
			(enabled no)
			(sheetname "")
		)
		(fill
			(thermal_gap 0.5)
			(thermal_bridge_width 0.5)
			(island_removal_mode 0)
		)
		(polygon
			(pts
				(xy 85.367622 -72.982582)
				(arc
					(start 85.367622 -72.08139)
					(mid 85.271332 -71.827244)
					(end 85.030818 -71.700644)
				)
				(arc
					(start 85.030818 -71.700644)
					(mid 84.729808 -71.793901)
					(end 84.600288 -72.081136)
				)
				(xy 84.601558 -72.082406)
				(arc
					(start 84.601558 -72.970136)
					(mid 84.978493 -73.353619)
					(end 85.368384 -72.983344)
				)
			)
		)
	)
	(zone
		(layer "Cmts.User")
		(hatch none 0.5)
		(connect_pads
			(clearance 0)
		)
		(min_thickness 0.25)
		(keepout
			(tracks allowed)
			(vias allowed)
			(pads allowed)
			(copperpour allowed)
			(footprints allowed)
		)
		(placement
			(enabled no)
			(sheetname "")
		)
		(fill
			(thermal_gap 0.5)
			(thermal_bridge_width 0.5)
			(island_removal_mode 0)
		)
		(polygon
			(pts
				(arc
					(start 197.921372 -88.810338)
					(mid 197.912754 -89.355531)
					(end 198.458074 -89.35847)
				)
				(arc
					(start 199.08647 -88.730074)
					(mid 199.08647 -88.18753)
					(end 198.543926 -88.18753)
				)
			)
		)
	)
	(zone
		(layer "Cmts.User")
		(hatch none 0.5)
		(connect_pads
			(clearance 0)
		)
		(min_thickness 0.25)
		(keepout
			(tracks allowed)
			(vias allowed)
			(pads allowed)
			(copperpour allowed)
			(footprints allowed)
		)
		(placement
			(enabled no)
			(sheetname "")
		)
		(fill
			(thermal_gap 0.5)
			(thermal_bridge_width 0.5)
			(island_removal_mode 0)
		)
		(polygon
			(pts
				(xy 180.800756 -19.30781) (xy 181.899814 -17.11071) (xy 182.861966 -17.59204) (xy 181.762654 -19.78914)
			)
		)
	)
	(zone
		(layer "Cmts.User")
		(hatch none 0.5)
		(connect_pads
			(clearance 0)
		)
		(min_thickness 0.25)
		(keepout
			(tracks allowed)
			(vias allowed)
			(pads allowed)
			(copperpour allowed)
			(footprints allowed)
		)
		(placement
			(enabled no)
			(sheetname "")
		)
		(fill
			(thermal_gap 0.5)
			(thermal_bridge_width 0.5)
			(island_removal_mode 0)
		)
		(polygon
			(pts
				(xy 137.16 -37.559488) (xy 137.16 -35.1028) (xy 138.23569 -35.1028) (xy 138.23569 -37.559488)
			)
		)
	)
	(zone
		(layer "Cmts.User")
		(hatch none 0.5)
		(connect_pads
			(clearance 0)
		)
		(min_thickness 0.25)
		(keepout
			(tracks allowed)
			(vias allowed)
			(pads allowed)
			(copperpour allowed)
			(footprints allowed)
		)
		(placement
			(enabled no)
			(sheetname "")
		)
		(fill
			(thermal_gap 0.5)
			(thermal_bridge_width 0.5)
			(island_removal_mode 0)
		)
		(polygon
			(pts
				(xy 128.120394 -35.119056) (xy 128.120394 -32.662368) (xy 129.196084 -32.662368) (xy 129.196084 -35.119056)
			)
		)
	)
	(zone
		(layer "Cmts.User")
		(hatch none 0.5)
		(connect_pads
			(clearance 0)
		)
		(min_thickness 0.25)
		(keepout
			(tracks allowed)
			(vias allowed)
			(pads allowed)
			(copperpour allowed)
			(footprints allowed)
		)
		(placement
			(enabled no)
			(sheetname "")
		)
		(fill
			(thermal_gap 0.5)
			(thermal_bridge_width 0.5)
			(island_removal_mode 0)
		)
		(polygon
			(pts
				(xy 211.329524 -64.194182) (xy 212.137498 -63.385954)
				(arc
					(start 212.137498 -63.3857)
					(mid 212.137498 -62.84722)
					(end 211.599018 -62.84722)
				)
				(xy 211.598764 -62.846966) (xy 210.790536 -63.655194)
				(arc
					(start 210.79079 -63.655448)
					(mid 210.79079 -64.193928)
					(end 211.32927 -64.193928)
				)
			)
		)
	)
	(zone
		(layer "Cmts.User")
		(hatch none 0.5)
		(connect_pads
			(clearance 0)
		)
		(min_thickness 0.25)
		(keepout
			(tracks allowed)
			(vias allowed)
			(pads allowed)
			(copperpour allowed)
			(footprints allowed)
		)
		(placement
			(enabled no)
			(sheetname "")
		)
		(fill
			(thermal_gap 0.5)
			(thermal_bridge_width 0.5)
			(island_removal_mode 0)
		)
		(polygon
			(pts
				(xy 216.90838 -75.984608) (xy 217.716354 -75.17638)
				(arc
					(start 217.716354 -75.176126)
					(mid 217.716354 -74.637646)
					(end 217.177874 -74.637646)
				)
				(xy 217.17762 -74.637392) (xy 216.369392 -75.44562)
				(arc
					(start 216.369646 -75.445874)
					(mid 216.369646 -75.984354)
					(end 216.908126 -75.984354)
				)
			)
		)
	)
	(zone
		(layer "Cmts.User")
		(hatch none 0.5)
		(connect_pads
			(clearance 0)
		)
		(min_thickness 0.25)
		(keepout
			(tracks allowed)
			(vias allowed)
			(pads allowed)
			(copperpour allowed)
			(footprints allowed)
		)
		(placement
			(enabled no)
			(sheetname "")
		)
		(fill
			(thermal_gap 0.5)
			(thermal_bridge_width 0.5)
			(island_removal_mode 0)
		)
		(polygon
			(pts
				(arc
					(start 196.630544 -85.686138)
					(mid 196.621926 -86.231331)
					(end 197.167246 -86.23427)
				)
				(arc
					(start 197.795642 -85.605874)
					(mid 197.795642 -85.06333)
					(end 197.253098 -85.06333)
				)
			)
		)
	)
	(zone
		(layer "Cmts.User")
		(hatch none 0.5)
		(connect_pads
			(clearance 0)
		)
		(min_thickness 0.25)
		(keepout
			(tracks allowed)
			(vias allowed)
			(pads allowed)
			(copperpour allowed)
			(footprints allowed)
		)
		(placement
			(enabled no)
			(sheetname "")
		)
		(fill
			(thermal_gap 0.5)
			(thermal_bridge_width 0.5)
			(island_removal_mode 0)
		)
		(polygon
			(pts
				(xy 137.143998 -33.914588) (xy 137.143998 -31.4579) (xy 138.219688 -31.4579) (xy 138.219688 -33.914588)
			)
		)
	)
	(zone
		(layer "Cmts.User")
		(hatch none 0.5)
		(connect_pads
			(clearance 0)
		)
		(min_thickness 0.25)
		(keepout
			(tracks allowed)
			(vias allowed)
			(pads allowed)
			(copperpour allowed)
			(footprints allowed)
		)
		(placement
			(enabled no)
			(sheetname "")
		)
		(fill
			(thermal_gap 0.5)
			(thermal_bridge_width 0.5)
			(island_removal_mode 0)
		)
		(polygon
			(pts
				(xy 85.367622 -85.80628)
				(arc
					(start 85.367622 -84.905088)
					(mid 85.271332 -84.650942)
					(end 85.030818 -84.524342)
				)
				(arc
					(start 85.030818 -84.524342)
					(mid 84.729808 -84.617599)
					(end 84.600288 -84.904834)
				)
				(xy 84.601558 -84.906104)
				(arc
					(start 84.601558 -85.793834)
					(mid 84.978493 -86.177317)
					(end 85.368384 -85.807042)
				)
			)
		)
	)
	(zone
		(layer "Cmts.User")
		(hatch none 0.5)
		(connect_pads
			(clearance 0)
		)
		(min_thickness 0.25)
		(keepout
			(tracks allowed)
			(vias allowed)
			(pads allowed)
			(copperpour allowed)
			(footprints allowed)
		)
		(placement
			(enabled no)
			(sheetname "")
		)
		(fill
			(thermal_gap 0.5)
			(thermal_bridge_width 0.5)
			(island_removal_mode 0)
		)
		(polygon
			(pts
				(xy 160.779714 -26.950162) (xy 161.878772 -24.753062) (xy 162.840924 -25.234392) (xy 161.741612 -27.431492)
			)
		)
	)
	(zone
		(layer "Cmts.User")
		(hatch none 0.5)
		(connect_pads
			(clearance 0)
		)
		(min_thickness 0.25)
		(keepout
			(tracks allowed)
			(vias allowed)
			(pads allowed)
			(copperpour allowed)
			(footprints allowed)
		)
		(placement
			(enabled no)
			(sheetname "")
		)
		(fill
			(thermal_gap 0.5)
			(thermal_bridge_width 0.5)
			(island_removal_mode 0)
		)
		(polygon
			(pts
				(xy 77.667612 -74.610214)
				(arc
					(start 77.667612 -73.709022)
					(mid 77.571322 -73.454876)
					(end 77.330808 -73.328276)
				)
				(arc
					(start 77.330808 -73.328276)
					(mid 77.029798 -73.421533)
					(end 76.900278 -73.708768)
				)
				(xy 76.901548 -73.710038)
				(arc
					(start 76.901548 -74.597768)
					(mid 77.278483 -74.981251)
					(end 77.668374 -74.610976)
				)
			)
		)
	)
	(zone
		(layer "Cmts.User")
		(hatch none 0.5)
		(connect_pads
			(clearance 0)
		)
		(min_thickness 0.25)
		(keepout
			(tracks allowed)
			(vias allowed)
			(pads allowed)
			(copperpour allowed)
			(footprints allowed)
		)
		(placement
			(enabled no)
			(sheetname "")
		)
		(fill
			(thermal_gap 0.5)
			(thermal_bridge_width 0.5)
			(island_removal_mode 0)
		)
		(polygon
			(pts
				(xy 129.918714 -33.914842) (xy 129.918714 -31.458154) (xy 130.994404 -31.458154) (xy 130.994404 -33.914842)
			)
		)
	)
	(zone
		(layer "Cmts.User")
		(hatch none 0.5)
		(connect_pads
			(clearance 0)
		)
		(min_thickness 0.25)
		(keepout
			(tracks allowed)
			(vias allowed)
			(pads allowed)
			(copperpour allowed)
			(footprints allowed)
		)
		(placement
			(enabled no)
			(sheetname "")
		)
		(fill
			(thermal_gap 0.5)
			(thermal_bridge_width 0.5)
			(island_removal_mode 0)
		)
		(polygon
			(pts
				(xy 215.76538 -79.921608) (xy 216.573354 -79.11338)
				(arc
					(start 216.573354 -79.113126)
					(mid 216.573354 -78.574646)
					(end 216.034874 -78.574646)
				)
				(xy 216.03462 -78.574392) (xy 215.226392 -79.38262)
				(arc
					(start 215.226646 -79.382874)
					(mid 215.226646 -79.921354)
					(end 215.765126 -79.921354)
				)
			)
		)
	)
	(zone
		(layer "Cmts.User")
		(hatch none 0.5)
		(connect_pads
			(clearance 0)
		)
		(min_thickness 0.25)
		(keepout
			(tracks allowed)
			(vias allowed)
			(pads allowed)
			(copperpour allowed)
			(footprints allowed)
		)
		(placement
			(enabled no)
			(sheetname "")
		)
		(fill
			(thermal_gap 0.5)
			(thermal_bridge_width 0.5)
			(island_removal_mode 0)
		)
		(polygon
			(pts
				(arc
					(start 189.285372 -84.238338)
					(mid 189.276754 -84.783531)
					(end 189.822074 -84.78647)
				)
				(arc
					(start 190.45047 -84.158074)
					(mid 190.45047 -83.61553)
					(end 189.907926 -83.61553)
				)
			)
		)
	)
	(zone
		(layer "Cmts.User")
		(hatch none 0.5)
		(connect_pads
			(clearance 0)
		)
		(min_thickness 0.25)
		(keepout
			(tracks allowed)
			(vias allowed)
			(pads allowed)
			(copperpour allowed)
			(footprints allowed)
		)
		(placement
			(enabled no)
			(sheetname "")
		)
		(fill
			(thermal_gap 0.5)
			(thermal_bridge_width 0.5)
			(island_removal_mode 0)
		)
		(polygon
			(pts
				(xy 115.547902 -37.493702) (xy 115.547902 -35.037014) (xy 116.623592 -35.037014) (xy 116.623592 -37.493702)
			)
		)
	)
	(zone
		(layer "Cmts.User")
		(hatch none 0.5)
		(connect_pads
			(clearance 0)
		)
		(min_thickness 0.25)
		(keepout
			(tracks allowed)
			(vias allowed)
			(pads allowed)
			(copperpour allowed)
			(footprints allowed)
		)
		(placement
			(enabled no)
			(sheetname "")
		)
		(fill
			(thermal_gap 0.5)
			(thermal_bridge_width 0.5)
			(island_removal_mode 0)
		)
		(polygon
			(pts
				(xy 214.49538 -69.761608) (xy 215.303354 -68.95338)
				(arc
					(start 215.303354 -68.953126)
					(mid 215.303354 -68.414646)
					(end 214.764874 -68.414646)
				)
				(xy 214.76462 -68.414392) (xy 213.956392 -69.22262)
				(arc
					(start 213.956646 -69.222874)
					(mid 213.956646 -69.761354)
					(end 214.495126 -69.761354)
				)
			)
		)
	)
	(zone
		(layer "Cmts.User")
		(hatch none 0.5)
		(connect_pads
			(clearance 0)
		)
		(min_thickness 0.25)
		(keepout
			(tracks allowed)
			(vias allowed)
			(pads allowed)
			(copperpour allowed)
			(footprints allowed)
		)
		(placement
			(enabled no)
			(sheetname "")
		)
		(fill
			(thermal_gap 0.5)
			(thermal_bridge_width 0.5)
			(island_removal_mode 0)
		)
		(polygon
			(pts
				(xy 138.942318 -38.763702) (xy 138.942318 -36.307014) (xy 140.018008 -36.307014) (xy 140.018008 -38.763702)
			)
		)
	)
	(zone
		(layer "Cmts.User")
		(hatch none 0.5)
		(connect_pads
			(clearance 0)
		)
		(min_thickness 0.25)
		(keepout
			(tracks allowed)
			(vias allowed)
			(pads allowed)
			(copperpour allowed)
			(footprints allowed)
		)
		(placement
			(enabled no)
			(sheetname "")
		)
		(fill
			(thermal_gap 0.5)
			(thermal_bridge_width 0.5)
			(island_removal_mode 0)
		)
		(polygon
			(pts
				(xy 83.742022 -76.206604)
				(arc
					(start 83.742022 -75.305412)
					(mid 83.645732 -75.051266)
					(end 83.405218 -74.924666)
				)
				(arc
					(start 83.405218 -74.924666)
					(mid 83.104208 -75.017923)
					(end 82.974688 -75.305158)
				)
				(xy 82.975958 -75.306428)
				(arc
					(start 82.975958 -76.194158)
					(mid 83.352893 -76.577641)
					(end 83.742784 -76.207366)
				)
			)
		)
	)
	(zone
		(layer "Cmts.User")
		(hatch none 0.5)
		(connect_pads
			(clearance 0)
		)
		(min_thickness 0.25)
		(keepout
			(tracks allowed)
			(vias allowed)
			(pads allowed)
			(copperpour allowed)
			(footprints allowed)
		)
		(placement
			(enabled no)
			(sheetname "")
		)
		(fill
			(thermal_gap 0.5)
			(thermal_bridge_width 0.5)
			(island_removal_mode 0)
		)
		(polygon
			(pts
				(xy 108.36656 -37.4777) (xy 108.36656 -35.021012) (xy 109.44225 -35.021012) (xy 109.44225 -37.4777)
			)
		)
	)
	(zone
		(layer "Cmts.User")
		(hatch none 0.5)
		(connect_pads
			(clearance 0)
		)
		(min_thickness 0.25)
		(keepout
			(tracks allowed)
			(vias allowed)
			(pads allowed)
			(copperpour allowed)
			(footprints allowed)
		)
		(placement
			(enabled no)
			(sheetname "")
		)
		(fill
			(thermal_gap 0.5)
			(thermal_bridge_width 0.5)
			(island_removal_mode 0)
		)
		(polygon
			(pts
				(xy 160.810702 -23.16099) (xy 161.90976 -20.96389) (xy 162.871912 -21.44522) (xy 161.7726 -23.64232)
			)
		)
	)
	(zone
		(layer "Cmts.User")
		(hatch none 0.5)
		(connect_pads
			(clearance 0)
		)
		(min_thickness 0.25)
		(keepout
			(tracks allowed)
			(vias allowed)
			(pads allowed)
			(copperpour allowed)
			(footprints allowed)
		)
		(placement
			(enabled no)
			(sheetname "")
		)
		(fill
			(thermal_gap 0.5)
			(thermal_bridge_width 0.5)
			(island_removal_mode 0)
		)
		(polygon
			(pts
				(arc
					(start 208.101692 -84.431124)
					(mid 208.093074 -84.976317)
					(end 208.638394 -84.979256)
				)
				(arc
					(start 209.26679 -84.35086)
					(mid 209.26679 -83.808316)
					(end 208.724246 -83.808316)
				)
			)
		)
	)
	(zone
		(layer "Cmts.User")
		(hatch none 0.5)
		(connect_pads
			(clearance 0)
		)
		(min_thickness 0.25)
		(keepout
			(tracks allowed)
			(vias allowed)
			(pads allowed)
			(copperpour allowed)
			(footprints allowed)
		)
		(placement
			(enabled no)
			(sheetname "")
		)
		(fill
			(thermal_gap 0.5)
			(thermal_bridge_width 0.5)
			(island_removal_mode 0)
		)
		(polygon
			(pts
				(arc
					(start 193.781172 -84.009738)
					(mid 193.772554 -84.554931)
					(end 194.317874 -84.55787)
				)
				(arc
					(start 194.94627 -83.929474)
					(mid 194.94627 -83.38693)
					(end 194.403726 -83.38693)
				)
			)
		)
	)
	(zone
		(layer "Cmts.User")
		(hatch none 0.5)
		(connect_pads
			(clearance 0)
		)
		(min_thickness 0.25)
		(keepout
			(tracks allowed)
			(vias allowed)
			(pads allowed)
			(copperpour allowed)
			(footprints allowed)
		)
		(placement
			(enabled no)
			(sheetname "")
		)
		(fill
			(thermal_gap 0.5)
			(thermal_bridge_width 0.5)
			(island_removal_mode 0)
		)
		(polygon
			(pts
				(xy 113.741454 -38.722046) (xy 113.741454 -36.265358) (xy 114.817144 -36.265358) (xy 114.817144 -38.722046)
			)
		)
	)
	(zone
		(layer "Cmts.User")
		(hatch none 0.5)
		(connect_pads
			(clearance 0)
		)
		(min_thickness 0.25)
		(keepout
			(tracks allowed)
			(vias allowed)
			(pads allowed)
			(copperpour allowed)
			(footprints allowed)
		)
		(placement
			(enabled no)
			(sheetname "")
		)
		(fill
			(thermal_gap 0.5)
			(thermal_bridge_width 0.5)
			(island_removal_mode 0)
		)
		(polygon
			(pts
				(xy 178.570128 -26.831036) (xy 179.669186 -24.633936) (xy 180.631338 -25.115266) (xy 179.532026 -27.312366)
			)
		)
	)
	(zone
		(layer "Cmts.User")
		(hatch none 0.5)
		(connect_pads
			(clearance 0.5)
		)
		(min_thickness 0.25)
		(fill
			(thermal_gap 0.5)
			(thermal_bridge_width 0.5)
			(island_removal_mode 0)
		)
		(polygon
			(pts
				(xy 285.968948 -199.987662) (xy 122.178064 -199.987662) (xy 122.178064 10.328148) (xy 285.968948 10.328148)
			)
		)
	)
	(zone
		(layer "Cmts.User")
		(hatch none 0.5)
		(connect_pads
			(clearance 0)
		)
		(min_thickness 0.25)
		(keepout
			(tracks allowed)
			(vias allowed)
			(pads allowed)
			(copperpour allowed)
			(footprints allowed)
		)
		(placement
			(enabled no)
			(sheetname "")
		)
		(fill
			(thermal_gap 0.5)
			(thermal_bridge_width 0.5)
			(island_removal_mode 0)
		)
		(polygon
			(pts
				(xy 85.367622 -79.406242)
				(arc
					(start 85.367622 -78.50505)
					(mid 85.271332 -78.250904)
					(end 85.030818 -78.124304)
				)
				(arc
					(start 85.030818 -78.124304)
					(mid 84.729808 -78.217561)
					(end 84.600288 -78.504796)
				)
				(xy 84.601558 -78.506066)
				(arc
					(start 84.601558 -79.393796)
					(mid 84.978493 -79.777279)
					(end 85.368384 -79.407004)
				)
			)
		)
	)
	(zone
		(layer "Cmts.User")
		(hatch none 0.5)
		(connect_pads
			(clearance 0)
		)
		(min_thickness 0.25)
		(keepout
			(tracks allowed)
			(vias allowed)
			(pads allowed)
			(copperpour allowed)
			(footprints allowed)
		)
		(placement
			(enabled no)
			(sheetname "")
		)
		(fill
			(thermal_gap 0.5)
			(thermal_bridge_width 0.5)
			(island_removal_mode 0)
		)
		(polygon
			(pts
				(xy 128.120394 -38.699694) (xy 128.120394 -36.243006) (xy 129.196084 -36.243006) (xy 129.196084 -38.699694)
			)
		)
	)
	(zone
		(layer "Cmts.User")
		(hatch none 0.5)
		(connect_pads
			(clearance 0)
		)
		(min_thickness 0.25)
		(keepout
			(tracks allowed)
			(vias allowed)
			(pads allowed)
			(copperpour allowed)
			(footprints allowed)
		)
		(placement
			(enabled no)
			(sheetname "")
		)
		(fill
			(thermal_gap 0.5)
			(thermal_bridge_width 0.5)
			(island_removal_mode 0)
		)
		(polygon
			(pts
				(xy 119.14505 -33.978596) (xy 119.14505 -31.521908) (xy 120.22074 -31.521908) (xy 120.22074 -33.978596)
			)
		)
	)
	(zone
		(layer "Cmts.User")
		(hatch none 0.5)
		(connect_pads
			(clearance 0)
		)
		(min_thickness 0.25)
		(keepout
			(tracks allowed)
			(vias allowed)
			(pads allowed)
			(copperpour allowed)
			(footprints allowed)
		)
		(placement
			(enabled no)
			(sheetname "")
		)
		(fill
			(thermal_gap 0.5)
			(thermal_bridge_width 0.5)
			(island_removal_mode 0)
		)
		(polygon
			(pts
				(xy 180.820314 -30.63113) (xy 181.919372 -28.43403) (xy 182.881524 -28.91536) (xy 181.782212 -31.11246)
			)
		)
	)
	(zone
		(layer "Cmts.User")
		(hatch none 0.5)
		(connect_pads
			(clearance 0)
		)
		(min_thickness 0.25)
		(keepout
			(tracks allowed)
			(vias allowed)
			(pads allowed)
			(copperpour allowed)
			(footprints allowed)
		)
		(placement
			(enabled no)
			(sheetname "")
		)
		(fill
			(thermal_gap 0.5)
			(thermal_bridge_width 0.5)
			(island_removal_mode 0)
		)
		(polygon
			(pts
				(xy 215.38438 -74.460608) (xy 216.192354 -73.65238)
				(arc
					(start 216.192354 -73.652126)
					(mid 216.192354 -73.113646)
					(end 215.653874 -73.113646)
				)
				(xy 215.65362 -73.113392) (xy 214.845392 -73.92162)
				(arc
					(start 214.845646 -73.921874)
					(mid 214.845646 -74.460354)
					(end 215.384126 -74.460354)
				)
			)
		)
	)
	(zone
		(layer "Cmts.User")
		(hatch none 0.5)
		(connect_pads
			(clearance 0)
		)
		(min_thickness 0.25)
		(keepout
			(tracks allowed)
			(vias allowed)
			(pads allowed)
			(copperpour allowed)
			(footprints allowed)
		)
		(placement
			(enabled no)
			(sheetname "")
		)
		(fill
			(thermal_gap 0.5)
			(thermal_bridge_width 0.5)
			(island_removal_mode 0)
		)
		(polygon
			(pts
				(xy 158.544006 -30.72384) (xy 159.643064 -28.52674) (xy 160.605216 -29.00807) (xy 159.505904 -31.20517)
			)
		)
	)
	(zone
		(layer "Cmts.User")
		(hatch none 0.5)
		(connect_pads
			(clearance 0)
		)
		(min_thickness 0.25)
		(keepout
			(tracks allowed)
			(vias allowed)
			(pads allowed)
			(copperpour allowed)
			(footprints allowed)
		)
		(placement
			(enabled no)
			(sheetname "")
		)
		(fill
			(thermal_gap 0.5)
			(thermal_bridge_width 0.5)
			(island_removal_mode 0)
		)
		(polygon
			(pts
				(xy 36.190936 -156.4386) (xy 36.190936 -133.5786) (xy 41.93794 -133.5786) (xy 42.6974 -132.81914)
				(xy 45.25518 -132.81914) (xy 45.95876 -132.11556) (xy 47.05604 -132.11556) (xy 47.46498 -132.5245)
				(xy 47.46498 -132.68198) (xy 47.45609 -132.69087) (xy 47.45609 -133.45795) (xy 47.57674 -133.5786)
				(xy 59.152536 -133.5786) (xy 59.152536 -141.224) (xy 60.5028 -142.574264) (xy 60.5028 -145.669)
				(xy 59.814968 -146.356832) (xy 59.814968 -150.065232) (xy 61.3664 -151.616664) (xy 61.3664 -155.1432)
				(xy 60.071 -156.4386) (xy 59.152536 -156.4386)
			)
		)
	)
	(zone
		(layer "Cmts.User")
		(hatch none 0.5)
		(connect_pads
			(clearance 0)
		)
		(min_thickness 0.25)
		(keepout
			(tracks allowed)
			(vias allowed)
			(pads allowed)
			(copperpour allowed)
			(footprints allowed)
		)
		(placement
			(enabled no)
			(sheetname "")
		)
		(fill
			(thermal_gap 0.5)
			(thermal_bridge_width 0.5)
			(island_removal_mode 0)
		)
		(polygon
			(pts
				(xy 113.765838 -35.101276) (xy 113.765838 -32.644588) (xy 114.841528 -32.644588) (xy 114.841528 -35.101276)
			)
		)
	)
	(zone
		(layer "Cmts.User")
		(hatch none 0.5)
		(connect_pads
			(clearance 0)
		)
		(min_thickness 0.25)
		(keepout
			(tracks allowed)
			(vias allowed)
			(pads allowed)
			(copperpour allowed)
			(footprints allowed)
		)
		(placement
			(enabled no)
			(sheetname "")
		)
		(fill
			(thermal_gap 0.5)
			(thermal_bridge_width 0.5)
			(island_removal_mode 0)
		)
		(polygon
			(pts
				(xy 158.5468 -19.33956) (xy 159.645858 -17.14246) (xy 160.60801 -17.62379) (xy 159.508698 -19.82089)
			)
		)
	)
	(zone
		(layer "Cmts.User")
		(hatch none 0.5)
		(connect_pads
			(clearance 0)
		)
		(min_thickness 0.25)
		(keepout
			(tracks allowed)
			(vias allowed)
			(pads allowed)
			(copperpour allowed)
			(footprints allowed)
		)
		(placement
			(enabled no)
			(sheetname "")
		)
		(fill
			(thermal_gap 0.5)
			(thermal_bridge_width 0.5)
			(island_removal_mode 0)
		)
		(polygon
			(pts
				(xy 85.367622 -92.207842)
				(arc
					(start 85.367622 -91.30665)
					(mid 85.271332 -91.052504)
					(end 85.030818 -90.925904)
				)
				(arc
					(start 85.030818 -90.925904)
					(mid 84.729808 -91.019161)
					(end 84.600288 -91.306396)
				)
				(xy 84.601558 -91.307666)
				(arc
					(start 84.601558 -92.195396)
					(mid 84.978493 -92.578879)
					(end 85.368384 -92.208604)
				)
			)
		)
	)
	(zone
		(layer "Cmts.User")
		(hatch none 0.5)
		(connect_pads
			(clearance 0)
		)
		(min_thickness 0.25)
		(keepout
			(tracks allowed)
			(vias allowed)
			(pads allowed)
			(copperpour allowed)
			(footprints allowed)
		)
		(placement
			(enabled no)
			(sheetname "")
		)
		(fill
			(thermal_gap 0.5)
			(thermal_bridge_width 0.5)
			(island_removal_mode 0)
		)
		(polygon
			(pts
				(xy 115.58016 -33.913064) (xy 115.58016 -31.456376) (xy 116.65585 -31.456376) (xy 116.65585 -33.913064)
			)
		)
	)
	(zone
		(layer "Cmts.User")
		(hatch none 0.5)
		(connect_pads
			(clearance 0)
		)
		(min_thickness 0.25)
		(keepout
			(tracks allowed)
			(vias allowed)
			(pads allowed)
			(copperpour allowed)
			(footprints allowed)
		)
		(placement
			(enabled no)
			(sheetname "")
		)
		(fill
			(thermal_gap 0.5)
			(thermal_bridge_width 0.5)
			(island_removal_mode 0)
		)
		(polygon
			(pts
				(xy 77.658468 -68.223638)
				(arc
					(start 77.658468 -67.322446)
					(mid 77.562178 -67.0683)
					(end 77.321664 -66.9417)
				)
				(arc
					(start 77.321664 -66.9417)
					(mid 77.020654 -67.034957)
					(end 76.891134 -67.322192)
				)
				(xy 76.892404 -67.323462)
				(arc
					(start 76.892404 -68.211192)
					(mid 77.269339 -68.594675)
					(end 77.65923 -68.2244)
				)
			)
		)
	)
	(zone
		(layer "Cmts.User")
		(hatch none 0.5)
		(connect_pads
			(clearance 0)
		)
		(min_thickness 0.25)
		(keepout
			(tracks allowed)
			(vias allowed)
			(pads allowed)
			(copperpour allowed)
			(footprints allowed)
		)
		(placement
			(enabled no)
			(sheetname "")
		)
		(fill
			(thermal_gap 0.5)
			(thermal_bridge_width 0.5)
			(island_removal_mode 0)
		)
		(polygon
			(pts
				(xy 78.504542 -71.409814)
				(arc
					(start 78.504542 -70.508622)
					(mid 78.408252 -70.254476)
					(end 78.167738 -70.127876)
				)
				(arc
					(start 78.167738 -70.127876)
					(mid 77.866728 -70.221133)
					(end 77.737208 -70.508368)
				)
				(xy 77.738478 -70.509638)
				(arc
					(start 77.738478 -71.397368)
					(mid 78.115413 -71.780851)
					(end 78.505304 -71.410576)
				)
			)
		)
	)
	(zone
		(layer "Cmts.User")
		(hatch none 0.5)
		(connect_pads
			(clearance 0)
		)
		(min_thickness 0.25)
		(keepout
			(tracks allowed)
			(vias allowed)
			(pads allowed)
			(copperpour allowed)
			(footprints allowed)
		)
		(placement
			(enabled no)
			(sheetname "")
		)
		(fill
			(thermal_gap 0.5)
			(thermal_bridge_width 0.5)
			(island_removal_mode 0)
		)
		(polygon
			(pts
				(xy 212.97138 -68.288408) (xy 213.779354 -67.48018)
				(arc
					(start 213.779354 -67.479926)
					(mid 213.779354 -66.941446)
					(end 213.240874 -66.941446)
				)
				(xy 213.24062 -66.941192) (xy 212.432392 -67.74942)
				(arc
					(start 212.432646 -67.749674)
					(mid 212.432646 -68.288154)
					(end 212.971126 -68.288154)
				)
			)
		)
	)
	(zone
		(layer "Cmts.User")
		(hatch none 0.5)
		(connect_pads
			(clearance 0)
		)
		(min_thickness 0.25)
		(keepout
			(tracks allowed)
			(vias allowed)
			(pads allowed)
			(copperpour allowed)
			(footprints allowed)
		)
		(placement
			(enabled no)
			(sheetname "")
		)
		(fill
			(thermal_gap 0.5)
			(thermal_bridge_width 0.5)
			(island_removal_mode 0)
		)
		(polygon
			(pts
				(xy 110.160816 -38.681914) (xy 110.160816 -36.225226) (xy 111.236506 -36.225226) (xy 111.236506 -38.681914)
			)
		)
	)
	(zone
		(layer "Cmts.User")
		(hatch none 0.5)
		(connect_pads
			(clearance 0)
		)
		(min_thickness 0.25)
		(keepout
			(tracks allowed)
			(vias allowed)
			(pads allowed)
			(copperpour allowed)
			(footprints allowed)
		)
		(placement
			(enabled no)
			(sheetname "")
		)
		(fill
			(thermal_gap 0.5)
			(thermal_bridge_width 0.5)
			(island_removal_mode 0)
		)
		(polygon
			(pts
				(xy 178.636676 -30.695392) (xy 179.735734 -28.498292) (xy 180.697886 -28.979622) (xy 179.598574 -31.176722)
			)
		)
	)
	(zone
		(layer "Cmts.User")
		(hatch none 0.5)
		(connect_pads
			(clearance 0)
		)
		(min_thickness 0.25)
		(keepout
			(tracks allowed)
			(vias allowed)
			(pads allowed)
			(copperpour allowed)
			(footprints allowed)
		)
		(placement
			(enabled no)
			(sheetname "")
		)
		(fill
			(thermal_gap 0.5)
			(thermal_bridge_width 0.5)
			(island_removal_mode 0)
		)
		(polygon
			(pts
				(xy 180.820314 -26.831036) (xy 181.919372 -24.633936) (xy 182.881524 -25.115266) (xy 181.782212 -27.312366)
			)
		)
	)
	(zone
		(layer "Cmts.User")
		(hatch none 0.5)
		(connect_pads
			(clearance 0)
		)
		(min_thickness 0.25)
		(keepout
			(tracks allowed)
			(vias allowed)
			(pads allowed)
			(copperpour allowed)
			(footprints allowed)
		)
		(placement
			(enabled no)
			(sheetname "")
		)
		(fill
			(thermal_gap 0.5)
			(thermal_bridge_width 0.5)
			(island_removal_mode 0)
		)
		(polygon
			(pts
				(xy 110.217458 -35.069272) (xy 110.217458 -32.612584) (xy 111.293148 -32.612584) (xy 111.293148 -35.069272)
			)
		)
	)
	(zone
		(layer "Cmts.User")
		(hatch none 0.5)
		(connect_pads
			(clearance 0)
		)
		(min_thickness 0.25)
		(keepout
			(tracks allowed)
			(vias allowed)
			(pads allowed)
			(copperpour allowed)
			(footprints allowed)
		)
		(placement
			(enabled no)
			(sheetname "")
		)
		(fill
			(thermal_gap 0.5)
			(thermal_bridge_width 0.5)
			(island_removal_mode 0)
		)
		(polygon
			(pts
				(xy 211.49818 -66.637408) (xy 212.306154 -65.82918)
				(arc
					(start 212.306154 -65.828926)
					(mid 212.306154 -65.290446)
					(end 211.767674 -65.290446)
				)
				(xy 211.76742 -65.290192) (xy 210.959192 -66.09842)
				(arc
					(start 210.959446 -66.098674)
					(mid 210.959446 -66.637154)
					(end 211.497926 -66.637154)
				)
			)
		)
	)
	(zone
		(layer "Cmts.User")
		(hatch none 0.5)
		(connect_pads
			(clearance 0)
		)
		(min_thickness 0.25)
		(keepout
			(tracks allowed)
			(vias allowed)
			(pads allowed)
			(copperpour allowed)
			(footprints allowed)
		)
		(placement
			(enabled no)
			(sheetname "")
		)
		(fill
			(thermal_gap 0.5)
			(thermal_bridge_width 0.5)
			(island_removal_mode 0)
		)
		(polygon
			(pts
				(xy 158.530544 -23.11146) (xy 159.629602 -20.91436) (xy 160.591754 -21.39569) (xy 159.492442 -23.59279)
			)
		)
	)
	(zone
		(layer "Cmts.User")
		(hatch none 0.5)
		(connect_pads
			(clearance 0)
		)
		(min_thickness 0.25)
		(keepout
			(tracks allowed)
			(vias allowed)
			(pads allowed)
			(copperpour allowed)
			(footprints allowed)
		)
		(placement
			(enabled no)
			(sheetname "")
		)
		(fill
			(thermal_gap 0.5)
			(thermal_bridge_width 0.5)
			(island_removal_mode 0)
		)
		(polygon
			(pts
				(xy 131.749292 -35.135058) (xy 131.749292 -32.67837) (xy 132.824982 -32.67837) (xy 132.824982 -35.135058)
			)
		)
	)
	(zone
		(layer "Cmts.User")
		(hatch none 0.5)
		(connect_pads
			(clearance 0)
		)
		(min_thickness 0.25)
		(keepout
			(tracks allowed)
			(vias allowed)
			(pads allowed)
			(copperpour allowed)
			(footprints allowed)
		)
		(placement
			(enabled no)
			(sheetname "")
		)
		(fill
			(thermal_gap 0.5)
			(thermal_bridge_width 0.5)
			(island_removal_mode 0)
		)
		(polygon
			(pts
				(xy 131.765294 -38.7477) (xy 131.765294 -36.291012) (xy 132.840984 -36.291012) (xy 132.840984 -38.7477)
			)
		)
	)
	(zone
		(layer "Cmts.User")
		(hatch none 0.5)
		(connect_pads
			(clearance 0)
		)
		(min_thickness 0.25)
		(keepout
			(tracks allowed)
			(vias allowed)
			(pads allowed)
			(copperpour allowed)
			(footprints allowed)
		)
		(placement
			(enabled no)
			(sheetname "")
		)
		(fill
			(thermal_gap 0.5)
			(thermal_bridge_width 0.5)
			(island_removal_mode 0)
		)
		(polygon
			(pts
				(xy 77.667612 -81.011014)
				(arc
					(start 77.667612 -80.109822)
					(mid 77.571322 -79.855676)
					(end 77.330808 -79.729076)
				)
				(arc
					(start 77.330808 -79.729076)
					(mid 77.029798 -79.822333)
					(end 76.900278 -80.109568)
				)
				(xy 76.901548 -80.110838)
				(arc
					(start 76.901548 -80.998568)
					(mid 77.278483 -81.382051)
					(end 77.668374 -81.011776)
				)
			)
		)
	)
	(zone
		(layer "Cmts.User")
		(hatch none 0.5)
		(connect_pads
			(clearance 0)
		)
		(min_thickness 0.25)
		(keepout
			(tracks allowed)
			(vias allowed)
			(pads allowed)
			(copperpour allowed)
			(footprints allowed)
		)
		(placement
			(enabled no)
			(sheetname "")
		)
		(fill
			(thermal_gap 0.5)
			(thermal_bridge_width 0.5)
			(island_removal_mode 0)
		)
		(polygon
			(pts
				(xy 178.569112 -19.30781) (xy 179.66817 -17.11071) (xy 180.630322 -17.59204) (xy 179.53101 -19.78914)
			)
		)
	)
	(zone
		(layer "Cmts.User")
		(hatch none 0.5)
		(connect_pads
			(clearance 0)
		)
		(min_thickness 0.25)
		(keepout
			(tracks allowed)
			(vias allowed)
			(pads allowed)
			(copperpour allowed)
			(footprints allowed)
		)
		(placement
			(enabled no)
			(sheetname "")
		)
		(fill
			(thermal_gap 0.5)
			(thermal_bridge_width 0.5)
			(island_removal_mode 0)
		)
		(polygon
			(pts
				(xy 83.742022 -89.00668)
				(arc
					(start 83.742022 -88.105488)
					(mid 83.645732 -87.851342)
					(end 83.405218 -87.724742)
				)
				(arc
					(start 83.405218 -87.724742)
					(mid 83.104208 -87.817999)
					(end 82.974688 -88.105234)
				)
				(xy 82.975958 -88.106504)
				(arc
					(start 82.975958 -88.994234)
					(mid 83.352893 -89.377717)
					(end 83.742784 -89.007442)
				)
			)
		)
	)
	(zone
		(layer "Cmts.User")
		(hatch none 0.5)
		(connect_pads
			(clearance 0)
		)
		(min_thickness 0.25)
		(keepout
			(tracks allowed)
			(vias allowed)
			(pads allowed)
			(copperpour allowed)
			(footprints allowed)
		)
		(placement
			(enabled no)
			(sheetname "")
		)
		(fill
			(thermal_gap 0.5)
			(thermal_bridge_width 0.5)
			(island_removal_mode 0)
		)
		(polygon
			(pts
				(xy 140.772642 -33.946846) (xy 140.772642 -31.490158) (xy 141.848332 -31.490158) (xy 141.848332 -33.946846)
			)
		)
	)
	(zone
		(layer "Cmts.User")
		(hatch none 0.5)
		(connect_pads
			(clearance 0)
		)
		(min_thickness 0.25)
		(keepout
			(tracks allowed)
			(vias allowed)
			(pads allowed)
			(copperpour allowed)
			(footprints allowed)
		)
		(placement
			(enabled no)
			(sheetname "")
		)
		(fill
			(thermal_gap 0.5)
			(thermal_bridge_width 0.5)
			(island_removal_mode 0)
		)
		(polygon
			(pts
				(xy 117.330728 -35.18281) (xy 117.330728 -32.726122) (xy 118.406418 -32.726122) (xy 118.406418 -35.18281)
			)
		)
	)
	(zone
		(layer "Cmts.User")
		(hatch none 0.5)
		(connect_pads
			(clearance 0)
		)
		(min_thickness 0.25)
		(keepout
			(tracks allowed)
			(vias allowed)
			(pads allowed)
			(copperpour allowed)
			(footprints allowed)
		)
		(placement
			(enabled no)
			(sheetname "")
		)
		(fill
			(thermal_gap 0.5)
			(thermal_bridge_width 0.5)
			(island_removal_mode 0)
		)
		(polygon
			(pts
				(xy 106.558842 -38.757098) (xy 106.558842 -36.30041) (xy 107.634532 -36.30041) (xy 107.634532 -38.757098)
			)
		)
	)
	(zone
		(layer "Cmts.User")
		(hatch none 0.5)
		(connect_pads
			(clearance 0)
		)
		(min_thickness 0.25)
		(keepout
			(tracks allowed)
			(vias allowed)
			(pads allowed)
			(copperpour allowed)
			(footprints allowed)
		)
		(placement
			(enabled no)
			(sheetname "")
		)
		(fill
			(thermal_gap 0.5)
			(thermal_bridge_width 0.5)
			(island_removal_mode 0)
		)
		(polygon
			(pts
				(xy 119.177054 -37.479224) (xy 119.177054 -35.022536) (xy 120.252744 -35.022536) (xy 120.252744 -37.479224)
			)
		)
	)
	(zone
		(layer "Cmts.User")
		(hatch none 0.5)
		(connect_pads
			(clearance 0)
		)
		(min_thickness 0.25)
		(keepout
			(tracks allowed)
			(vias allowed)
			(pads allowed)
			(copperpour allowed)
			(footprints allowed)
		)
		(placement
			(enabled no)
			(sheetname "")
		)
		(fill
			(thermal_gap 0.5)
			(thermal_bridge_width 0.5)
			(island_removal_mode 0)
		)
		(polygon
			(pts
				(xy 78.505812 -90.612214)
				(arc
					(start 78.505812 -89.711022)
					(mid 78.409522 -89.456876)
					(end 78.169008 -89.330276)
				)
				(arc
					(start 78.169008 -89.330276)
					(mid 77.867998 -89.423533)
					(end 77.738478 -89.710768)
				)
				(xy 77.739748 -89.712038)
				(arc
					(start 77.739748 -90.599768)
					(mid 78.116683 -90.983251)
					(end 78.506574 -90.612976)
				)
			)
		)
	)
	(zone
		(layer "Cmts.User")
		(hatch none 0.5)
		(connect_pads
			(clearance 0)
		)
		(min_thickness 0.25)
		(keepout
			(tracks allowed)
			(vias allowed)
			(pads allowed)
			(copperpour allowed)
			(footprints allowed)
		)
		(placement
			(enabled no)
			(sheetname "")
		)
		(fill
			(thermal_gap 0.5)
			(thermal_bridge_width 0.5)
			(island_removal_mode 0)
		)
		(polygon
			(pts
				(xy 111.951262 -37.525706) (xy 111.951262 -35.069018) (xy 113.026952 -35.069018) (xy 113.026952 -37.525706)
			)
		)
	)
	(zone
		(layer "Cmts.User")
		(hatch none 0.5)
		(connect_pads
			(clearance 0)
		)
		(min_thickness 0.25)
		(keepout
			(tracks allowed)
			(vias allowed)
			(pads allowed)
			(copperpour allowed)
			(footprints allowed)
		)
		(placement
			(enabled no)
			(sheetname "")
		)
		(fill
			(thermal_gap 0.5)
			(thermal_bridge_width 0.5)
			(island_removal_mode 0)
		)
		(polygon
			(pts
				(xy 160.767776 -30.74797) (xy 161.866834 -28.55087) (xy 162.828986 -29.0322) (xy 161.729674 -31.2293)
			)
		)
	)
	(zone
		(layer "Cmts.User")
		(hatch none 0.5)
		(connect_pads
			(clearance 0)
		)
		(min_thickness 0.25)
		(keepout
			(tracks allowed)
			(vias allowed)
			(pads allowed)
			(copperpour allowed)
			(footprints allowed)
		)
		(placement
			(enabled no)
			(sheetname "")
		)
		(fill
			(thermal_gap 0.5)
			(thermal_bridge_width 0.5)
			(island_removal_mode 0)
		)
		(polygon
			(pts
				(xy 135.377682 -35.167062) (xy 135.377682 -32.710374) (xy 136.453372 -32.710374) (xy 136.453372 -35.167062)
			)
		)
	)
	(zone
		(layer "Cmts.User")
		(hatch none 0.5)
		(connect_pads
			(clearance 0)
		)
		(min_thickness 0.25)
		(keepout
			(tracks allowed)
			(vias allowed)
			(pads allowed)
			(copperpour allowed)
			(footprints allowed)
		)
		(placement
			(enabled no)
			(sheetname "")
		)
		(fill
			(thermal_gap 0.5)
			(thermal_bridge_width 0.5)
			(island_removal_mode 0)
		)
		(polygon
			(pts
				(xy 78.505812 -84.236814)
				(arc
					(start 78.505812 -83.335622)
					(mid 78.409522 -83.081476)
					(end 78.169008 -82.954876)
				)
				(arc
					(start 78.169008 -82.954876)
					(mid 77.867998 -83.048133)
					(end 77.738478 -83.335368)
				)
				(xy 77.739748 -83.336638)
				(arc
					(start 77.739748 -84.224368)
					(mid 78.116683 -84.607851)
					(end 78.506574 -84.237576)
				)
			)
		)
	)
	(zone
		(layer "Cmts.User")
		(hatch none 0.5)
		(connect_pads
			(clearance 0)
		)
		(min_thickness 0.25)
		(keepout
			(tracks allowed)
			(vias allowed)
			(pads allowed)
			(copperpour allowed)
			(footprints allowed)
		)
		(placement
			(enabled no)
			(sheetname "")
		)
		(fill
			(thermal_gap 0.5)
			(thermal_bridge_width 0.5)
			(island_removal_mode 0)
		)
		(polygon
			(pts
				(xy 178.601116 -23.145242) (xy 179.700174 -20.948142) (xy 180.662326 -21.429472) (xy 179.563014 -23.626572)
			)
		)
	)
	(zone
		(layer "Cmts.User")
		(hatch none 0.5)
		(connect_pads
			(clearance 0)
		)
		(min_thickness 0.25)
		(keepout
			(tracks allowed)
			(vias allowed)
			(pads allowed)
			(copperpour allowed)
			(footprints allowed)
		)
		(placement
			(enabled no)
			(sheetname "")
		)
		(fill
			(thermal_gap 0.5)
			(thermal_bridge_width 0.5)
			(island_removal_mode 0)
		)
		(polygon
			(pts
				(xy 106.58856 -35.117278) (xy 106.58856 -32.66059) (xy 107.66425 -32.66059) (xy 107.66425 -35.117278)
			)
		)
	)
	(zone
		(layer "Cmts.User")
		(hatch none 0.5)
		(connect_pads
			(clearance 0)
		)
		(min_thickness 0.25)
		(keepout
			(tracks allowed)
			(vias allowed)
			(pads allowed)
			(copperpour allowed)
			(footprints allowed)
		)
		(placement
			(enabled no)
			(sheetname "")
		)
		(fill
			(thermal_gap 0.5)
			(thermal_bridge_width 0.5)
			(island_removal_mode 0)
		)
		(polygon
			(pts
				(arc
					(start 193.557144 -88.734138)
					(mid 193.548526 -89.279331)
					(end 194.093846 -89.28227)
				)
				(arc
					(start 194.722242 -88.653874)
					(mid 194.722242 -88.11133)
					(end 194.179698 -88.11133)
				)
			)
		)
	)
	(zone
		(layer "Cmts.User")
		(hatch none 0.5)
		(connect_pads
			(clearance 0)
		)
		(min_thickness 0.25)
		(keepout
			(tracks allowed)
			(vias allowed)
			(pads allowed)
			(copperpour allowed)
			(footprints allowed)
		)
		(placement
			(enabled no)
			(sheetname "")
		)
		(fill
			(thermal_gap 0.5)
			(thermal_bridge_width 0.5)
			(island_removal_mode 0)
		)
		(polygon
			(pts
				(arc
					(start 200.943972 -85.813138)
					(mid 200.935354 -86.358331)
					(end 201.480674 -86.36127)
				)
				(arc
					(start 202.10907 -85.732874)
					(mid 202.10907 -85.19033)
					(end 201.566526 -85.19033)
				)
			)
		)
	)
	(zone
		(layer "Cmts.User")
		(hatch none 0.5)
		(connect_pads
			(clearance 0)
		)
		(min_thickness 0.25)
		(keepout
			(tracks allowed)
			(vias allowed)
			(pads allowed)
			(copperpour allowed)
			(footprints allowed)
		)
		(placement
			(enabled no)
			(sheetname "")
		)
		(fill
			(thermal_gap 0.5)
			(thermal_bridge_width 0.5)
			(island_removal_mode 0)
		)
		(polygon
			(pts
				(arc
					(start 190.834772 -87.032338)
					(mid 190.826154 -87.577531)
					(end 191.371474 -87.58047)
				)
				(arc
					(start 191.99987 -86.952074)
					(mid 191.99987 -86.40953)
					(end 191.457326 -86.40953)
				)
			)
		)
	)
	(zone
		(layer "Cmts.User")
		(hatch none 0.5)
		(connect_pads
			(clearance 0)
		)
		(min_thickness 0.25)
		(keepout
			(tracks allowed)
			(vias allowed)
			(pads allowed)
			(copperpour allowed)
			(footprints allowed)
		)
		(placement
			(enabled no)
			(sheetname "")
		)
		(fill
			(thermal_gap 0.5)
			(thermal_bridge_width 0.5)
			(island_removal_mode 0)
		)
		(polygon
			(pts
				(xy 117.394736 -38.763702) (xy 117.394736 -36.307014) (xy 118.470426 -36.307014) (xy 118.470426 -38.763702)
			)
		)
	)
	(zone
		(layer "Cmts.User")
		(hatch none 0.5)
		(connect_pads
			(clearance 0)
		)
		(min_thickness 0.25)
		(keepout
			(tracks allowed)
			(vias allowed)
			(pads allowed)
			(copperpour allowed)
			(footprints allowed)
		)
		(placement
			(enabled no)
			(sheetname "")
		)
		(fill
			(thermal_gap 0.5)
			(thermal_bridge_width 0.5)
			(island_removal_mode 0)
		)
		(polygon
			(pts
				(xy 83.742022 -95.394018)
				(arc
					(start 83.742022 -94.492826)
					(mid 83.645732 -94.23868)
					(end 83.405218 -94.11208)
				)
				(arc
					(start 83.405218 -94.11208)
					(mid 83.104208 -94.205337)
					(end 82.974688 -94.492572)
				)
				(xy 82.975958 -94.493842)
				(arc
					(start 82.975958 -95.381572)
					(mid 83.352893 -95.765055)
					(end 83.742784 -95.39478)
				)
			)
		)
	)
	(zone
		(layer "Cmts.User")
		(hatch none 0.5)
		(connect_pads
			(clearance 0)
		)
		(min_thickness 0.25)
		(keepout
			(tracks allowed)
			(vias allowed)
			(pads allowed)
			(copperpour allowed)
			(footprints allowed)
		)
		(placement
			(enabled no)
			(sheetname "")
		)
		(fill
			(thermal_gap 0.5)
			(thermal_bridge_width 0.5)
			(island_removal_mode 0)
		)
		(polygon
			(pts
				(xy 133.563614 -37.527484) (xy 133.563614 -35.070796) (xy 134.639304 -35.070796) (xy 134.639304 -37.527484)
			)
		)
	)
	(zone
		(layer "Cmts.User")
		(hatch none 0.5)
		(connect_pads
			(clearance 0)
		)
		(min_thickness 0.25)
		(keepout
			(tracks allowed)
			(vias allowed)
			(pads allowed)
			(copperpour allowed)
			(footprints allowed)
		)
		(placement
			(enabled no)
			(sheetname "")
		)
		(fill
			(thermal_gap 0.5)
			(thermal_bridge_width 0.5)
			(island_removal_mode 0)
		)
		(polygon
			(pts
				(xy 119.150638 -44.724828) (xy 119.150638 -42.26814) (xy 120.226328 -42.26814) (xy 120.226328 -44.724828)
			)
		)
	)
	(zone
		(layer "Cmts.User")
		(hatch none 0.5)
		(connect_pads
			(clearance 0)
		)
		(min_thickness 0.25)
		(keepout
			(tracks allowed)
			(vias allowed)
			(pads allowed)
			(copperpour allowed)
			(footprints allowed)
		)
		(placement
			(enabled no)
			(sheetname "")
		)
		(fill
			(thermal_gap 0.5)
			(thermal_bridge_width 0.5)
			(island_removal_mode 0)
		)
		(polygon
			(pts
				(xy 129.966974 -37.575744) (xy 129.966974 -35.119056) (xy 131.042664 -35.119056) (xy 131.042664 -37.575744)
			)
		)
	)
	(zone
		(layer "Cmts.User")
		(hatch none 0.5)
		(connect_pads
			(clearance 0)
		)
		(min_thickness 0.25)
		(keepout
			(tracks allowed)
			(vias allowed)
			(pads allowed)
			(copperpour allowed)
			(footprints allowed)
		)
		(placement
			(enabled no)
			(sheetname "")
		)
		(fill
			(thermal_gap 0.5)
			(thermal_bridge_width 0.5)
			(island_removal_mode 0)
		)
		(polygon
			(pts
				(xy 77.667612 -93.812614)
				(arc
					(start 77.667612 -92.911422)
					(mid 77.571322 -92.657276)
					(end 77.330808 -92.530676)
				)
				(arc
					(start 77.330808 -92.530676)
					(mid 77.029798 -92.623933)
					(end 76.900278 -92.911168)
				)
				(xy 76.901548 -92.912438)
				(arc
					(start 76.901548 -93.800168)
					(mid 77.278483 -94.183651)
					(end 77.668374 -93.813376)
				)
			)
		)
	)
	(zone
		(layer "Cmts.User")
		(hatch none 0.5)
		(connect_pads
			(clearance 0)
		)
		(min_thickness 0.25)
		(keepout
			(tracks allowed)
			(vias allowed)
			(pads allowed)
			(copperpour allowed)
			(footprints allowed)
		)
		(placement
			(enabled no)
			(sheetname "")
		)
		(fill
			(thermal_gap 0.5)
			(thermal_bridge_width 0.5)
			(island_removal_mode 0)
		)
		(polygon
			(pts
				(xy 36.195 -156.50464) (xy 36.195 -133.51002) (xy 59.19216 -133.51002) (xy 59.19216 -156.50464)
			)
		)
	)
	(zone
		(layer "Cmts.User")
		(hatch none 0.5)
		(connect_pads
			(clearance 0)
		)
		(min_thickness 0.25)
		(keepout
			(tracks allowed)
			(vias allowed)
			(pads allowed)
			(copperpour allowed)
			(footprints allowed)
		)
		(placement
			(enabled no)
			(sheetname "")
		)
		(fill
			(thermal_gap 0.5)
			(thermal_bridge_width 0.5)
			(island_removal_mode 0)
		)
		(polygon
			(pts
				(xy 133.547612 -33.930844) (xy 133.547612 -31.474156) (xy 134.623302 -31.474156) (xy 134.623302 -33.930844)
			)
		)
	)
	(zone
		(layer "Cmts.User")
		(hatch none 0.5)
		(connect_pads
			(clearance 0)
		)
		(min_thickness 0.25)
		(keepout
			(tracks allowed)
			(vias allowed)
			(pads allowed)
			(copperpour allowed)
			(footprints allowed)
		)
		(placement
			(enabled no)
			(sheetname "")
		)
		(fill
			(thermal_gap 0.5)
			(thermal_bridge_width 0.5)
			(island_removal_mode 0)
		)
		(polygon
			(pts
				(xy 78.505812 -77.810614)
				(arc
					(start 78.505812 -76.909422)
					(mid 78.409522 -76.655276)
					(end 78.169008 -76.528676)
				)
				(arc
					(start 78.169008 -76.528676)
					(mid 77.867998 -76.621933)
					(end 77.738478 -76.909168)
				)
				(xy 77.739748 -76.910438)
				(arc
					(start 77.739748 -77.798168)
					(mid 78.116683 -78.181651)
					(end 78.506574 -77.811376)
				)
			)
		)
	)
	(zone
		(layer "Cmts.User")
		(hatch none 0.5)
		(connect_pads
			(clearance 0)
		)
		(min_thickness 0.25)
		(keepout
			(tracks allowed)
			(vias allowed)
			(pads allowed)
			(copperpour allowed)
			(footprints allowed)
		)
		(placement
			(enabled no)
			(sheetname "")
		)
		(fill
			(thermal_gap 0.5)
			(thermal_bridge_width 0.5)
			(island_removal_mode 0)
		)
		(polygon
			(pts
				(xy 158.539688 -26.926032) (xy 159.638746 -24.728932) (xy 160.600898 -25.210262) (xy 159.501586 -27.407362)
			)
		)
	)
	(zone
		(layer "Cmts.User")
		(hatch none 0.5)
		(connect_pads
			(clearance 0)
		)
		(min_thickness 0.25)
		(keepout
			(tracks allowed)
			(vias allowed)
			(pads allowed)
			(copperpour allowed)
			(footprints allowed)
		)
		(placement
			(enabled no)
			(sheetname "")
		)
		(fill
			(thermal_gap 0.5)
			(thermal_bridge_width 0.5)
			(island_removal_mode 0)
		)
		(polygon
			(pts
				(arc
					(start 203.534772 -85.228938)
					(mid 203.526154 -85.774131)
					(end 204.071474 -85.77707)
				)
				(arc
					(start 204.69987 -85.148674)
					(mid 204.69987 -84.60613)
					(end 204.157326 -84.60613)
				)
			)
		)
	)
	(zone
		(layer "Cmts.User")
		(hatch none 0.5)
		(connect_pads
			(clearance 0)
		)
		(min_thickness 0.25)
		(keepout
			(tracks allowed)
			(vias allowed)
			(pads allowed)
			(copperpour allowed)
			(footprints allowed)
		)
		(placement
			(enabled no)
			(sheetname "")
		)
		(fill
			(thermal_gap 0.5)
			(thermal_bridge_width 0.5)
			(island_removal_mode 0)
		)
		(polygon
			(pts
				(xy 135.31342 -38.715442) (xy 135.31342 -36.258754) (xy 136.38911 -36.258754) (xy 136.38911 -38.715442)
			)
		)
	)
	(zone
		(layer "Cmts.User")
		(hatch none 0.5)
		(connect_pads
			(clearance 0)
		)
		(min_thickness 0.25)
		(keepout
			(tracks allowed)
			(vias allowed)
			(pads allowed)
			(copperpour allowed)
			(footprints allowed)
		)
		(placement
			(enabled no)
			(sheetname "")
		)
		(fill
			(thermal_gap 0.5)
			(thermal_bridge_width 0.5)
			(island_removal_mode 0)
		)
		(polygon
			(pts
				(xy 160.778698 -19.307556) (xy 161.877756 -17.110456) (xy 162.839908 -17.591786) (xy 161.740596 -19.788886)
			)
		)
	)
	(zone
		(layer "Cmts.User")
		(hatch none 0.5)
		(connect_pads
			(clearance 0)
		)
		(min_thickness 0.25)
		(keepout
			(tracks allowed)
			(vias allowed)
			(pads allowed)
			(copperpour allowed)
			(footprints allowed)
		)
		(placement
			(enabled no)
			(sheetname "")
		)
		(fill
			(thermal_gap 0.5)
			(thermal_bridge_width 0.5)
			(island_removal_mode 0)
		)
		(polygon
			(pts
				(xy 140.766038 -44.750228) (xy 140.766038 -42.2402) (xy 141.841728 -42.2402) (xy 141.841728 -44.750228)
			)
		)
	)
	(zone
		(layer "Cmts.User")
		(hatch none 0.5)
		(connect_pads
			(clearance 0)
		)
		(min_thickness 0.25)
		(keepout
			(tracks allowed)
			(vias allowed)
			(pads allowed)
			(copperpour allowed)
			(footprints allowed)
		)
		(placement
			(enabled no)
			(sheetname "")
		)
		(fill
			(thermal_gap 0.5)
			(thermal_bridge_width 0.5)
			(island_removal_mode 0)
		)
		(polygon
			(pts
				(xy 77.667612 -87.411814)
				(arc
					(start 77.667612 -86.510622)
					(mid 77.571322 -86.256476)
					(end 77.330808 -86.129876)
				)
				(arc
					(start 77.330808 -86.129876)
					(mid 77.029798 -86.223133)
					(end 76.900278 -86.510368)
				)
				(xy 76.901548 -86.511638)
				(arc
					(start 76.901548 -87.399368)
					(mid 77.278483 -87.782851)
					(end 77.668374 -87.412576)
				)
			)
		)
	)
	(zone
		(layer "Cmts.User")
		(hatch none 0.5)
		(connect_pads
			(clearance 0)
		)
		(min_thickness 0.25)
		(keepout
			(tracks allowed)
			(vias allowed)
			(pads allowed)
			(copperpour allowed)
			(footprints allowed)
		)
		(placement
			(enabled no)
			(sheetname "")
		)
		(fill
			(thermal_gap 0.5)
			(thermal_bridge_width 0.5)
			(island_removal_mode 0)
		)
		(polygon
			(pts
				(xy 138.974322 -35.1028) (xy 138.974322 -32.646112) (xy 140.050012 -32.646112) (xy 140.050012 -35.1028)
			)
		)
	)
	(zone
		(layer "Cmts.User")
		(hatch none 0.5)
		(connect_pads
			(clearance 0)
		)
		(min_thickness 0.25)
		(keepout
			(tracks allowed)
			(vias allowed)
			(pads allowed)
			(copperpour allowed)
			(footprints allowed)
		)
		(placement
			(enabled no)
			(sheetname "")
		)
		(fill
			(thermal_gap 0.5)
			(thermal_bridge_width 0.5)
			(island_removal_mode 0)
		)
		(polygon
			(pts
				(xy 213.98738 -73.063608) (xy 214.795354 -72.25538)
				(arc
					(start 214.795354 -72.255126)
					(mid 214.795354 -71.716646)
					(end 214.256874 -71.716646)
				)
				(xy 214.25662 -71.716392) (xy 213.448392 -72.52462)
				(arc
					(start 213.448646 -72.524874)
					(mid 213.448646 -73.063354)
					(end 213.987126 -73.063354)
				)
			)
		)
	)
	(zone
		(layer "Cmts.User")
		(hatch none 0.5)
		(connect_pads
			(clearance 0)
		)
		(min_thickness 0.25)
		(keepout
			(tracks allowed)
			(vias allowed)
			(pads allowed)
			(copperpour allowed)
			(footprints allowed)
		)
		(placement
			(enabled no)
			(sheetname "")
		)
		(fill
			(thermal_gap 0.5)
			(thermal_bridge_width 0.5)
			(island_removal_mode 0)
		)
		(polygon
			(pts
				(xy 180.784754 -23.096982) (xy 181.883812 -20.899882) (xy 182.845964 -21.381212) (xy 181.746652 -23.578312)
			)
		)
	)
	(zone
		(layer "Cmts.User")
		(hatch none 0.5)
		(connect_pads
			(clearance 0)
		)
		(min_thickness 0.25)
		(keepout
			(tracks allowed)
			(vias allowed)
			(pads allowed)
			(copperpour allowed)
			(footprints allowed)
		)
		(placement
			(enabled no)
			(sheetname "")
		)
		(fill
			(thermal_gap 0.5)
			(thermal_bridge_width 0.5)
			(island_removal_mode 0)
		)
		(polygon
			(pts
				(xy 108.38688 -33.800796) (xy 108.38688 -31.344108) (xy 109.46257 -31.344108) (xy 109.46257 -33.800796)
			)
		)
	)
	(zone
		(layer "Cmts.User")
		(hatch none 0.5)
		(connect_pads
			(clearance 0)
		)
		(min_thickness 0.25)
		(keepout
			(tracks allowed)
			(vias allowed)
			(pads allowed)
			(copperpour allowed)
			(footprints allowed)
		)
		(placement
			(enabled no)
			(sheetname "")
		)
		(fill
			(thermal_gap 0.5)
			(thermal_bridge_width 0.5)
			(island_removal_mode 0)
		)
		(polygon
			(pts
				(xy 83.742022 -82.606642)
				(arc
					(start 83.742022 -81.70545)
					(mid 83.645732 -81.451304)
					(end 83.405218 -81.324704)
				)
				(arc
					(start 83.405218 -81.324704)
					(mid 83.104208 -81.417961)
					(end 82.974688 -81.705196)
				)
				(xy 82.975958 -81.706466)
				(arc
					(start 82.975958 -82.594196)
					(mid 83.352893 -82.977679)
					(end 83.742784 -82.607404)
				)
			)
		)
	)
	(zone
		(layer "Cmts.User")
		(hatch none 0.5)
		(connect_pads
			(clearance 0)
		)
		(min_thickness 0.25)
		(keepout
			(tracks allowed)
			(vias allowed)
			(pads allowed)
			(copperpour allowed)
			(footprints allowed)
		)
		(placement
			(enabled no)
			(sheetname "")
		)
		(fill
			(thermal_gap 0.5)
			(thermal_bridge_width 0.5)
			(island_removal_mode 0)
		)
		(polygon
			(pts
				(xy 111.903256 -33.913064) (xy 111.903256 -31.456376) (xy 112.978946 -31.456376) (xy 112.978946 -33.913064)
			)
		)
	)
)
